G04 ================== begin FILE IDENTIFICATION RECORD ==================*
G04 Layout Name:  15126-1b.brd*
G04 Film Name:    DP_REF_L5*
G04 File Format:  Gerber RS274X*
G04 File Origin:  Cadence Allegro 16.6-2015-S079*
G04 Origin Date:  Fri Feb 10 17:23:34 2017*
G04 *
G04 Layer:  BOARD GEOMETRY/PANEL_OUTLINE*
G04 Layer:  BOARD GEOMETRY/DP_REF_L5_TBL*
G04 Layer:  BOARD GEOMETRY/DP_REF_L5_L5*
G04 *
G04 Offset:    (0.00 0.00)*
G04 Mirror:    No*
G04 Mode:      Positive*
G04 Rotation:  0*
G04 FullContactRelief:  No*
G04 UndefLineWidth:     6.00*
G04 ================== end FILE IDENTIFICATION RECORD ====================*
%FSLAX35Y35*MOIN*%
%IR0*IPPOS*OFA0.00000B0.00000*MIA0B0*SFA1.00000B1.00000*%
%ADD10C,.02*%
%ADD11C,.006*%
%ADD12C,.0045*%
%ADD13C,.0056*%
G75*
%LPD*%
G75*
G54D10*
G01X2026678Y631398D02*
Y458148D01*
G01D02*
X2866678D01*
G01X2026678Y492798D02*
X2866678D01*
G01X2026678Y527448D02*
X2866678D01*
G01X2026678Y562098D02*
X2866678D01*
G01X2026678Y596748D02*
X2866678D01*
G01X2026678Y631398D02*
X2866678D01*
G01X2201678D02*
Y458148D01*
G01X2551678Y631398D02*
Y458148D01*
G01X2656678Y631398D02*
Y458148D01*
G01X2866678Y631398D02*
Y458148D01*
G54D11*
G01X-17372Y-95792D02*
Y-113292D01*
G01X-22394Y-95792D02*
X-12350D01*
G01X-3584Y-113292D02*
Y-95792D01*
G01Y-104250D02*
X-2492Y-102792D01*
X-1400Y-101917D01*
X346Y-101626D01*
X1656Y-101917D01*
X3185Y-103084D01*
X3840Y-104834D01*
Y-113292D01*
G01X17628Y-101626D02*
Y-113292D01*
G01Y-96959D02*
X17191Y-96667D01*
Y-96084D01*
X17628Y-95792D01*
X18065Y-96084D01*
Y-96667D01*
X17628Y-96959D01*
G01X31853Y-111251D02*
X32945Y-112417D01*
X34473Y-113292D01*
X35783D01*
X37093Y-112709D01*
X37966Y-111834D01*
X38403Y-110668D01*
X38185Y-108917D01*
X37311Y-108042D01*
X33381Y-106292D01*
X32508Y-104250D01*
X32945Y-102792D01*
X33818Y-101917D01*
X35128Y-101626D01*
X36438Y-101917D01*
X37748Y-102792D01*
G01X67071Y-117667D02*
X68600Y-118834D01*
X70346Y-119125D01*
X71874Y-118834D01*
X73185Y-117376D01*
X74058Y-115334D01*
Y-101626D01*
G01Y-103959D02*
X73185Y-102792D01*
X71874Y-101917D01*
X70346Y-101626D01*
X68600Y-102209D01*
X67508Y-103375D01*
X66634Y-105417D01*
X66198Y-107459D01*
X66416Y-109209D01*
X67290Y-111251D01*
X68600Y-112709D01*
X70346Y-113292D01*
X71656Y-113000D01*
X73185Y-111834D01*
X74058Y-110668D01*
G01X84353Y-105417D02*
X91340D01*
X90685Y-103375D01*
X89593Y-102209D01*
X88065Y-101626D01*
X86536Y-101917D01*
X85226Y-102792D01*
X84353Y-104834D01*
X83916Y-106584D01*
Y-108334D01*
X84353Y-110084D01*
X85445Y-111834D01*
X86755Y-113000D01*
X88283Y-113292D01*
X89811Y-112709D01*
X91340Y-110959D01*
G01X102071Y-113292D02*
Y-101626D01*
G01Y-103959D02*
X103163Y-102792D01*
X104255Y-101917D01*
X105783Y-101626D01*
X106874Y-101917D01*
X108185Y-102792D01*
G01X118698Y-113292D02*
Y-95792D01*
G01Y-104542D02*
X119790Y-102792D01*
X121100Y-101917D01*
X122410Y-101626D01*
X124374Y-102209D01*
X125685Y-103375D01*
X126558Y-105417D01*
Y-107750D01*
X126121Y-110084D01*
X125248Y-111834D01*
X123720Y-113000D01*
X122410Y-113292D01*
X121100Y-113000D01*
X119790Y-112126D01*
X118698Y-110668D01*
G01X136853Y-105417D02*
X143840D01*
X143185Y-103375D01*
X142093Y-102209D01*
X140565Y-101626D01*
X139036Y-101917D01*
X137726Y-102792D01*
X136853Y-104834D01*
X136416Y-106584D01*
Y-108334D01*
X136853Y-110084D01*
X137945Y-111834D01*
X139255Y-113000D01*
X140783Y-113292D01*
X142311Y-112709D01*
X143840Y-110959D01*
G01X154571Y-113292D02*
Y-101626D01*
G01Y-103959D02*
X155663Y-102792D01*
X156755Y-101917D01*
X158283Y-101626D01*
X159374Y-101917D01*
X160685Y-102792D01*
G01X192628Y-101626D02*
Y-113292D01*
G01Y-96959D02*
X192191Y-96667D01*
Y-96084D01*
X192628Y-95792D01*
X193065Y-96084D01*
Y-96667D01*
X192628Y-96959D01*
G01X206853Y-111251D02*
X207945Y-112417D01*
X209473Y-113292D01*
X210783D01*
X212093Y-112709D01*
X212966Y-111834D01*
X213403Y-110668D01*
X213185Y-108917D01*
X212311Y-108042D01*
X208381Y-106292D01*
X207508Y-104250D01*
X207945Y-102792D01*
X208818Y-101917D01*
X210128Y-101626D01*
X211438Y-101917D01*
X212748Y-102792D01*
G01X241634Y-117667D02*
X243163Y-118834D01*
X244473Y-119125D01*
X246220Y-118542D01*
X247530Y-117084D01*
X248185Y-114458D01*
Y-101626D01*
G01Y-96959D02*
X247748Y-96667D01*
Y-96084D01*
X248185Y-95792D01*
X248621Y-96084D01*
Y-96667D01*
X248185Y-96959D01*
G01X258916Y-101626D02*
Y-109792D01*
X259790Y-111834D01*
X261100Y-113000D01*
X262628Y-113292D01*
X264156Y-113000D01*
X265466Y-111834D01*
X266340Y-109792D01*
G01Y-113292D02*
Y-101626D01*
G01X276853Y-111251D02*
X277945Y-112417D01*
X279473Y-113292D01*
X280783D01*
X282093Y-112709D01*
X282966Y-111834D01*
X283403Y-110668D01*
X283185Y-108917D01*
X282311Y-108042D01*
X278381Y-106292D01*
X277508Y-104250D01*
X277945Y-102792D01*
X278818Y-101917D01*
X280128Y-101626D01*
X281438Y-101917D01*
X282748Y-102792D01*
G01X297628Y-95792D02*
Y-113292D01*
G01X294571Y-101626D02*
X300685D01*
G01X331318Y-113292D02*
Y-98417D01*
X331755Y-96959D01*
X332628Y-96084D01*
X333938Y-95792D01*
X335248Y-96375D01*
X335903Y-97834D01*
G01X333283Y-102792D02*
X328916D01*
G01X350128Y-113292D02*
X348818Y-113000D01*
X347508Y-111834D01*
X346634Y-109792D01*
X346198Y-107459D01*
X346634Y-105125D01*
X347508Y-103084D01*
X348818Y-101917D01*
X350128Y-101626D01*
X351438Y-101917D01*
X352748Y-103084D01*
X353621Y-105125D01*
X353840Y-107459D01*
X353621Y-109792D01*
X352748Y-111834D01*
X351438Y-113000D01*
X350128Y-113292D01*
G01X364571D02*
Y-101626D01*
G01Y-103959D02*
X365663Y-102792D01*
X366755Y-101917D01*
X368283Y-101626D01*
X369374Y-101917D01*
X370685Y-102792D01*
G01X398043Y-118542D02*
X399353Y-119125D01*
X401100Y-118542D01*
X402191Y-117376D01*
X403065Y-115917D01*
X404374Y-111251D01*
X407213Y-101626D01*
G01X400226D02*
X404374Y-111251D01*
G01X420128Y-113292D02*
X418818Y-113000D01*
X417508Y-111834D01*
X416634Y-109792D01*
X416198Y-107459D01*
X416634Y-105125D01*
X417508Y-103084D01*
X418818Y-101917D01*
X420128Y-101626D01*
X421438Y-101917D01*
X422748Y-103084D01*
X423621Y-105125D01*
X423840Y-107459D01*
X423621Y-109792D01*
X422748Y-111834D01*
X421438Y-113000D01*
X420128Y-113292D01*
G01X433916Y-101626D02*
Y-109792D01*
X434790Y-111834D01*
X436100Y-113000D01*
X437628Y-113292D01*
X439156Y-113000D01*
X440466Y-111834D01*
X441340Y-109792D01*
G01Y-113292D02*
Y-101626D01*
G01X452071Y-113292D02*
Y-101626D01*
G01Y-103959D02*
X453163Y-102792D01*
X454255Y-101917D01*
X455783Y-101626D01*
X456874Y-101917D01*
X458185Y-102792D01*
G01X487071Y-113292D02*
Y-101626D01*
G01Y-103959D02*
X488163Y-102792D01*
X489255Y-101917D01*
X490783Y-101626D01*
X491874Y-101917D01*
X493185Y-102792D01*
G01X504353Y-105417D02*
X511340D01*
X510685Y-103375D01*
X509593Y-102209D01*
X508065Y-101626D01*
X506536Y-101917D01*
X505226Y-102792D01*
X504353Y-104834D01*
X503916Y-106584D01*
Y-108334D01*
X504353Y-110084D01*
X505445Y-111834D01*
X506755Y-113000D01*
X508283Y-113292D01*
X509811Y-112709D01*
X511340Y-110959D01*
G01X523818Y-113292D02*
Y-98417D01*
X524255Y-96959D01*
X525128Y-96084D01*
X526438Y-95792D01*
X527748Y-96375D01*
X528403Y-97834D01*
G01X525783Y-102792D02*
X521416D01*
G01X539353Y-105417D02*
X546340D01*
X545685Y-103375D01*
X544593Y-102209D01*
X543065Y-101626D01*
X541536Y-101917D01*
X540226Y-102792D01*
X539353Y-104834D01*
X538916Y-106584D01*
Y-108334D01*
X539353Y-110084D01*
X540445Y-111834D01*
X541755Y-113000D01*
X543283Y-113292D01*
X544811Y-112709D01*
X546340Y-110959D01*
G01X557071Y-113292D02*
Y-101626D01*
G01Y-103959D02*
X558163Y-102792D01*
X559255Y-101917D01*
X560783Y-101626D01*
X561874Y-101917D01*
X563185Y-102792D01*
G01X574353Y-105417D02*
X581340D01*
X580685Y-103375D01*
X579593Y-102209D01*
X578065Y-101626D01*
X576536Y-101917D01*
X575226Y-102792D01*
X574353Y-104834D01*
X573916Y-106584D01*
Y-108334D01*
X574353Y-110084D01*
X575445Y-111834D01*
X576755Y-113000D01*
X578283Y-113292D01*
X579811Y-112709D01*
X581340Y-110959D01*
G01X591416Y-113292D02*
Y-101626D01*
G01Y-104542D02*
X592290Y-103084D01*
X593600Y-101917D01*
X595346Y-101626D01*
X596874Y-101917D01*
X598185Y-103084D01*
X598840Y-105125D01*
Y-113292D01*
G01X616121Y-103084D02*
X614593Y-101917D01*
X613283Y-101626D01*
X611536Y-102209D01*
X610226Y-103375D01*
X609353Y-105417D01*
X609134Y-107459D01*
X609353Y-109501D01*
X610226Y-111251D01*
X611536Y-112709D01*
X613283Y-113292D01*
X614811Y-112709D01*
X616121Y-111542D01*
G01X626853Y-105417D02*
X633840D01*
X633185Y-103375D01*
X632093Y-102209D01*
X630565Y-101626D01*
X629036Y-101917D01*
X627726Y-102792D01*
X626853Y-104834D01*
X626416Y-106584D01*
Y-108334D01*
X626853Y-110084D01*
X627945Y-111834D01*
X629255Y-113000D01*
X630783Y-113292D01*
X632311Y-112709D01*
X633840Y-110959D01*
G01X665128Y-95792D02*
Y-113292D01*
G01X662071Y-101626D02*
X668185D01*
G01X682628Y-113292D02*
X681318Y-113000D01*
X680008Y-111834D01*
X679134Y-109792D01*
X678698Y-107459D01*
X679134Y-105125D01*
X680008Y-103084D01*
X681318Y-101917D01*
X682628Y-101626D01*
X683938Y-101917D01*
X685248Y-103084D01*
X686121Y-105125D01*
X686340Y-107459D01*
X686121Y-109792D01*
X685248Y-111834D01*
X683938Y-113000D01*
X682628Y-113292D01*
G01X716318D02*
Y-98417D01*
X716755Y-96959D01*
X717628Y-96084D01*
X718938Y-95792D01*
X720248Y-96375D01*
X720903Y-97834D01*
G01X718283Y-102792D02*
X713916D01*
G01X735128Y-101626D02*
Y-113292D01*
G01Y-96959D02*
X734691Y-96667D01*
Y-96084D01*
X735128Y-95792D01*
X735565Y-96084D01*
Y-96667D01*
X735128Y-96959D01*
G01X748916Y-113292D02*
Y-101626D01*
G01Y-104542D02*
X749790Y-103084D01*
X751100Y-101917D01*
X752846Y-101626D01*
X754374Y-101917D01*
X755685Y-103084D01*
X756340Y-105125D01*
Y-113292D01*
G01X774058Y-95792D02*
Y-113292D01*
G01Y-110668D02*
X773185Y-112126D01*
X771874Y-113000D01*
X770346Y-113292D01*
X768600Y-112709D01*
X767290Y-111251D01*
X766416Y-109501D01*
X766198Y-107459D01*
X766416Y-105417D01*
X767290Y-103667D01*
X768600Y-102209D01*
X770346Y-101626D01*
X771874Y-101917D01*
X772966Y-102501D01*
X774058Y-103667D01*
G01X805128Y-95792D02*
Y-113292D01*
G01X802071Y-101626D02*
X808185D01*
G01X818916Y-113292D02*
Y-95792D01*
G01Y-104250D02*
X820008Y-102792D01*
X821100Y-101917D01*
X822846Y-101626D01*
X824156Y-101917D01*
X825685Y-103084D01*
X826340Y-104834D01*
Y-113292D01*
G01X836853Y-105417D02*
X843840D01*
X843185Y-103375D01*
X842093Y-102209D01*
X840565Y-101626D01*
X839036Y-101917D01*
X837726Y-102792D01*
X836853Y-104834D01*
X836416Y-106584D01*
Y-108334D01*
X836853Y-110084D01*
X837945Y-111834D01*
X839255Y-113000D01*
X840783Y-113292D01*
X842311Y-112709D01*
X843840Y-110959D01*
G01X870325Y-113292D02*
Y-95792D01*
X874691D01*
X876438Y-96667D01*
X877748Y-97834D01*
X878840Y-99583D01*
X879713Y-101626D01*
X879931Y-104542D01*
X879713Y-107459D01*
X878840Y-109501D01*
X877748Y-111251D01*
X876438Y-112417D01*
X874691Y-113292D01*
X870325D01*
G01X888261D02*
Y-95792D01*
X893501D01*
X895248Y-96667D01*
X896558Y-98709D01*
X896995Y-101042D01*
X896558Y-103375D01*
X895466Y-105125D01*
X893501Y-106001D01*
X888261D01*
G01X927628Y-101626D02*
Y-113292D01*
G01Y-96959D02*
X927191Y-96667D01*
Y-96084D01*
X927628Y-95792D01*
X928065Y-96084D01*
Y-96667D01*
X927628Y-96959D01*
G01X938578Y-113292D02*
Y-101626D01*
G01Y-104834D02*
X939233Y-103375D01*
X940325Y-102209D01*
X941853Y-101626D01*
X943381Y-102209D01*
X944473Y-103375D01*
X945128Y-104834D01*
Y-113292D01*
G01Y-104834D02*
X945783Y-103375D01*
X946874Y-102209D01*
X948403Y-101626D01*
X949931Y-102209D01*
X951023Y-103375D01*
X951678Y-105125D01*
Y-113292D01*
G01X958698Y-119125D02*
Y-101626D01*
G01Y-104250D02*
X959790Y-102792D01*
X960881Y-101917D01*
X962628Y-101626D01*
X964156Y-101917D01*
X965685Y-103375D01*
X966340Y-105417D01*
X966558Y-107459D01*
X966340Y-109501D01*
X965685Y-111542D01*
X964374Y-112709D01*
X962628Y-113292D01*
X961100Y-113000D01*
X959571Y-112126D01*
X958698Y-110959D01*
G01X976853Y-105417D02*
X983840D01*
X983185Y-103375D01*
X982093Y-102209D01*
X980565Y-101626D01*
X979036Y-101917D01*
X977726Y-102792D01*
X976853Y-104834D01*
X976416Y-106584D01*
Y-108334D01*
X976853Y-110084D01*
X977945Y-111834D01*
X979255Y-113000D01*
X980783Y-113292D01*
X982311Y-112709D01*
X983840Y-110959D01*
G01X1001558Y-95792D02*
Y-113292D01*
G01Y-110668D02*
X1000685Y-112126D01*
X999374Y-113000D01*
X997846Y-113292D01*
X996100Y-112709D01*
X994790Y-111251D01*
X993916Y-109501D01*
X993698Y-107459D01*
X993916Y-105417D01*
X994790Y-103667D01*
X996100Y-102209D01*
X997846Y-101626D01*
X999374Y-101917D01*
X1000466Y-102501D01*
X1001558Y-103667D01*
G01X1019058Y-113292D02*
Y-101626D01*
G01Y-103667D02*
X1018185Y-102501D01*
X1016874Y-101917D01*
X1015346Y-101626D01*
X1013818Y-102209D01*
X1012508Y-103375D01*
X1011634Y-105125D01*
X1011198Y-107459D01*
X1011634Y-109792D01*
X1012508Y-111542D01*
X1013818Y-112709D01*
X1015346Y-113292D01*
X1016874Y-113000D01*
X1018185Y-112126D01*
X1019058Y-110959D01*
G01X1028916Y-113292D02*
Y-101626D01*
G01Y-104542D02*
X1029790Y-103084D01*
X1031100Y-101917D01*
X1032846Y-101626D01*
X1034374Y-101917D01*
X1035685Y-103084D01*
X1036340Y-105125D01*
Y-113292D01*
G01X1053621Y-103084D02*
X1052093Y-101917D01*
X1050783Y-101626D01*
X1049036Y-102209D01*
X1047726Y-103375D01*
X1046853Y-105417D01*
X1046634Y-107459D01*
X1046853Y-109501D01*
X1047726Y-111251D01*
X1049036Y-112709D01*
X1050783Y-113292D01*
X1052311Y-112709D01*
X1053621Y-111542D01*
G01X1064353Y-105417D02*
X1071340D01*
X1070685Y-103375D01*
X1069593Y-102209D01*
X1068065Y-101626D01*
X1066536Y-101917D01*
X1065226Y-102792D01*
X1064353Y-104834D01*
X1063916Y-106584D01*
Y-108334D01*
X1064353Y-110084D01*
X1065445Y-111834D01*
X1066755Y-113000D01*
X1068283Y-113292D01*
X1069811Y-112709D01*
X1071340Y-110959D01*
G01X1102628Y-95792D02*
Y-113292D01*
G01X1099571Y-101626D02*
X1105685D01*
G01X1117071Y-113292D02*
Y-101626D01*
G01Y-103959D02*
X1118163Y-102792D01*
X1119255Y-101917D01*
X1120783Y-101626D01*
X1121874Y-101917D01*
X1123185Y-102792D01*
G01X1141558Y-113292D02*
Y-101626D01*
G01Y-103667D02*
X1140685Y-102501D01*
X1139374Y-101917D01*
X1137846Y-101626D01*
X1136318Y-102209D01*
X1135008Y-103375D01*
X1134134Y-105125D01*
X1133698Y-107459D01*
X1134134Y-109792D01*
X1135008Y-111542D01*
X1136318Y-112709D01*
X1137846Y-113292D01*
X1139374Y-113000D01*
X1140685Y-112126D01*
X1141558Y-110959D01*
G01X1158621Y-103084D02*
X1157093Y-101917D01*
X1155783Y-101626D01*
X1154036Y-102209D01*
X1152726Y-103375D01*
X1151853Y-105417D01*
X1151634Y-107459D01*
X1151853Y-109501D01*
X1152726Y-111251D01*
X1154036Y-112709D01*
X1155783Y-113292D01*
X1157311Y-112709D01*
X1158621Y-111542D01*
G01X1169353Y-105417D02*
X1176340D01*
X1175685Y-103375D01*
X1174593Y-102209D01*
X1173065Y-101626D01*
X1171536Y-101917D01*
X1170226Y-102792D01*
X1169353Y-104834D01*
X1168916Y-106584D01*
Y-108334D01*
X1169353Y-110084D01*
X1170445Y-111834D01*
X1171755Y-113000D01*
X1173283Y-113292D01*
X1174811Y-112709D01*
X1176340Y-110959D01*
G01X1186853Y-111251D02*
X1187945Y-112417D01*
X1189473Y-113292D01*
X1190783D01*
X1192093Y-112709D01*
X1192966Y-111834D01*
X1193403Y-110668D01*
X1193185Y-108917D01*
X1192311Y-108042D01*
X1188381Y-106292D01*
X1187508Y-104250D01*
X1187945Y-102792D01*
X1188818Y-101917D01*
X1190128Y-101626D01*
X1191438Y-101917D01*
X1192748Y-102792D01*
G01X1225128Y-101626D02*
Y-113292D01*
G01Y-96959D02*
X1224691Y-96667D01*
Y-96084D01*
X1225128Y-95792D01*
X1225565Y-96084D01*
Y-96667D01*
X1225128Y-96959D01*
G01X1238916Y-113292D02*
Y-101626D01*
G01Y-104542D02*
X1239790Y-103084D01*
X1241100Y-101917D01*
X1242846Y-101626D01*
X1244374Y-101917D01*
X1245685Y-103084D01*
X1246340Y-105125D01*
Y-113292D01*
G01X1277628D02*
Y-95792D01*
G01X1299058Y-113292D02*
Y-101626D01*
G01Y-103667D02*
X1298185Y-102501D01*
X1296874Y-101917D01*
X1295346Y-101626D01*
X1293818Y-102209D01*
X1292508Y-103375D01*
X1291634Y-105125D01*
X1291198Y-107459D01*
X1291634Y-109792D01*
X1292508Y-111542D01*
X1293818Y-112709D01*
X1295346Y-113292D01*
X1296874Y-113000D01*
X1298185Y-112126D01*
X1299058Y-110959D01*
G01X1308043Y-118542D02*
X1309353Y-119125D01*
X1311100Y-118542D01*
X1312191Y-117376D01*
X1313065Y-115917D01*
X1314374Y-111251D01*
X1317213Y-101626D01*
G01X1310226D02*
X1314374Y-111251D01*
G01X1326853Y-105417D02*
X1333840D01*
X1333185Y-103375D01*
X1332093Y-102209D01*
X1330565Y-101626D01*
X1329036Y-101917D01*
X1327726Y-102792D01*
X1326853Y-104834D01*
X1326416Y-106584D01*
Y-108334D01*
X1326853Y-110084D01*
X1327945Y-111834D01*
X1329255Y-113000D01*
X1330783Y-113292D01*
X1332311Y-112709D01*
X1333840Y-110959D01*
G01X1344571Y-113292D02*
Y-101626D01*
G01Y-103959D02*
X1345663Y-102792D01*
X1346755Y-101917D01*
X1348283Y-101626D01*
X1349374Y-101917D01*
X1350685Y-102792D01*
G01X1378261Y-95792D02*
Y-113292D01*
X1386995D01*
G01X1395325Y-110668D02*
X1396634Y-112126D01*
X1398163Y-113000D01*
X1400128Y-113292D01*
X1402093Y-112709D01*
X1403621Y-111542D01*
X1404713Y-109501D01*
X1404931Y-107167D01*
X1404495Y-104834D01*
X1403403Y-103375D01*
X1401874Y-102209D01*
X1400346Y-101917D01*
X1398818Y-102209D01*
X1396853Y-103375D01*
X1397508Y-95792D01*
X1403403D01*
G01X1417628Y-113875D02*
X1417191Y-113584D01*
Y-113000D01*
X1417628Y-112709D01*
X1418065Y-113000D01*
Y-113584D01*
X1417628Y-113875D01*
G01X2079178Y467898D02*
Y485398D01*
X2076558Y481898D01*
G01Y467898D02*
X2081798D01*
G01X2096678Y485398D02*
X2094931Y484815D01*
X2093621Y483356D01*
X2092748Y481607D01*
X2092093Y479273D01*
X2091875Y476648D01*
X2092093Y474023D01*
X2092748Y471689D01*
X2093621Y469939D01*
X2094931Y468481D01*
X2096678Y467898D01*
X2098424Y468481D01*
X2099735Y469939D01*
X2100608Y471689D01*
X2101263Y474023D01*
X2101481Y476648D01*
X2101263Y479273D01*
X2100608Y481607D01*
X2099735Y483356D01*
X2098424Y484815D01*
X2096678Y485398D01*
G01X2114178D02*
X2112431Y484815D01*
X2111121Y483356D01*
X2110248Y481607D01*
X2109593Y479273D01*
X2109375Y476648D01*
X2109593Y474023D01*
X2110248Y471689D01*
X2111121Y469939D01*
X2112431Y468481D01*
X2114178Y467898D01*
X2115924Y468481D01*
X2117235Y469939D01*
X2118108Y471689D01*
X2118763Y474023D01*
X2118981Y476648D01*
X2118763Y479273D01*
X2118108Y481607D01*
X2117235Y483356D01*
X2115924Y484815D01*
X2114178Y485398D01*
G01X2131678Y467315D02*
X2131241Y467606D01*
Y468190D01*
X2131678Y468481D01*
X2132115Y468190D01*
Y467606D01*
X2131678Y467315D01*
G01X2149178Y485398D02*
X2147431Y484815D01*
X2146121Y483356D01*
X2145248Y481607D01*
X2144593Y479273D01*
X2144375Y476648D01*
X2144593Y474023D01*
X2145248Y471689D01*
X2146121Y469939D01*
X2147431Y468481D01*
X2149178Y467898D01*
X2150924Y468481D01*
X2152235Y469939D01*
X2153108Y471689D01*
X2153763Y474023D01*
X2153981Y476648D01*
X2153763Y479273D01*
X2153108Y481607D01*
X2152235Y483356D01*
X2150924Y484815D01*
X2149178Y485398D01*
G01X2084216Y504589D02*
X2085745Y503131D01*
X2087491Y502548D01*
X2089238Y503131D01*
X2090766Y504881D01*
X2091858Y507506D01*
X2092295Y510131D01*
Y513339D01*
X2091858Y515964D01*
X2090766Y518298D01*
X2089456Y519465D01*
X2087928Y520048D01*
X2086181Y519465D01*
X2084871Y518298D01*
X2083998Y516548D01*
X2083561Y514214D01*
X2083998Y512173D01*
X2085090Y510131D01*
X2086400Y508964D01*
X2087928Y508673D01*
X2089674Y509256D01*
X2090985Y510715D01*
X2092295Y513339D01*
G01X2100625Y505172D02*
X2101934Y503714D01*
X2103463Y502840D01*
X2105428Y502548D01*
X2107393Y503131D01*
X2108921Y504298D01*
X2110013Y506339D01*
X2110231Y508673D01*
X2109795Y511006D01*
X2108703Y512465D01*
X2107174Y513631D01*
X2105646Y513923D01*
X2104118Y513631D01*
X2102153Y512465D01*
X2102808Y520048D01*
X2108703D01*
G01X2122928Y501965D02*
X2122491Y502256D01*
Y502840D01*
X2122928Y503131D01*
X2123365Y502840D01*
Y502256D01*
X2122928Y501965D01*
G01X2140428Y520048D02*
X2138681Y519465D01*
X2137371Y518006D01*
X2136498Y516257D01*
X2135843Y513923D01*
X2135625Y511298D01*
X2135843Y508673D01*
X2136498Y506339D01*
X2137371Y504589D01*
X2138681Y503131D01*
X2140428Y502548D01*
X2142174Y503131D01*
X2143485Y504589D01*
X2144358Y506339D01*
X2145013Y508673D01*
X2145231Y511298D01*
X2145013Y513923D01*
X2144358Y516257D01*
X2143485Y518006D01*
X2142174Y519465D01*
X2140428Y520048D01*
G01X2087928Y537198D02*
X2089456Y537490D01*
X2091203Y538364D01*
X2092295Y539822D01*
X2092731Y541865D01*
X2092295Y543906D01*
X2090985Y545656D01*
X2089020Y546531D01*
X2086836D01*
X2085526Y547115D01*
X2084434Y548573D01*
X2083998Y550614D01*
X2084653Y552656D01*
X2086181Y554115D01*
X2087928Y554698D01*
X2089674Y554115D01*
X2091203Y552656D01*
X2091858Y550614D01*
X2091421Y548573D01*
X2090330Y547115D01*
X2089020Y546531D01*
X2086836D01*
X2084871Y545656D01*
X2083561Y543906D01*
X2083125Y541865D01*
X2083561Y539822D01*
X2084653Y538364D01*
X2086400Y537490D01*
X2087928Y537198D01*
G01X2100625Y539822D02*
X2101934Y538364D01*
X2103463Y537490D01*
X2105428Y537198D01*
X2107393Y537781D01*
X2108921Y538948D01*
X2110013Y540989D01*
X2110231Y543323D01*
X2109795Y545656D01*
X2108703Y547115D01*
X2107174Y548281D01*
X2105646Y548573D01*
X2104118Y548281D01*
X2102153Y547115D01*
X2102808Y554698D01*
X2108703D01*
G01X2122928Y536615D02*
X2122491Y536906D01*
Y537490D01*
X2122928Y537781D01*
X2123365Y537490D01*
Y536906D01*
X2122928Y536615D01*
G01X2140428Y554698D02*
X2138681Y554115D01*
X2137371Y552656D01*
X2136498Y550907D01*
X2135843Y548573D01*
X2135625Y545948D01*
X2135843Y543323D01*
X2136498Y540989D01*
X2137371Y539239D01*
X2138681Y537781D01*
X2140428Y537198D01*
X2142174Y537781D01*
X2143485Y539239D01*
X2144358Y540989D01*
X2145013Y543323D01*
X2145231Y545948D01*
X2145013Y548573D01*
X2144358Y550907D01*
X2143485Y552656D01*
X2142174Y554115D01*
X2140428Y554698D01*
G01X2087491Y571848D02*
X2087928Y575639D01*
X2088583Y578848D01*
X2089456Y581765D01*
X2090548Y584973D01*
X2092295Y589348D01*
X2083561D01*
G01X2100625Y575348D02*
X2101934Y573306D01*
X2103681Y572140D01*
X2105646Y571848D01*
X2107393Y572140D01*
X2109140Y573598D01*
X2110231Y575348D01*
X2110450Y577098D01*
X2110013Y579139D01*
X2108485Y580598D01*
X2106956Y581181D01*
X2104991D01*
G01X2106956D02*
X2108266Y582056D01*
X2109358Y583514D01*
X2109795Y585264D01*
X2109358Y587015D01*
X2108266Y588473D01*
X2106301Y589348D01*
X2104336Y589056D01*
X2102371Y587889D01*
G01X2122928Y571265D02*
X2122491Y571556D01*
Y572140D01*
X2122928Y572431D01*
X2123365Y572140D01*
Y571556D01*
X2122928Y571265D01*
G01X2140428Y589348D02*
X2138681Y588765D01*
X2137371Y587306D01*
X2136498Y585557D01*
X2135843Y583223D01*
X2135625Y580598D01*
X2135843Y577973D01*
X2136498Y575639D01*
X2137371Y573889D01*
X2138681Y572431D01*
X2140428Y571848D01*
X2142174Y572431D01*
X2143485Y573889D01*
X2144358Y575639D01*
X2145013Y577973D01*
X2145231Y580598D01*
X2145013Y583223D01*
X2144358Y585557D01*
X2143485Y587306D01*
X2142174Y588765D01*
X2140428Y589348D01*
G01X2050308Y623998D02*
X2055548D01*
G01X2052928D02*
Y606498D01*
G01X2050308D02*
X2055548D01*
G01X2064751D02*
Y623998D01*
X2070428Y609415D01*
X2076105Y623998D01*
Y606498D01*
G01X2083561D02*
Y623998D01*
X2088801D01*
X2090548Y623123D01*
X2091858Y621081D01*
X2092295Y618748D01*
X2091858Y616415D01*
X2090766Y614665D01*
X2088801Y613789D01*
X2083561D01*
G01X2104336Y600665D02*
X2102153Y603581D01*
X2101061Y606498D01*
Y618164D01*
X2102153Y621081D01*
X2104336Y623998D01*
G01X2122928Y606498D02*
X2121181Y606790D01*
X2119653Y607956D01*
X2118343Y609706D01*
X2117469Y611748D01*
X2117033Y614081D01*
Y616415D01*
X2117469Y618748D01*
X2118343Y620790D01*
X2119653Y622539D01*
X2121181Y623706D01*
X2122928Y623998D01*
X2124674Y623706D01*
X2126203Y622539D01*
X2127513Y620790D01*
X2128387Y618748D01*
X2128823Y616415D01*
Y614081D01*
X2128387Y611748D01*
X2127513Y609706D01*
X2126203Y607956D01*
X2124674Y606790D01*
X2122928Y606498D01*
G01X2136716D02*
Y623998D01*
G01Y615540D02*
X2137808Y616998D01*
X2138900Y617873D01*
X2140646Y618164D01*
X2141956Y617873D01*
X2143485Y616706D01*
X2144140Y614956D01*
Y606498D01*
G01X2151378D02*
Y618164D01*
G01Y614956D02*
X2152033Y616415D01*
X2153125Y617581D01*
X2154653Y618164D01*
X2156181Y617581D01*
X2157273Y616415D01*
X2157928Y614956D01*
Y606498D01*
G01Y614956D02*
X2158583Y616415D01*
X2159674Y617581D01*
X2161203Y618164D01*
X2162731Y617581D01*
X2163823Y616415D01*
X2164478Y614665D01*
Y606498D01*
G01X2176520Y600665D02*
X2178703Y603581D01*
X2179795Y606498D01*
Y618164D01*
X2178703Y621081D01*
X2176520Y623998D01*
G01X2028425Y641148D02*
Y658648D01*
X2032791D01*
X2034538Y657773D01*
X2035848Y656606D01*
X2036940Y654857D01*
X2037813Y652814D01*
X2038031Y649898D01*
X2037813Y646981D01*
X2036940Y644939D01*
X2035848Y643189D01*
X2034538Y642023D01*
X2032791Y641148D01*
X2028425D01*
G01X2046361D02*
Y658648D01*
X2051601D01*
X2053348Y657773D01*
X2054658Y655731D01*
X2055095Y653398D01*
X2054658Y651065D01*
X2053566Y649315D01*
X2051601Y648439D01*
X2046361D01*
G01X2083108Y658648D02*
X2088348D01*
G01X2085728D02*
Y641148D01*
G01X2083108D02*
X2088348D01*
G01X2097551D02*
Y658648D01*
X2103228Y644065D01*
X2108905Y658648D01*
Y641148D01*
G01X2116361D02*
Y658648D01*
X2121601D01*
X2123348Y657773D01*
X2124658Y655731D01*
X2125095Y653398D01*
X2124658Y651065D01*
X2123566Y649315D01*
X2121601Y648439D01*
X2116361D01*
G01X2142595Y641148D02*
X2133861D01*
Y658648D01*
X2142595D01*
G01X2139101Y650190D02*
X2133861D01*
G01X2150925Y641148D02*
Y658648D01*
X2155291D01*
X2157038Y657773D01*
X2158348Y656606D01*
X2159440Y654857D01*
X2160313Y652814D01*
X2160531Y649898D01*
X2160313Y646981D01*
X2159440Y644939D01*
X2158348Y643189D01*
X2157038Y642023D01*
X2155291Y641148D01*
X2150925D01*
G01X2167769D02*
X2173228Y658648D01*
X2178687Y641148D01*
G01X2176721Y647273D02*
X2169734D01*
G01X2185706Y641148D02*
Y658648D01*
X2195750Y641148D01*
Y658648D01*
G01X2213031Y657189D02*
X2211721Y658065D01*
X2210193Y658648D01*
X2208446D01*
X2206481Y657773D01*
X2204953Y656315D01*
X2203861Y654564D01*
X2202988Y651648D01*
X2202769Y649023D01*
X2203206Y646398D01*
X2203861Y644648D01*
X2205171Y642898D01*
X2206700Y641731D01*
X2208228Y641148D01*
X2209756D01*
X2211285Y641731D01*
X2212595Y642606D01*
X2213687Y643772D01*
G01X2230095Y641148D02*
X2221361D01*
Y658648D01*
X2230095D01*
G01X2226601Y650190D02*
X2221361D01*
G01X2260728Y658648D02*
Y641148D01*
G01X2255706Y658648D02*
X2265750D01*
G01X2272769Y641148D02*
X2278228Y658648D01*
X2283687Y641148D01*
G01X2281721Y647273D02*
X2274734D01*
G01X2297474Y650481D02*
X2298348Y651356D01*
X2299003Y652814D01*
X2299440Y654857D01*
X2299003Y656606D01*
X2298130Y657773D01*
X2296601Y658648D01*
X2290706D01*
Y641148D01*
X2297911D01*
X2299440Y642314D01*
X2300313Y644065D01*
X2300750Y646106D01*
X2300313Y648148D01*
X2299003Y649898D01*
X2297474Y650481D01*
X2290706D01*
G01X2308861Y658648D02*
Y641148D01*
X2317595D01*
G01X2335095D02*
X2326361D01*
Y658648D01*
X2335095D01*
G01X2331601Y650190D02*
X2326361D01*
G01X2348228Y640565D02*
X2347791Y640856D01*
Y641440D01*
X2348228Y641731D01*
X2348665Y641440D01*
Y640856D01*
X2348228Y640565D01*
G01Y648439D02*
X2347791Y648731D01*
Y649315D01*
X2348228Y649606D01*
X2348665Y649315D01*
Y648731D01*
X2348228Y648439D01*
G01X2378861Y658648D02*
Y641148D01*
X2387595D01*
G01X2395925Y643772D02*
X2397234Y642314D01*
X2398763Y641440D01*
X2400728Y641148D01*
X2402693Y641731D01*
X2404221Y642898D01*
X2405313Y644939D01*
X2405531Y647273D01*
X2405095Y649606D01*
X2404003Y651065D01*
X2402474Y652231D01*
X2400946Y652523D01*
X2399418Y652231D01*
X2397453Y651065D01*
X2398108Y658648D01*
X2404003D01*
G01X2284375Y467315D02*
X2293981Y480148D01*
G01X2289178Y482481D02*
Y464981D01*
G01X2293981Y467315D02*
X2284375Y480148D01*
G01X2282628Y473731D02*
X2295728D01*
G01X2301875Y471398D02*
X2303184Y469356D01*
X2304931Y468190D01*
X2306896Y467898D01*
X2308643Y468190D01*
X2310390Y469648D01*
X2311481Y471398D01*
X2311700Y473148D01*
X2311263Y475189D01*
X2309735Y476648D01*
X2308206Y477231D01*
X2306241D01*
G01X2308206D02*
X2309516Y478106D01*
X2310608Y479564D01*
X2311045Y481314D01*
X2310608Y483065D01*
X2309516Y484523D01*
X2307551Y485398D01*
X2305586Y485106D01*
X2303621Y483939D01*
G01X2324178Y467315D02*
X2323741Y467606D01*
Y468190D01*
X2324178Y468481D01*
X2324615Y468190D01*
Y467606D01*
X2324178Y467315D01*
G01X2337966Y469939D02*
X2339495Y468481D01*
X2341241Y467898D01*
X2342988Y468481D01*
X2344516Y470231D01*
X2345608Y472856D01*
X2346045Y475481D01*
Y478689D01*
X2345608Y481314D01*
X2344516Y483648D01*
X2343206Y484815D01*
X2341678Y485398D01*
X2339931Y484815D01*
X2338621Y483648D01*
X2337748Y481898D01*
X2337311Y479564D01*
X2337748Y477523D01*
X2338840Y475481D01*
X2340150Y474314D01*
X2341678Y474023D01*
X2343424Y474606D01*
X2344735Y476065D01*
X2346045Y478689D01*
G01X2355466Y469939D02*
X2356995Y468481D01*
X2358741Y467898D01*
X2360488Y468481D01*
X2362016Y470231D01*
X2363108Y472856D01*
X2363545Y475481D01*
Y478689D01*
X2363108Y481314D01*
X2362016Y483648D01*
X2360706Y484815D01*
X2359178Y485398D01*
X2357431Y484815D01*
X2356121Y483648D01*
X2355248Y481898D01*
X2354811Y479564D01*
X2355248Y477523D01*
X2356340Y475481D01*
X2357650Y474314D01*
X2359178Y474023D01*
X2360924Y474606D01*
X2362235Y476065D01*
X2363545Y478689D01*
G01X2372748Y467315D02*
X2380608Y485398D01*
G01X2394178Y467898D02*
Y485398D01*
X2391558Y481898D01*
G01Y467898D02*
X2396798D01*
G01X2407530Y482481D02*
X2408840Y484231D01*
X2410368Y485106D01*
X2412115Y485398D01*
X2414298Y484815D01*
X2415826Y483356D01*
X2416263Y481607D01*
X2416045Y479856D01*
X2415171Y478398D01*
X2410805Y475481D01*
X2408840Y473440D01*
X2407530Y470522D01*
X2407093Y467898D01*
X2416263D01*
G01X2429178Y467315D02*
X2428741Y467606D01*
Y468190D01*
X2429178Y468481D01*
X2429615Y468190D01*
Y467606D01*
X2429178Y467315D01*
G01X2441875Y470522D02*
X2443184Y469064D01*
X2444713Y468190D01*
X2446678Y467898D01*
X2448643Y468481D01*
X2450171Y469648D01*
X2451263Y471689D01*
X2451481Y474023D01*
X2451045Y476356D01*
X2449953Y477815D01*
X2448424Y478981D01*
X2446896Y479273D01*
X2445368Y478981D01*
X2443403Y477815D01*
X2444058Y485398D01*
X2449953D01*
G01X2460030Y482481D02*
X2461340Y484231D01*
X2462868Y485106D01*
X2464615Y485398D01*
X2466798Y484815D01*
X2468326Y483356D01*
X2468763Y481607D01*
X2468545Y479856D01*
X2467671Y478398D01*
X2463305Y475481D01*
X2461340Y473440D01*
X2460030Y470522D01*
X2459593Y467898D01*
X2468763D01*
G01X2284375Y501965D02*
X2293981Y514798D01*
G01X2289178Y517131D02*
Y499631D01*
G01X2293981Y501965D02*
X2284375Y514798D01*
G01X2282628Y508381D02*
X2295728D01*
G01X2309298Y502548D02*
Y520048D01*
X2301219Y507506D01*
X2312137D01*
G01X2324178Y501965D02*
X2323741Y502256D01*
Y502840D01*
X2324178Y503131D01*
X2324615Y502840D01*
Y502256D01*
X2324178Y501965D01*
G01X2341678Y520048D02*
X2339931Y519465D01*
X2338621Y518006D01*
X2337748Y516257D01*
X2337093Y513923D01*
X2336875Y511298D01*
X2337093Y508673D01*
X2337748Y506339D01*
X2338621Y504589D01*
X2339931Y503131D01*
X2341678Y502548D01*
X2343424Y503131D01*
X2344735Y504589D01*
X2345608Y506339D01*
X2346263Y508673D01*
X2346481Y511298D01*
X2346263Y513923D01*
X2345608Y516257D01*
X2344735Y518006D01*
X2343424Y519465D01*
X2341678Y520048D01*
G01X2355030Y517131D02*
X2356340Y518881D01*
X2357868Y519756D01*
X2359615Y520048D01*
X2361798Y519465D01*
X2363326Y518006D01*
X2363763Y516257D01*
X2363545Y514506D01*
X2362671Y513048D01*
X2358305Y510131D01*
X2356340Y508090D01*
X2355030Y505172D01*
X2354593Y502548D01*
X2363763D01*
G01X2372748Y501965D02*
X2380608Y520048D01*
G01X2394178Y502548D02*
Y520048D01*
X2391558Y516548D01*
G01Y502548D02*
X2396798D01*
G01X2411678D02*
Y520048D01*
X2409058Y516548D01*
G01Y502548D02*
X2414298D01*
G01X2429178Y501965D02*
X2428741Y502256D01*
Y502840D01*
X2429178Y503131D01*
X2429615Y502840D01*
Y502256D01*
X2429178Y501965D01*
G01X2442966Y504589D02*
X2444495Y503131D01*
X2446241Y502548D01*
X2447988Y503131D01*
X2449516Y504881D01*
X2450608Y507506D01*
X2451045Y510131D01*
Y513339D01*
X2450608Y515964D01*
X2449516Y518298D01*
X2448206Y519465D01*
X2446678Y520048D01*
X2444931Y519465D01*
X2443621Y518298D01*
X2442748Y516548D01*
X2442311Y514214D01*
X2442748Y512173D01*
X2443840Y510131D01*
X2445150Y508964D01*
X2446678Y508673D01*
X2448424Y509256D01*
X2449735Y510715D01*
X2451045Y513339D01*
G01X2464178Y502548D02*
X2465706Y502840D01*
X2467453Y503714D01*
X2468545Y505172D01*
X2468981Y507215D01*
X2468545Y509256D01*
X2467235Y511006D01*
X2465270Y511881D01*
X2463086D01*
X2461776Y512465D01*
X2460684Y513923D01*
X2460248Y515964D01*
X2460903Y518006D01*
X2462431Y519465D01*
X2464178Y520048D01*
X2465924Y519465D01*
X2467453Y518006D01*
X2468108Y515964D01*
X2467671Y513923D01*
X2466580Y512465D01*
X2465270Y511881D01*
X2463086D01*
X2461121Y511006D01*
X2459811Y509256D01*
X2459375Y507215D01*
X2459811Y505172D01*
X2460903Y503714D01*
X2462650Y502840D01*
X2464178Y502548D01*
G01X2326798Y537198D02*
Y554698D01*
X2318719Y542156D01*
X2329637D01*
G01X2341678Y536615D02*
X2341241Y536906D01*
Y537490D01*
X2341678Y537781D01*
X2342115Y537490D01*
Y536906D01*
X2341678Y536615D01*
G01X2354375Y539822D02*
X2355684Y538364D01*
X2357213Y537490D01*
X2359178Y537198D01*
X2361143Y537781D01*
X2362671Y538948D01*
X2363763Y540989D01*
X2363981Y543323D01*
X2363545Y545656D01*
X2362453Y547115D01*
X2360924Y548281D01*
X2359396Y548573D01*
X2357868Y548281D01*
X2355903Y547115D01*
X2356558Y554698D01*
X2362453D01*
G01X2372748Y536615D02*
X2380608Y554698D01*
G01X2393741Y537198D02*
X2394178Y540989D01*
X2394833Y544198D01*
X2395706Y547115D01*
X2396798Y550323D01*
X2398545Y554698D01*
X2389811D01*
G01X2411678Y536615D02*
X2411241Y536906D01*
Y537490D01*
X2411678Y537781D01*
X2412115Y537490D01*
Y536906D01*
X2411678Y536615D01*
G01X2429178Y554698D02*
X2427431Y554115D01*
X2426121Y552656D01*
X2425248Y550907D01*
X2424593Y548573D01*
X2424375Y545948D01*
X2424593Y543323D01*
X2425248Y540989D01*
X2426121Y539239D01*
X2427431Y537781D01*
X2429178Y537198D01*
X2430924Y537781D01*
X2432235Y539239D01*
X2433108Y540989D01*
X2433763Y543323D01*
X2433981Y545948D01*
X2433763Y548573D01*
X2433108Y550907D01*
X2432235Y552656D01*
X2430924Y554115D01*
X2429178Y554698D01*
G01X2319375Y574472D02*
X2320684Y573014D01*
X2322213Y572140D01*
X2324178Y571848D01*
X2326143Y572431D01*
X2327671Y573598D01*
X2328763Y575639D01*
X2328981Y577973D01*
X2328545Y580306D01*
X2327453Y581765D01*
X2325924Y582931D01*
X2324396Y583223D01*
X2322868Y582931D01*
X2320903Y581765D01*
X2321558Y589348D01*
X2327453D01*
G01X2341678Y571265D02*
X2341241Y571556D01*
Y572140D01*
X2341678Y572431D01*
X2342115Y572140D01*
Y571556D01*
X2341678Y571265D01*
G01X2355030Y579139D02*
X2356558Y581181D01*
X2357868Y582348D01*
X2359615Y582931D01*
X2361143Y582348D01*
X2362235Y581181D01*
X2363108Y579431D01*
X2363326Y577390D01*
X2363108Y575639D01*
X2362235Y573889D01*
X2360924Y572431D01*
X2359396Y571848D01*
X2357650Y572431D01*
X2356121Y574181D01*
X2355248Y576806D01*
X2355030Y579723D01*
X2355466Y583514D01*
X2356121Y585557D01*
X2357213Y587598D01*
X2358741Y589056D01*
X2360270Y589348D01*
X2361798Y588765D01*
X2362890Y587306D01*
G01X2372748Y571265D02*
X2380608Y589348D01*
G01X2389375Y574472D02*
X2390684Y573014D01*
X2392213Y572140D01*
X2394178Y571848D01*
X2396143Y572431D01*
X2397671Y573598D01*
X2398763Y575639D01*
X2398981Y577973D01*
X2398545Y580306D01*
X2397453Y581765D01*
X2395924Y582931D01*
X2394396Y583223D01*
X2392868Y582931D01*
X2390903Y581765D01*
X2391558Y589348D01*
X2397453D01*
G01X2411678Y571265D02*
X2411241Y571556D01*
Y572140D01*
X2411678Y572431D01*
X2412115Y572140D01*
Y571556D01*
X2411678Y571265D01*
G01X2429178Y589348D02*
X2427431Y588765D01*
X2426121Y587306D01*
X2425248Y585557D01*
X2424593Y583223D01*
X2424375Y580598D01*
X2424593Y577973D01*
X2425248Y575639D01*
X2426121Y573889D01*
X2427431Y572431D01*
X2429178Y571848D01*
X2430924Y572431D01*
X2432235Y573889D01*
X2433108Y575639D01*
X2433763Y577973D01*
X2433981Y580598D01*
X2433763Y583223D01*
X2433108Y585557D01*
X2432235Y587306D01*
X2430924Y588765D01*
X2429178Y589348D01*
G01X2282628Y623998D02*
X2285684Y606498D01*
X2289178Y623998D01*
X2292671Y606498D01*
X2295728Y623998D01*
G01X2304058D02*
X2309298D01*
G01X2306678D02*
Y606498D01*
G01X2304058D02*
X2309298D01*
G01X2319375D02*
Y623998D01*
X2323741D01*
X2325488Y623123D01*
X2326798Y621956D01*
X2327890Y620207D01*
X2328763Y618164D01*
X2328981Y615248D01*
X2328763Y612331D01*
X2327890Y610289D01*
X2326798Y608539D01*
X2325488Y607373D01*
X2323741Y606498D01*
X2319375D01*
G01X2341678Y623998D02*
Y606498D01*
G01X2336656Y623998D02*
X2346700D01*
G01X2354593Y606498D02*
Y623998D01*
G01X2363763D02*
Y606498D01*
G01Y615248D02*
X2354593D01*
G01X2375586Y600665D02*
X2373403Y603581D01*
X2372311Y606498D01*
Y618164D01*
X2373403Y621081D01*
X2375586Y623998D01*
G01X2387628Y606498D02*
Y618164D01*
G01Y614956D02*
X2388283Y616415D01*
X2389375Y617581D01*
X2390903Y618164D01*
X2392431Y617581D01*
X2393523Y616415D01*
X2394178Y614956D01*
Y606498D01*
G01Y614956D02*
X2394833Y616415D01*
X2395924Y617581D01*
X2397453Y618164D01*
X2398981Y617581D01*
X2400073Y616415D01*
X2400728Y614665D01*
Y606498D01*
G01X2411678Y618164D02*
Y606498D01*
G01Y622831D02*
X2411241Y623123D01*
Y623706D01*
X2411678Y623998D01*
X2412115Y623706D01*
Y623123D01*
X2411678Y622831D01*
G01X2429178Y606498D02*
Y623998D01*
G01X2443403Y608539D02*
X2444495Y607373D01*
X2446023Y606498D01*
X2447333D01*
X2448643Y607081D01*
X2449516Y607956D01*
X2449953Y609122D01*
X2449735Y610873D01*
X2448861Y611748D01*
X2444931Y613498D01*
X2444058Y615540D01*
X2444495Y616998D01*
X2445368Y617873D01*
X2446678Y618164D01*
X2447988Y617873D01*
X2449298Y616998D01*
G01X2465270Y600665D02*
X2467453Y603581D01*
X2468545Y606498D01*
Y618164D01*
X2467453Y621081D01*
X2465270Y623998D01*
G01X2577928D02*
Y606498D01*
G01X2572906Y623998D02*
X2582950D01*
G01X2595428Y606498D02*
Y614373D01*
X2591061Y623998D01*
G01X2599795D02*
X2595428Y614373D01*
G01X2608561Y606498D02*
Y623998D01*
X2613801D01*
X2615548Y623123D01*
X2616858Y621081D01*
X2617295Y618748D01*
X2616858Y616415D01*
X2615766Y614665D01*
X2613801Y613789D01*
X2608561D01*
G01X2634795Y606498D02*
X2626061D01*
Y623998D01*
X2634795D01*
G01X2631301Y615540D02*
X2626061D01*
G01X2590625Y467898D02*
Y485398D01*
X2594991D01*
X2596738Y484523D01*
X2598048Y483356D01*
X2599140Y481607D01*
X2600013Y479564D01*
X2600231Y476648D01*
X2600013Y473731D01*
X2599140Y471689D01*
X2598048Y469939D01*
X2596738Y468773D01*
X2594991Y467898D01*
X2590625D01*
G01X2608561D02*
Y485398D01*
X2613801D01*
X2615548Y484523D01*
X2616858Y482481D01*
X2617295Y480148D01*
X2616858Y477815D01*
X2615766Y476065D01*
X2613801Y475189D01*
X2608561D01*
G01X2590625Y502548D02*
Y520048D01*
X2594991D01*
X2596738Y519173D01*
X2598048Y518006D01*
X2599140Y516257D01*
X2600013Y514214D01*
X2600231Y511298D01*
X2600013Y508381D01*
X2599140Y506339D01*
X2598048Y504589D01*
X2596738Y503423D01*
X2594991Y502548D01*
X2590625D01*
G01X2608561D02*
Y520048D01*
X2613801D01*
X2615548Y519173D01*
X2616858Y517131D01*
X2617295Y514798D01*
X2616858Y512465D01*
X2615766Y510715D01*
X2613801Y509839D01*
X2608561D01*
G01X2590625Y537198D02*
Y554698D01*
X2594991D01*
X2596738Y553823D01*
X2598048Y552656D01*
X2599140Y550907D01*
X2600013Y548864D01*
X2600231Y545948D01*
X2600013Y543031D01*
X2599140Y540989D01*
X2598048Y539239D01*
X2596738Y538073D01*
X2594991Y537198D01*
X2590625D01*
G01X2608561D02*
Y554698D01*
X2613801D01*
X2615548Y553823D01*
X2616858Y551781D01*
X2617295Y549448D01*
X2616858Y547115D01*
X2615766Y545365D01*
X2613801Y544489D01*
X2608561D01*
G01X2590625Y571848D02*
Y589348D01*
X2594991D01*
X2596738Y588473D01*
X2598048Y587306D01*
X2599140Y585557D01*
X2600013Y583514D01*
X2600231Y580598D01*
X2600013Y577681D01*
X2599140Y575639D01*
X2598048Y573889D01*
X2596738Y572723D01*
X2594991Y571848D01*
X2590625D01*
G01X2608561D02*
Y589348D01*
X2613801D01*
X2615548Y588473D01*
X2616858Y586431D01*
X2617295Y584098D01*
X2616858Y581765D01*
X2615766Y580015D01*
X2613801Y579139D01*
X2608561D01*
G01X2678561Y606498D02*
Y623998D01*
X2684020D01*
X2685766Y623123D01*
X2686858Y621956D01*
X2687295Y619623D01*
X2686858Y617289D01*
X2685548Y615831D01*
X2684020Y614956D01*
X2678561D01*
G01X2684020D02*
X2687295Y606498D01*
G01X2697153Y614373D02*
X2704140D01*
X2703485Y616415D01*
X2702393Y617581D01*
X2700865Y618164D01*
X2699336Y617873D01*
X2698026Y616998D01*
X2697153Y614956D01*
X2696716Y613206D01*
Y611456D01*
X2697153Y609706D01*
X2698245Y607956D01*
X2699555Y606790D01*
X2701083Y606498D01*
X2702611Y607081D01*
X2704140Y608831D01*
G01X2716618Y606498D02*
Y621373D01*
X2717055Y622831D01*
X2717928Y623706D01*
X2719238Y623998D01*
X2720548Y623415D01*
X2721203Y621956D01*
G01X2718583Y616998D02*
X2714216D01*
G01X2735428Y605915D02*
X2734991Y606206D01*
Y606790D01*
X2735428Y607081D01*
X2735865Y606790D01*
Y606206D01*
X2735428Y605915D01*
G01X2766061Y606498D02*
Y623998D01*
X2771301D01*
X2773048Y623123D01*
X2774358Y621081D01*
X2774795Y618748D01*
X2774358Y616415D01*
X2773266Y614665D01*
X2771301Y613789D01*
X2766061D01*
G01X2787928Y606498D02*
Y623998D01*
G01X2809358Y606498D02*
Y618164D01*
G01Y616123D02*
X2808485Y617289D01*
X2807174Y617873D01*
X2805646Y618164D01*
X2804118Y617581D01*
X2802808Y616415D01*
X2801934Y614665D01*
X2801498Y612331D01*
X2801934Y609998D01*
X2802808Y608248D01*
X2804118Y607081D01*
X2805646Y606498D01*
X2807174Y606790D01*
X2808485Y607664D01*
X2809358Y608831D01*
G01X2819216Y606498D02*
Y618164D01*
G01Y615248D02*
X2820090Y616706D01*
X2821400Y617873D01*
X2823146Y618164D01*
X2824674Y617873D01*
X2825985Y616706D01*
X2826640Y614665D01*
Y606498D01*
G01X2837153Y614373D02*
X2844140D01*
X2843485Y616415D01*
X2842393Y617581D01*
X2840865Y618164D01*
X2839336Y617873D01*
X2838026Y616998D01*
X2837153Y614956D01*
X2836716Y613206D01*
Y611456D01*
X2837153Y609706D01*
X2838245Y607956D01*
X2839555Y606790D01*
X2841083Y606498D01*
X2842611Y607081D01*
X2844140Y608831D01*
G01X2722311Y485398D02*
Y467898D01*
X2731045D01*
G01X2746798D02*
Y485398D01*
X2738719Y472856D01*
X2749637D01*
G01X2757748Y467315D02*
X2765608Y485398D01*
G01X2774811D02*
Y467898D01*
X2783545D01*
G01X2792530Y475189D02*
X2794058Y477231D01*
X2795368Y478398D01*
X2797115Y478981D01*
X2798643Y478398D01*
X2799735Y477231D01*
X2800608Y475481D01*
X2800826Y473440D01*
X2800608Y471689D01*
X2799735Y469939D01*
X2798424Y468481D01*
X2796896Y467898D01*
X2795150Y468481D01*
X2793621Y470231D01*
X2792748Y472856D01*
X2792530Y475773D01*
X2792966Y479564D01*
X2793621Y481607D01*
X2794713Y483648D01*
X2796241Y485106D01*
X2797770Y485398D01*
X2799298Y484815D01*
X2800390Y483356D01*
G01X2722311Y520048D02*
Y502548D01*
X2731045D01*
G01X2746798D02*
Y520048D01*
X2738719Y507506D01*
X2749637D01*
G01X2757748Y501965D02*
X2765608Y520048D01*
G01X2774811D02*
Y502548D01*
X2783545D01*
G01X2792530Y509839D02*
X2794058Y511881D01*
X2795368Y513048D01*
X2797115Y513631D01*
X2798643Y513048D01*
X2799735Y511881D01*
X2800608Y510131D01*
X2800826Y508090D01*
X2800608Y506339D01*
X2799735Y504589D01*
X2798424Y503131D01*
X2796896Y502548D01*
X2795150Y503131D01*
X2793621Y504881D01*
X2792748Y507506D01*
X2792530Y510423D01*
X2792966Y514214D01*
X2793621Y516257D01*
X2794713Y518298D01*
X2796241Y519756D01*
X2797770Y520048D01*
X2799298Y519465D01*
X2800390Y518006D01*
G01X2722311Y554698D02*
Y537198D01*
X2731045D01*
G01X2746798D02*
Y554698D01*
X2738719Y542156D01*
X2749637D01*
G01X2757748Y536615D02*
X2765608Y554698D01*
G01X2774811D02*
Y537198D01*
X2783545D01*
G01X2792530Y544489D02*
X2794058Y546531D01*
X2795368Y547698D01*
X2797115Y548281D01*
X2798643Y547698D01*
X2799735Y546531D01*
X2800608Y544781D01*
X2800826Y542740D01*
X2800608Y540989D01*
X2799735Y539239D01*
X2798424Y537781D01*
X2796896Y537198D01*
X2795150Y537781D01*
X2793621Y539531D01*
X2792748Y542156D01*
X2792530Y545073D01*
X2792966Y548864D01*
X2793621Y550907D01*
X2794713Y552948D01*
X2796241Y554406D01*
X2797770Y554698D01*
X2799298Y554115D01*
X2800390Y552656D01*
G01X2722311Y589348D02*
Y571848D01*
X2731045D01*
G01X2746798D02*
Y589348D01*
X2738719Y576806D01*
X2749637D01*
G01X2757748Y571265D02*
X2765608Y589348D01*
G01X2774811D02*
Y571848D01*
X2783545D01*
G01X2792530Y579139D02*
X2794058Y581181D01*
X2795368Y582348D01*
X2797115Y582931D01*
X2798643Y582348D01*
X2799735Y581181D01*
X2800608Y579431D01*
X2800826Y577390D01*
X2800608Y575639D01*
X2799735Y573889D01*
X2798424Y572431D01*
X2796896Y571848D01*
X2795150Y572431D01*
X2793621Y574181D01*
X2792748Y576806D01*
X2792530Y579723D01*
X2792966Y583514D01*
X2793621Y585557D01*
X2794713Y587598D01*
X2796241Y589056D01*
X2797770Y589348D01*
X2799298Y588765D01*
X2800390Y587306D01*
G01X2958228Y548864D02*
Y537198D01*
G01Y553531D02*
X2957791Y553823D01*
Y554406D01*
X2958228Y554698D01*
X2958665Y554406D01*
Y553823D01*
X2958228Y553531D01*
G01X2972016Y537198D02*
Y548864D01*
G01Y545948D02*
X2972890Y547406D01*
X2974200Y548573D01*
X2975946Y548864D01*
X2977474Y548573D01*
X2978785Y547406D01*
X2979440Y545365D01*
Y537198D01*
G01X2989953Y539239D02*
X2991045Y538073D01*
X2992573Y537198D01*
X2993883D01*
X2995193Y537781D01*
X2996066Y538656D01*
X2996503Y539822D01*
X2996285Y541573D01*
X2995411Y542448D01*
X2991481Y544198D01*
X2990608Y546240D01*
X2991045Y547698D01*
X2991918Y548573D01*
X2993228Y548864D01*
X2994538Y548573D01*
X2995848Y547698D01*
G01X3010728Y548864D02*
Y537198D01*
G01Y553531D02*
X3010291Y553823D01*
Y554406D01*
X3010728Y554698D01*
X3011165Y554406D01*
Y553823D01*
X3010728Y553531D01*
G01X3032158Y554698D02*
Y537198D01*
G01Y539822D02*
X3031285Y538364D01*
X3029974Y537490D01*
X3028446Y537198D01*
X3026700Y537781D01*
X3025390Y539239D01*
X3024516Y540989D01*
X3024298Y543031D01*
X3024516Y545073D01*
X3025390Y546823D01*
X3026700Y548281D01*
X3028446Y548864D01*
X3029974Y548573D01*
X3031066Y547989D01*
X3032158Y546823D01*
G01X3042453Y545073D02*
X3049440D01*
X3048785Y547115D01*
X3047693Y548281D01*
X3046165Y548864D01*
X3044636Y548573D01*
X3043326Y547698D01*
X3042453Y545656D01*
X3042016Y543906D01*
Y542156D01*
X3042453Y540406D01*
X3043545Y538656D01*
X3044855Y537490D01*
X3046383Y537198D01*
X3047911Y537781D01*
X3049440Y539531D01*
G01X3076798Y537198D02*
Y554698D01*
G01Y545948D02*
X3077890Y547698D01*
X3079200Y548573D01*
X3080510Y548864D01*
X3082474Y548281D01*
X3083785Y547115D01*
X3084658Y545073D01*
Y542740D01*
X3084221Y540406D01*
X3083348Y538656D01*
X3081820Y537490D01*
X3080510Y537198D01*
X3079200Y537490D01*
X3077890Y538364D01*
X3076798Y539822D01*
G01X3098228Y537198D02*
X3096918Y537490D01*
X3095608Y538656D01*
X3094734Y540698D01*
X3094298Y543031D01*
X3094734Y545365D01*
X3095608Y547406D01*
X3096918Y548573D01*
X3098228Y548864D01*
X3099538Y548573D01*
X3100848Y547406D01*
X3101721Y545365D01*
X3101940Y543031D01*
X3101721Y540698D01*
X3100848Y538656D01*
X3099538Y537490D01*
X3098228Y537198D01*
G01X3119658D02*
Y548864D01*
G01Y546823D02*
X3118785Y547989D01*
X3117474Y548573D01*
X3115946Y548864D01*
X3114418Y548281D01*
X3113108Y547115D01*
X3112234Y545365D01*
X3111798Y543031D01*
X3112234Y540698D01*
X3113108Y538948D01*
X3114418Y537781D01*
X3115946Y537198D01*
X3117474Y537490D01*
X3118785Y538364D01*
X3119658Y539531D01*
G01X3130171Y537198D02*
Y548864D01*
G01Y546531D02*
X3131263Y547698D01*
X3132355Y548573D01*
X3133883Y548864D01*
X3134974Y548573D01*
X3136285Y547698D01*
G01X3154658Y554698D02*
Y537198D01*
G01Y539822D02*
X3153785Y538364D01*
X3152474Y537490D01*
X3150946Y537198D01*
X3149200Y537781D01*
X3147890Y539239D01*
X3147016Y540989D01*
X3146798Y543031D01*
X3147016Y545073D01*
X3147890Y546823D01*
X3149200Y548281D01*
X3150946Y548864D01*
X3152474Y548573D01*
X3153566Y547989D01*
X3154658Y546823D01*
G01X3185728Y537198D02*
X3184418Y537490D01*
X3183108Y538656D01*
X3182234Y540698D01*
X3181798Y543031D01*
X3182234Y545365D01*
X3183108Y547406D01*
X3184418Y548573D01*
X3185728Y548864D01*
X3187038Y548573D01*
X3188348Y547406D01*
X3189221Y545365D01*
X3189440Y543031D01*
X3189221Y540698D01*
X3188348Y538656D01*
X3187038Y537490D01*
X3185728Y537198D01*
G01X3199516Y548864D02*
Y540698D01*
X3200390Y538656D01*
X3201700Y537490D01*
X3203228Y537198D01*
X3204756Y537490D01*
X3206066Y538656D01*
X3206940Y540698D01*
G01Y537198D02*
Y548864D01*
G01X3220728Y554698D02*
Y537198D01*
G01X3217671Y548864D02*
X3223785D01*
G01X3238228Y537198D02*
Y554698D01*
G01X3255728Y548864D02*
Y537198D01*
G01Y553531D02*
X3255291Y553823D01*
Y554406D01*
X3255728Y554698D01*
X3256165Y554406D01*
Y553823D01*
X3255728Y553531D01*
G01X3269516Y537198D02*
Y548864D01*
G01Y545948D02*
X3270390Y547406D01*
X3271700Y548573D01*
X3273446Y548864D01*
X3274974Y548573D01*
X3276285Y547406D01*
X3276940Y545365D01*
Y537198D01*
G01X3287453Y545073D02*
X3294440D01*
X3293785Y547115D01*
X3292693Y548281D01*
X3291165Y548864D01*
X3289636Y548573D01*
X3288326Y547698D01*
X3287453Y545656D01*
X3287016Y543906D01*
Y542156D01*
X3287453Y540406D01*
X3288545Y538656D01*
X3289855Y537490D01*
X3291383Y537198D01*
X3292911Y537781D01*
X3294440Y539531D01*
G01X3308228Y536615D02*
X3307791Y536906D01*
Y537490D01*
X3308228Y537781D01*
X3308665Y537490D01*
Y536906D01*
X3308228Y536615D01*
G01X2958228Y583514D02*
Y571848D01*
G01Y588181D02*
X2957791Y588473D01*
Y589056D01*
X2958228Y589348D01*
X2958665Y589056D01*
Y588473D01*
X2958228Y588181D01*
G01X2972453Y573889D02*
X2973545Y572723D01*
X2975073Y571848D01*
X2976383D01*
X2977693Y572431D01*
X2978566Y573306D01*
X2979003Y574472D01*
X2978785Y576223D01*
X2977911Y577098D01*
X2973981Y578848D01*
X2973108Y580890D01*
X2973545Y582348D01*
X2974418Y583223D01*
X2975728Y583514D01*
X2977038Y583223D01*
X2978348Y582348D01*
G01X3005706Y571848D02*
Y589348D01*
X3015750Y571848D01*
Y589348D01*
G01X3028228Y571848D02*
X3026481Y572140D01*
X3024953Y573306D01*
X3023643Y575056D01*
X3022769Y577098D01*
X3022333Y579431D01*
Y581765D01*
X3022769Y584098D01*
X3023643Y586140D01*
X3024953Y587889D01*
X3026481Y589056D01*
X3028228Y589348D01*
X3029974Y589056D01*
X3031503Y587889D01*
X3032813Y586140D01*
X3033687Y584098D01*
X3034123Y581765D01*
Y579431D01*
X3033687Y577098D01*
X3032813Y575056D01*
X3031503Y573306D01*
X3029974Y572140D01*
X3028228Y571848D01*
G01X3045728Y589348D02*
Y571848D01*
G01X3040706Y589348D02*
X3050750D01*
G01X3077016Y583514D02*
Y575348D01*
X3077890Y573306D01*
X3079200Y572140D01*
X3080728Y571848D01*
X3082256Y572140D01*
X3083566Y573306D01*
X3084440Y575348D01*
G01Y571848D02*
Y583514D01*
G01X3094953Y573889D02*
X3096045Y572723D01*
X3097573Y571848D01*
X3098883D01*
X3100193Y572431D01*
X3101066Y573306D01*
X3101503Y574472D01*
X3101285Y576223D01*
X3100411Y577098D01*
X3096481Y578848D01*
X3095608Y580890D01*
X3096045Y582348D01*
X3096918Y583223D01*
X3098228Y583514D01*
X3099538Y583223D01*
X3100848Y582348D01*
G01X3112453Y579723D02*
X3119440D01*
X3118785Y581765D01*
X3117693Y582931D01*
X3116165Y583514D01*
X3114636Y583223D01*
X3113326Y582348D01*
X3112453Y580306D01*
X3112016Y578556D01*
Y576806D01*
X3112453Y575056D01*
X3113545Y573306D01*
X3114855Y572140D01*
X3116383Y571848D01*
X3117911Y572431D01*
X3119440Y574181D01*
G01X3137158Y589348D02*
Y571848D01*
G01Y574472D02*
X3136285Y573014D01*
X3134974Y572140D01*
X3133446Y571848D01*
X3131700Y572431D01*
X3130390Y573889D01*
X3129516Y575639D01*
X3129298Y577681D01*
X3129516Y579723D01*
X3130390Y581473D01*
X3131700Y582931D01*
X3133446Y583514D01*
X3134974Y583223D01*
X3136066Y582639D01*
X3137158Y581473D01*
G01X3168228Y583514D02*
Y571848D01*
G01Y588181D02*
X3167791Y588473D01*
Y589056D01*
X3168228Y589348D01*
X3168665Y589056D01*
Y588473D01*
X3168228Y588181D01*
G01X3182016Y571848D02*
Y583514D01*
G01Y580598D02*
X3182890Y582056D01*
X3184200Y583223D01*
X3185946Y583514D01*
X3187474Y583223D01*
X3188785Y582056D01*
X3189440Y580015D01*
Y571848D01*
G01X3220728Y589348D02*
Y571848D01*
G01X3217671Y583514D02*
X3223785D01*
G01X3234516Y571848D02*
Y589348D01*
G01Y580890D02*
X3235608Y582348D01*
X3236700Y583223D01*
X3238446Y583514D01*
X3239756Y583223D01*
X3241285Y582056D01*
X3241940Y580306D01*
Y571848D01*
G01X3255728Y583514D02*
Y571848D01*
G01Y588181D02*
X3255291Y588473D01*
Y589056D01*
X3255728Y589348D01*
X3256165Y589056D01*
Y588473D01*
X3255728Y588181D01*
G01X3269953Y573889D02*
X3271045Y572723D01*
X3272573Y571848D01*
X3273883D01*
X3275193Y572431D01*
X3276066Y573306D01*
X3276503Y574472D01*
X3276285Y576223D01*
X3275411Y577098D01*
X3271481Y578848D01*
X3270608Y580890D01*
X3271045Y582348D01*
X3271918Y583223D01*
X3273228Y583514D01*
X3274538Y583223D01*
X3275848Y582348D01*
G01X3308228Y571848D02*
Y589348D01*
G01X3329658Y571848D02*
Y583514D01*
G01Y581473D02*
X3328785Y582639D01*
X3327474Y583223D01*
X3325946Y583514D01*
X3324418Y582931D01*
X3323108Y581765D01*
X3322234Y580015D01*
X3321798Y577681D01*
X3322234Y575348D01*
X3323108Y573598D01*
X3324418Y572431D01*
X3325946Y571848D01*
X3327474Y572140D01*
X3328785Y573014D01*
X3329658Y574181D01*
G01X3338643Y566598D02*
X3339953Y566015D01*
X3341700Y566598D01*
X3342791Y567764D01*
X3343665Y569223D01*
X3344974Y573889D01*
X3347813Y583514D01*
G01X3340826D02*
X3344974Y573889D01*
G01X3357453Y579723D02*
X3364440D01*
X3363785Y581765D01*
X3362693Y582931D01*
X3361165Y583514D01*
X3359636Y583223D01*
X3358326Y582348D01*
X3357453Y580306D01*
X3357016Y578556D01*
Y576806D01*
X3357453Y575056D01*
X3358545Y573306D01*
X3359855Y572140D01*
X3361383Y571848D01*
X3362911Y572431D01*
X3364440Y574181D01*
G01X3375171Y571848D02*
Y583514D01*
G01Y581181D02*
X3376263Y582348D01*
X3377355Y583223D01*
X3378883Y583514D01*
X3379974Y583223D01*
X3381285Y582348D01*
G01X2883425Y605915D02*
X2893031Y618748D01*
G01X2888228Y621081D02*
Y603581D01*
G01X2893031Y605915D02*
X2883425Y618748D01*
G01X2881678Y612331D02*
X2894778D01*
G01X2920390D02*
X2926066D01*
G01X2953425Y606498D02*
Y623998D01*
X2957791D01*
X2959538Y623123D01*
X2960848Y621956D01*
X2961940Y620207D01*
X2962813Y618164D01*
X2963031Y615248D01*
X2962813Y612331D01*
X2961940Y610289D01*
X2960848Y608539D01*
X2959538Y607373D01*
X2957791Y606498D01*
X2953425D01*
G01X2972453Y614373D02*
X2979440D01*
X2978785Y616415D01*
X2977693Y617581D01*
X2976165Y618164D01*
X2974636Y617873D01*
X2973326Y616998D01*
X2972453Y614956D01*
X2972016Y613206D01*
Y611456D01*
X2972453Y609706D01*
X2973545Y607956D01*
X2974855Y606790D01*
X2976383Y606498D01*
X2977911Y607081D01*
X2979440Y608831D01*
G01X2989516Y606498D02*
Y618164D01*
G01Y615248D02*
X2990390Y616706D01*
X2991700Y617873D01*
X2993446Y618164D01*
X2994974Y617873D01*
X2996285Y616706D01*
X2996940Y614665D01*
Y606498D01*
G01X3010728D02*
X3009418Y606790D01*
X3008108Y607956D01*
X3007234Y609998D01*
X3006798Y612331D01*
X3007234Y614665D01*
X3008108Y616706D01*
X3009418Y617873D01*
X3010728Y618164D01*
X3012038Y617873D01*
X3013348Y616706D01*
X3014221Y614665D01*
X3014440Y612331D01*
X3014221Y609998D01*
X3013348Y607956D01*
X3012038Y606790D01*
X3010728Y606498D01*
G01X3028228Y623998D02*
Y606498D01*
G01X3025171Y618164D02*
X3031285D01*
G01X3042453Y614373D02*
X3049440D01*
X3048785Y616415D01*
X3047693Y617581D01*
X3046165Y618164D01*
X3044636Y617873D01*
X3043326Y616998D01*
X3042453Y614956D01*
X3042016Y613206D01*
Y611456D01*
X3042453Y609706D01*
X3043545Y607956D01*
X3044855Y606790D01*
X3046383Y606498D01*
X3047911Y607081D01*
X3049440Y608831D01*
G01X3059953Y608539D02*
X3061045Y607373D01*
X3062573Y606498D01*
X3063883D01*
X3065193Y607081D01*
X3066066Y607956D01*
X3066503Y609122D01*
X3066285Y610873D01*
X3065411Y611748D01*
X3061481Y613498D01*
X3060608Y615540D01*
X3061045Y616998D01*
X3061918Y617873D01*
X3063228Y618164D01*
X3064538Y617873D01*
X3065848Y616998D01*
G01X3098228Y623998D02*
Y606498D01*
G01X3095171Y618164D02*
X3101285D01*
G01X3112016Y606498D02*
Y623998D01*
G01Y615540D02*
X3113108Y616998D01*
X3114200Y617873D01*
X3115946Y618164D01*
X3117256Y617873D01*
X3118785Y616706D01*
X3119440Y614956D01*
Y606498D01*
G01X3137158D02*
Y618164D01*
G01Y616123D02*
X3136285Y617289D01*
X3134974Y617873D01*
X3133446Y618164D01*
X3131918Y617581D01*
X3130608Y616415D01*
X3129734Y614665D01*
X3129298Y612331D01*
X3129734Y609998D01*
X3130608Y608248D01*
X3131918Y607081D01*
X3133446Y606498D01*
X3134974Y606790D01*
X3136285Y607664D01*
X3137158Y608831D01*
G01X3150728Y623998D02*
Y606498D01*
G01X3147671Y618164D02*
X3153785D01*
G01X3179178Y623998D02*
X3182234Y606498D01*
X3185728Y623998D01*
X3189221Y606498D01*
X3192278Y623998D01*
G01X3200608D02*
X3205848D01*
G01X3203228D02*
Y606498D01*
G01X3200608D02*
X3205848D01*
G01X3215925D02*
Y623998D01*
X3220291D01*
X3222038Y623123D01*
X3223348Y621956D01*
X3224440Y620207D01*
X3225313Y618164D01*
X3225531Y615248D01*
X3225313Y612331D01*
X3224440Y610289D01*
X3223348Y608539D01*
X3222038Y607373D01*
X3220291Y606498D01*
X3215925D01*
G01X3238228Y623998D02*
Y606498D01*
G01X3233206Y623998D02*
X3243250D01*
G01X3251143Y606498D02*
Y623998D01*
G01X3260313D02*
Y606498D01*
G01Y615248D02*
X3251143D01*
G01X-7874Y-31496D02*
X-19685D01*
G01X-7874D02*
X-19685D01*
G01D02*
G03X-23622Y-35433I0J-3937D01*
G01D02*
Y-59055D01*
G01Y-35433D02*
Y-59055D01*
G01X-19685Y-31496D02*
G03X-23622Y-35433I0J-3937D01*
G01Y-59055D02*
G03X-19685Y-62992I3937J0D01*
G01D02*
X1972441D01*
G01X-19685D02*
X1972441D01*
G01X-23622Y-59055D02*
G03X-19685Y-62992I3937J0D01*
G01Y-23622D02*
X1972441D01*
G01X-19685D02*
X1972441D01*
G01X-19685D02*
X1972441D01*
G01X-19685D02*
X1972441D01*
G01X-23622Y622441D02*
Y-19685D01*
G01Y622441D02*
Y-19685D01*
G01Y622441D02*
Y-19685D01*
G01Y622441D02*
Y-19685D01*
G01D02*
G03X-19685Y-23622I3937J0D01*
G01X-23622Y-19685D02*
G03X-19685Y-23622I3937J0D01*
G01X-23622Y-19685D02*
G03X-19685Y-23622I3937J0D01*
G01X-23622Y-19685D02*
G03X-19685Y-23622I3937J0D01*
G01X1972441Y626378D02*
X-19685D01*
G01X1972441D02*
X-19685D01*
G01X1972441D02*
X-19685D01*
G01X1972441D02*
X-19685D01*
G01D02*
G03X-23622Y622441I0J-3937D01*
G01X-19685Y626378D02*
G03X-23622Y622441I0J-3937D01*
G01X-19685Y626378D02*
G03X-23622Y622441I0J-3937D01*
G01X-19685Y626378D02*
G03X-23622Y622441I0J-3937D01*
G01X-19685Y634252D02*
X-7874D01*
G01X-19685D02*
X-7874D01*
G01X-23622Y661811D02*
Y638189D01*
G01Y661811D02*
Y638189D01*
G01D02*
G03X-19685Y634252I3937J0D01*
G01X-23622Y638189D02*
G03X-19685Y634252I3937J0D01*
G01X1972441Y665748D02*
X-19685D01*
G01X1972441D02*
X-19685D01*
G01D02*
G03X-23622Y661811I0J-3937D01*
G01X-19685Y665748D02*
G03X-23622Y661811I0J-3937D01*
G01X-7874Y-31496D02*
G03Y-23622I0J3937D01*
G01Y-31496D02*
G03Y-23622I0J3937D01*
G01X22835D02*
G03Y-31496I0J-3937D01*
G01X137795D02*
X22835D01*
G01X137795D02*
X22835D01*
G01Y-23622D02*
G03Y-31496I0J-3937D01*
G01X0Y616535D02*
G03Y604724I0J-5905D01*
G01Y616535D02*
G03Y604724I0J-5905D01*
G01Y616535D02*
X2646D01*
G01X2644D02*
X0D01*
G01Y604724D02*
X2644D01*
G01X2646D02*
X0D01*
G01X2646D02*
X0D01*
G01D02*
X2644D01*
G01Y616535D02*
X0D01*
G01D02*
X2646D01*
G01X0D02*
G03Y604724I0J-5905D01*
G01Y616535D02*
G03Y604724I0J-5905D01*
G01X2646Y616535D02*
G03X7595Y618285I0J7874D01*
G01X2644Y616535D02*
G03X7593Y618285I0J7874D01*
G01X2644Y616535D02*
G03X7593Y618285I0J7874D01*
G01X7595Y602975D02*
G03X2646Y604724I-4948J-6125D01*
G01X7593Y602975D02*
G03X2644Y604724I-4948J-6125D01*
G01X7593Y602975D02*
G03X2644Y604724I-4948J-6125D01*
G01X7593Y602975D02*
G03X2644Y604724I-4948J-6125D01*
G01X7593Y602975D02*
G03X2644Y604724I-4948J-6125D01*
G01X7595Y602975D02*
G03X2646Y604724I-4948J-6125D01*
G01X2644Y616535D02*
G03X7593Y618285I0J7874D01*
G01X2644Y616535D02*
G03X7593Y618285I0J7874D01*
G01X2646Y616535D02*
G03X7595Y618285I0J7874D01*
G01Y602975D02*
G03Y618285I6186J7655D01*
G01X7593Y602975D02*
G03Y618285I6187J7655D01*
G01Y602975D02*
G03Y618285I6187J7655D01*
G01Y602975D02*
G03Y618285I6187J7655D01*
G01Y602975D02*
G03Y618285I6187J7655D01*
G01X7595Y602975D02*
G03Y618285I6186J7655D01*
G01X-7874Y626378D02*
G03Y634252I0J3937D01*
G01Y626378D02*
G03Y634252I0J3937D01*
G01X22835D02*
G03Y626378I0J-3937D01*
G01Y634252D02*
X137795D01*
G01X22835D02*
X137795D01*
G01X22835D02*
G03Y626378I0J-3937D01*
G01X168504Y-23622D02*
G03Y-31496I0J-3937D01*
G01X137795D02*
G03Y-23622I0J3937D01*
G01X341732Y-31496D02*
X168504D01*
G01X341732D02*
X168504D01*
G01X137795D02*
G03Y-23622I0J3937D01*
G01X168504D02*
G03Y-31496I0J-3937D01*
G01Y634252D02*
G03Y626378I0J-3937D01*
G01X137795D02*
G03Y634252I0J3937D01*
G01X168504D02*
X341732D01*
G01X168504D02*
X341732D01*
G01X137795Y626378D02*
G03Y634252I0J3937D01*
G01X168504D02*
G03Y626378I0J-3937D01*
G01X341732Y-31496D02*
G03Y-23622I0J3937D01*
G01Y-31496D02*
G03Y-23622I0J3937D01*
G01Y626378D02*
G03Y634252I0J3937D01*
G01Y626378D02*
G03Y634252I0J3937D01*
G01X372441Y-23622D02*
G03Y-31496I0J-3937D01*
G01X529921D02*
X372441D01*
G01X529921D02*
X372441D01*
G01Y-23622D02*
G03Y-31496I0J-3937D01*
G01Y634252D02*
G03Y626378I0J-3937D01*
G01Y634252D02*
X529921D01*
G01X372441D02*
X529921D01*
G01X372441D02*
G03Y626378I0J-3937D01*
G01X529921Y-31496D02*
G03Y-23622I0J3937D01*
G01Y-31496D02*
G03Y-23622I0J3937D01*
G01Y626378D02*
G03Y634252I0J3937D01*
G01Y626378D02*
G03Y634252I0J3937D01*
G01X560630Y-23622D02*
G03Y-31496I0J-3937D01*
G01X788976D02*
X560630D01*
G01X788976D02*
X560630D01*
G01Y-23622D02*
G03Y-31496I0J-3937D01*
G01Y634252D02*
G03Y626378I0J-3937D01*
G01Y634252D02*
X788976D01*
G01X560630D02*
X788976D01*
G01X560630D02*
G03Y626378I0J-3937D01*
G01X684760Y-15529D02*
G03Y-219I6187J7655D01*
G01X684759Y-15529D02*
G03X679809Y-13780I-4948J-6125D01*
G01X679811Y-1969D02*
G03X684760Y-219I0J7874D01*
G01X677165Y-1969D02*
X679811D01*
G01X677165D02*
G03Y-13780I0J-5906D01*
G01D02*
X679809D01*
G01X684760Y602975D02*
G03Y618285I6187J7655D01*
G01X684759Y602975D02*
G03Y618285I6186J7655D01*
G01Y602975D02*
G03Y618285I6186J7655D01*
G01Y602975D02*
G03Y618285I6186J7655D01*
G01Y602975D02*
G03Y618285I6186J7655D01*
G01X684760Y602975D02*
G03Y618285I6187J7655D01*
G01X679811Y616535D02*
G03X684760Y618285I0J7874D01*
G01X679809Y616535D02*
G03X684759Y618285I0J7874D01*
G01X679809Y616535D02*
G03X684759Y618285I0J7874D01*
G01X684760Y602975D02*
G03X679811Y604724I-4948J-6125D01*
G01X684759Y602975D02*
G03X679809Y604724I-4948J-6125D01*
G01X684759Y602975D02*
G03X679809Y604724I-4948J-6125D01*
G01X684759Y602975D02*
G03X679809Y604724I-4948J-6125D01*
G01X684759Y602975D02*
G03X679809Y604724I-4948J-6125D01*
G01X684760Y602975D02*
G03X679811Y604724I-4948J-6125D01*
G01X679809Y616535D02*
G03X684759Y618285I0J7874D01*
G01X679809Y616535D02*
G03X684759Y618285I0J7874D01*
G01X679811Y616535D02*
G03X684760Y618285I0J7874D01*
G01X677165Y616535D02*
X679811D01*
G01X677165D02*
G03Y604724I0J-5905D01*
G01D02*
X679809D01*
G01X788976Y-31496D02*
G03Y-23622I0J3937D01*
G01Y-31496D02*
G03Y-23622I0J3937D01*
G01X819685D02*
G03Y-31496I0J-3937D01*
G01X975591D02*
X819685D01*
G01X975591D02*
X819685D01*
G01Y-23622D02*
G03Y-31496I0J-3937D01*
G01X788976Y626378D02*
G03Y634252I0J3937D01*
G01Y626378D02*
G03Y634252I0J3937D01*
G01X819685D02*
G03Y626378I0J-3937D01*
G01Y634252D02*
X975591D01*
G01X819685D02*
X975591D01*
G01X819685D02*
G03Y626378I0J-3937D01*
G01X975591Y-31496D02*
G03Y-23622I0J3937D01*
G01Y-31496D02*
G03Y-23622I0J3937D01*
G01X1006299D02*
G03Y-31496I0J-3937D01*
G01X1162205D02*
X1006299D01*
G01X1162205D02*
X1006299D01*
G01Y-23622D02*
G03Y-31496I0J-3937D01*
G01Y634252D02*
X1162205D01*
G01X1006299D02*
X1162205D01*
G01X975591Y626378D02*
G03Y634252I0J3937D01*
G01Y626378D02*
G03Y634252I0J3937D01*
G01X1006299D02*
G03Y626378I0J-3937D01*
G01Y634252D02*
G03Y626378I0J-3937D01*
G01X1162205Y-31496D02*
G03Y-23622I0J3937D01*
G01Y-31496D02*
G03Y-23622I0J3937D01*
G01X1192913D02*
G03Y-31496I0J-3937D01*
G01X1398425D02*
X1192913D01*
G01X1398425D02*
X1192913D01*
G01Y-23622D02*
G03Y-31496I0J-3937D01*
G01Y634252D02*
X1394488D01*
G01X1192913D02*
X1394488D01*
G01X1162205Y626378D02*
G03Y634252I0J3937D01*
G01Y626378D02*
G03Y634252I0J3937D01*
G01X1192913D02*
G03Y626378I0J-3937D01*
G01Y634252D02*
G03Y626378I0J-3937D01*
G01X1398425Y-31496D02*
G03Y-23622I0J3937D01*
G01Y-31496D02*
G03Y-23622I0J3937D01*
G01X1405512Y-1968D02*
G03Y-13779I0J-5906D01*
G01Y-1968D02*
G03Y-13779I0J-5906D01*
G01Y-1968D02*
G03Y-13779I0J-5906D01*
G01Y-1968D02*
G03Y-13779I0J-5906D01*
G01X1394488Y626378D02*
G03Y634252I0J3937D01*
G01Y626378D02*
G03Y634252I0J3937D01*
G01X1405512Y616535D02*
G03Y604724I0J-5905D01*
G01Y616535D02*
G03Y604724I0J-5905D01*
G01Y616535D02*
G03Y604724I0J-5905D01*
G01Y616535D02*
G03Y604724I0J-5905D01*
G01X1429134Y-23622D02*
G03Y-31496I0J-3937D01*
G01X1851181D02*
X1429134D01*
G01X1851181D02*
X1429134D01*
G01Y-23622D02*
G03Y-31496I0J-3937D01*
G01X1413107Y-15529D02*
G03Y-218I6186J7655D01*
G01X1413105Y-15529D02*
G03Y-218I6186J7655D01*
G01Y-15529D02*
G03Y-218I6186J7655D01*
G01Y-15529D02*
G03Y-218I6186J7655D01*
G01Y-15529D02*
G03Y-218I6186J7655D01*
G01X1413107Y-15529D02*
G03Y-218I6186J7655D01*
G01X1408157Y-1968D02*
G03X1413107Y-218I1J7874D01*
G01X1408156Y-1968D02*
G03X1413105Y-218I0J7874D01*
G01X1408156Y-1968D02*
G03X1413105Y-218I0J7874D01*
G01X1408156Y-1968D02*
G03X1413105Y-218I0J7874D01*
G01X1408156Y-1968D02*
G03X1413105Y-218I0J7874D01*
G01X1408157Y-1968D02*
G03X1413107Y-218I1J7874D01*
G01Y-15529D02*
G03X1408157Y-13779I-4949J-6124D01*
G01X1413105Y-15529D02*
G03X1408156Y-13779I-4949J-6124D01*
G01X1413105Y-15529D02*
G03X1408156Y-13779I-4949J-6124D01*
G01X1413105Y-15529D02*
G03X1408156Y-13779I-4949J-6124D01*
G01X1413105Y-15529D02*
G03X1408156Y-13779I-4949J-6124D01*
G01X1413107Y-15529D02*
G03X1408157Y-13779I-4949J-6124D01*
G01X1405512D02*
X1408156D01*
G01X1408157D02*
X1405512D01*
G01X1408157D02*
X1405512D01*
G01D02*
X1408156D01*
G01X1405512Y-1968D02*
X1408157D01*
G01X1408156D02*
X1405512D01*
G01X1408156D02*
X1405512D01*
G01D02*
X1408157D01*
G01X1425197Y634252D02*
X1851181D01*
G01X1425197D02*
X1851181D01*
G01X1425197D02*
G03Y626378I0J-3937D01*
G01Y634252D02*
G03Y626378I0J-3937D01*
G01X1408157Y616535D02*
G03X1413107Y618285I1J7874D01*
G01X1408156Y616535D02*
G03X1413105Y618285I0J7874D01*
G01X1408156Y616535D02*
G03X1413105Y618285I0J7874D01*
G01X1413107Y602975D02*
G03Y618285I6186J7655D01*
G01X1413105Y602975D02*
G03Y618285I6187J7655D01*
G01Y602975D02*
G03Y618285I6187J7655D01*
G01X1413107Y602975D02*
G03X1408157Y604724I-4948J-6125D01*
G01X1413105Y602975D02*
G03X1408156Y604724I-4948J-6125D01*
G01X1413105Y602975D02*
G03X1408156Y604724I-4948J-6125D01*
G01X1413105Y602975D02*
G03X1408156Y604724I-4948J-6125D01*
G01X1413105Y602975D02*
G03X1408156Y604724I-4948J-6125D01*
G01X1413107Y602975D02*
G03X1408157Y604724I-4948J-6125D01*
G01X1413105Y602975D02*
G03Y618285I6187J7655D01*
G01Y602975D02*
G03Y618285I6187J7655D01*
G01X1413107Y602975D02*
G03Y618285I6186J7655D01*
G01X1408156Y616535D02*
G03X1413105Y618285I0J7874D01*
G01X1408156Y616535D02*
G03X1413105Y618285I0J7874D01*
G01X1408157Y616535D02*
G03X1413107Y618285I1J7874D01*
G01X1405512Y616535D02*
X1408157D01*
G01X1408156D02*
X1405512D01*
G01Y604724D02*
X1408156D01*
G01X1408157D02*
X1405512D01*
G01X1408157D02*
X1405512D01*
G01D02*
X1408156D01*
G01Y616535D02*
X1405512D01*
G01D02*
X1408157D01*
G01X1685866Y267244D02*
X1883780D01*
G01X1685866D02*
X1883780D01*
G01X1685866D02*
X1883780D01*
G01X1685866D02*
X1883780D01*
G01X1681929Y271181D02*
G03X1685866Y267244I3937J0D01*
G01X1681929Y271181D02*
G03X1685866Y267244I3937J0D01*
G01X1681929Y271181D02*
G03X1685866Y267244I3937J0D01*
G01X1681929Y271181D02*
G03X1685866Y267244I3937J0D01*
G01X1681929Y428661D02*
Y271181D01*
G01Y428661D02*
Y271181D01*
G01Y428661D02*
Y271181D01*
G01Y428661D02*
Y271181D01*
G01X1685866Y432598D02*
G03X1681929Y428661I0J-3937D01*
G01X1685866Y432598D02*
G03X1681929Y428661I0J-3937D01*
G01X1972441Y432598D02*
X1685866D01*
G01X1972441D02*
X1685866D01*
G01X1972441D02*
X1685866D01*
G01X1972441D02*
X1685866D01*
G01D02*
G03X1681929Y428661I0J-3937D01*
G01X1685866Y432598D02*
G03X1681929Y428661I0J-3937D01*
G01X1851181Y-31496D02*
G03Y-23622I0J3937D01*
G01Y-31496D02*
G03Y-23622I0J3937D01*
G01X1881890D02*
G03Y-31496I0J-3937D01*
G01X1972441D02*
X1881890D01*
G01X1972441D02*
X1881890D01*
G01Y-23622D02*
G03Y-31496I0J-3937D01*
G01X1861926Y-15529D02*
G03X1856976Y-13780I-4948J-6125D01*
G01X1861924Y-15529D02*
G03X1856975Y-13780I-4948J-6125D01*
G01X1861924Y-15529D02*
G03X1856975Y-13780I-4948J-6125D01*
G01X1861924Y-15529D02*
G03X1856975Y-13780I-4948J-6125D01*
G01X1861924Y-15529D02*
G03X1856975Y-13780I-4948J-6125D01*
G01X1861926Y-15529D02*
G03X1856976Y-13780I-4948J-6125D01*
G01Y-1969D02*
G03X1861926Y-219I0J7874D01*
G01X1856975Y-1969D02*
G03X1861924Y-219I0J7874D01*
G01X1856975Y-1969D02*
G03X1861924Y-219I0J7874D01*
G01X1861926Y-15529D02*
G03Y-219I6186J7655D01*
G01X1861924Y-15529D02*
G03Y-219I6186J7655D01*
G01Y-15529D02*
G03Y-219I6186J7655D01*
G01Y-15529D02*
G03Y-219I6186J7655D01*
G01Y-15529D02*
G03Y-219I6186J7655D01*
G01X1861926Y-15529D02*
G03Y-219I6186J7655D01*
G01X1856975Y-1969D02*
G03X1861924Y-219I0J7874D01*
G01X1856975Y-1969D02*
G03X1861924Y-219I0J7874D01*
G01X1856976Y-1969D02*
G03X1861926Y-219I0J7874D01*
G01X1854331Y-1969D02*
G03Y-13780I0J-5906D01*
G01Y-1969D02*
G03Y-13780I0J-5906D01*
G01D02*
X1856975D01*
G01X1856976D02*
X1854331D01*
G01X1856976D02*
X1854331D01*
G01D02*
X1856975D01*
G01X1854331Y-1969D02*
G03Y-13780I0J-5906D01*
G01Y-1969D02*
G03Y-13780I0J-5906D01*
G01Y-1969D02*
X1856976D01*
G01X1856975D02*
X1854331D01*
G01X1856975D02*
X1854331D01*
G01D02*
X1856976D01*
G01X1891654Y246772D02*
X1972441D01*
G01X1891654D02*
X1972441D01*
G01X1891654D02*
X1972441D01*
G01X1891654D02*
X1972441D01*
G01X1887717Y250709D02*
G03X1891654Y246772I3937J0D01*
G01X1887717Y250709D02*
G03X1891654Y246772I3937J0D01*
G01X1887717Y263307D02*
Y250709D01*
G01Y263307D02*
Y250709D01*
G01Y263307D02*
Y250709D01*
G01Y263307D02*
Y250709D01*
G01D02*
G03X1891654Y246772I3937J0D01*
G01X1887717Y250709D02*
G03X1891654Y246772I3937J0D01*
G01X1887717Y263307D02*
G03X1883780Y267244I-3937J0D01*
G01X1887717Y263307D02*
G03X1883780Y267244I-3937J0D01*
G01X1887717Y263307D02*
G03X1883780Y267244I-3937J0D01*
G01X1887717Y263307D02*
G03X1883780Y267244I-3937J0D01*
G01X1881890Y634252D02*
G03Y626378I0J-3937D01*
G01Y634252D02*
X1972441D01*
G01X1881890D02*
X1972441D01*
G01X1881890D02*
G03Y626378I0J-3937D01*
G01X1851181D02*
G03Y634252I0J3937D01*
G01Y626378D02*
G03Y634252I0J3937D01*
G01X1856976Y616535D02*
G03X1861926Y618285I0J7874D01*
G01X1856975Y616535D02*
G03X1861924Y618285I0J7874D01*
G01X1856975Y616535D02*
G03X1861924Y618285I0J7874D01*
G01X1861926Y602975D02*
G03Y618285I6186J7655D01*
G01X1861924Y602975D02*
G03Y618285I6186J7655D01*
G01Y602975D02*
G03Y618285I6186J7655D01*
G01Y602975D02*
G03Y618285I6186J7655D01*
G01Y602975D02*
G03Y618285I6186J7655D01*
G01X1861926Y602975D02*
G03Y618285I6186J7655D01*
G01X1856975Y616535D02*
G03X1861924Y618285I0J7874D01*
G01X1856975Y616535D02*
G03X1861924Y618285I0J7874D01*
G01X1856976Y616535D02*
G03X1861926Y618285I0J7874D01*
G01Y602975D02*
G03X1856976Y604724I-4948J-6125D01*
G01X1861924Y602975D02*
G03X1856975Y604724I-4948J-6125D01*
G01X1861924Y602975D02*
G03X1856975Y604724I-4948J-6125D01*
G01X1861924Y602975D02*
G03X1856975Y604724I-4948J-6125D01*
G01X1861924Y602975D02*
G03X1856975Y604724I-4948J-6125D01*
G01X1861926Y602975D02*
G03X1856976Y604724I-4948J-6125D01*
G01X1854331Y616535D02*
G03Y604724I0J-5905D01*
G01Y616535D02*
G03Y604724I0J-5905D01*
G01D02*
X1856975D01*
G01X1856976D02*
X1854331D01*
G01X1856976D02*
X1854331D01*
G01D02*
X1856975D01*
G01X1854331Y616535D02*
G03Y604724I0J-5905D01*
G01Y616535D02*
G03Y604724I0J-5905D01*
G01Y616535D02*
X1856976D01*
G01X1856975D02*
X1854331D01*
G01X1856975D02*
X1854331D01*
G01D02*
X1856976D01*
G01X1972441Y-11811D02*
X1906890D01*
G01X1904921Y-9843D02*
G03X1906890Y-11811I1969J1D01*
G01X1904921Y53150D02*
Y-9843D01*
G01X1972441Y-11811D02*
X1906890D01*
G01X1904921Y-9843D02*
G03X1906890Y-11811I1969J1D01*
G01X1904921Y53150D02*
Y-9843D01*
G01X1923071Y53150D02*
Y-9843D01*
G01X1940787Y-3937D02*
X1972441D01*
G01X1940787D02*
G03X1938819Y-5906I0J-1968D01*
G01Y-9843D02*
Y-5906D01*
G01Y-9843D02*
G03X1940787Y-11811I1968J0D01*
G01X1921102D02*
G03X1923071Y-9843I0J1969D01*
G01X1906890Y55118D02*
G03X1904921Y53150I0J-1969D01*
G01X1972441Y55118D02*
X1906890D01*
G01X1972441D02*
X1906890D01*
G01X1972441D02*
X1906890D01*
G01X1972441D02*
X1906890D01*
G01D02*
G03X1904921Y53150I0J-1969D01*
G01X1923071D02*
G03X1921102Y55118I-1969J-1D01*
G01X1940787D02*
G03X1938819Y53150I0J-1968D01*
G01Y49213D02*
Y53150D01*
G01Y49213D02*
G03X1940787Y47244I1968J-1D01*
G01X1972441D02*
X1940787D01*
G01X1976378Y-35433D02*
G03X1972441Y-31496I-3937J0D01*
G01X1976378Y-59055D02*
Y-35433D01*
G01Y-59055D02*
Y-35433D01*
G01D02*
G03X1972441Y-31496I-3937J0D01*
G01Y-62992D02*
G03X1976378Y-59055I0J3937D01*
G01X1972441Y-62992D02*
G03X1976378Y-59055I0J3937D01*
G01X1972441Y-23622D02*
G03X1976378Y-19685I0J3937D01*
G01X1972441Y-23622D02*
G03X1976378Y-19685I0J3937D01*
G01X1972441Y-23622D02*
G03X1976378Y-19685I0J3937D01*
G01X1972441Y-23622D02*
G03X1976378Y-19685I0J3937D01*
G01D02*
Y-15748D01*
G01Y-19685D02*
Y-15748D01*
G01Y-19685D02*
Y-15748D01*
G01Y-19685D02*
Y-15748D01*
G01D02*
G03X1972441Y-11811I-3937J0D01*
G01X1976378Y-15748D02*
G03X1972441Y-11811I-3937J0D01*
G01X1976378Y-15748D02*
G03X1972441Y-11811I-3937J0D01*
G01X1976378Y-15748D02*
G03X1972441Y-11811I-3937J0D01*
G01X1976378Y0D02*
Y43307D01*
G01X1972441Y-3937D02*
G03X1976378Y0I0J3937D01*
G01X1972441Y55118D02*
G03X1976378Y59055I0J3937D01*
G01X1972441Y55118D02*
G03X1976378Y59055I0J3937D01*
G01X1972441Y55118D02*
G03X1976378Y59055I0J3937D01*
G01X1972441Y55118D02*
G03X1976378Y59055I0J3937D01*
G01D02*
Y242835D01*
G01Y59055D02*
Y242835D01*
G01Y59055D02*
Y242835D01*
G01Y59055D02*
Y242835D01*
G01Y43307D02*
G03X1972441Y47244I-3937J0D01*
G01X1976378Y242835D02*
G03X1972441Y246772I-3937J0D01*
G01X1976378Y242835D02*
G03X1972441Y246772I-3937J0D01*
G01X1976378Y242835D02*
G03X1972441Y246772I-3937J0D01*
G01X1976378Y242835D02*
G03X1972441Y246772I-3937J0D01*
G01Y432598D02*
G03X1976378Y436535I0J3937D01*
G01X1972441Y432598D02*
G03X1976378Y436535I0J3937D01*
G01X1972441Y432598D02*
G03X1976378Y436535I0J3937D01*
G01X1972441Y432598D02*
G03X1976378Y436535I0J3937D01*
G01D02*
Y622441D01*
G01Y436535D02*
Y622441D01*
G01Y436535D02*
Y622441D01*
G01Y436535D02*
Y622441D01*
G01D02*
G03X1972441Y626378I-3937J0D01*
G01X1976378Y622441D02*
G03X1972441Y626378I-3937J0D01*
G01X1976378Y622441D02*
G03X1972441Y626378I-3937J0D01*
G01X1976378Y622441D02*
G03X1972441Y626378I-3937J0D01*
G01Y634252D02*
G03X1976378Y638189I0J3937D01*
G01X1972441Y634252D02*
G03X1976378Y638189I0J3937D01*
G01D02*
Y661811D01*
G01Y638189D02*
Y661811D01*
G01D02*
G03X1972441Y665748I-3937J0D01*
G01X1976378Y661811D02*
G03X1972441Y665748I-3937J0D01*
G54D12*
G01X-13731Y369070D02*
X-17449D01*
G01X-14208Y367920D02*
X-17926D01*
G01X-17449Y369070D02*
X-19250Y370871D01*
G01X-17926Y367920D02*
X-20400Y370394D01*
G01X-19250Y370871D02*
Y373101D01*
G01Y375751D02*
Y377101D01*
G01Y379751D02*
Y383309D01*
G01X-20400Y370394D02*
Y383786D01*
G01X-19250Y383309D02*
X-17689Y384870D01*
G01X-20400Y383786D02*
X-18166Y386020D01*
G01X-17689Y384870D02*
X-14835D01*
G01X-18166Y386020D02*
X34643D01*
G01X-14208Y367920D02*
X-17926D01*
G01X-13731Y369070D02*
X-17449D01*
G01X-17926Y367920D02*
X-20400Y370394D01*
G01X-17449Y369070D02*
X-19250Y370871D01*
G01X-20400Y370394D02*
Y383786D01*
G01X-19250Y370871D02*
Y373101D01*
G01X-20400Y370394D02*
Y383786D01*
G01X-19250Y375751D02*
Y377101D01*
G01X-20400Y370394D02*
Y383786D01*
G01X-19250Y379751D02*
Y383309D01*
G01X-20400Y383786D02*
X-18166Y386020D01*
G01X-19250Y383309D02*
X-17689Y384870D01*
G01X-18166Y386020D02*
X34643D01*
G01X-17689Y384870D02*
X-14835D01*
G01X-18166Y386020D02*
X34643D01*
G01X51826Y147400D02*
X44601D01*
G01X51349Y148550D02*
X44124D01*
G01X44601Y147400D02*
X42500Y145299D01*
G01X44124Y148550D02*
X41350Y145776D01*
G01X42500Y145299D02*
Y136193D01*
G01X41350Y145776D02*
Y136670D01*
G01X42500Y136193D02*
X34557Y128250D01*
G01X41350Y136670D02*
X34080Y129400D01*
G01X34557Y128250D02*
X27783D01*
G01X34080Y129400D02*
X28260D01*
G01X27783Y128250D02*
X25016Y131017D01*
G01X28260Y129400D02*
X26166Y131494D01*
G01X25016Y131017D02*
Y132267D01*
G01X26166Y131494D02*
Y132267D01*
G01X51349Y148550D02*
X44124D01*
G01X51826Y147400D02*
X44601D01*
G01X44124Y148550D02*
X41350Y145776D01*
G01X44601Y147400D02*
X42500Y145299D01*
G01X41350Y145776D02*
Y136670D01*
G01X42500Y145299D02*
Y136193D01*
G01X41350Y136670D02*
X34080Y129400D01*
G01X42500Y136193D02*
X34557Y128250D01*
G01X34080Y129400D02*
X28260D01*
G01X34557Y128250D02*
X27783D01*
G01X28260Y129400D02*
X26166Y131494D01*
G01X27783Y128250D02*
X25016Y131017D01*
G01X26166Y131494D02*
Y132267D01*
G01X25016Y131017D02*
Y132267D01*
G01X-12120Y366138D02*
Y367459D01*
G01X-13270Y365860D02*
Y366982D01*
G01X-12120Y367459D02*
X-13731Y369070D01*
G01X-13270Y366982D02*
X-14208Y367920D01*
G01X-12185Y384870D02*
X35120D01*
G01D02*
X38481Y388230D01*
G01X34643Y386020D02*
X37505Y388882D01*
G01X38481Y388230D02*
X43252Y399750D01*
G01X37505Y388882D02*
X42102Y399979D01*
G01X43252Y399750D02*
Y418852D01*
G01X42102Y399979D02*
Y419329D01*
G01X-13270Y365860D02*
Y366982D01*
G01X-12120Y366138D02*
Y367459D01*
G01X-13270Y366982D02*
X-14208Y367920D01*
G01X-12120Y367459D02*
X-13731Y369070D01*
G01X-12185Y384870D02*
X35120D01*
G01X34643Y386020D02*
X37505Y388882D01*
G01X35120Y384870D02*
X38481Y388230D01*
G01X37505Y388882D02*
X42102Y399979D01*
G01X38481Y388230D02*
X43252Y399750D01*
G01X42102Y399979D02*
Y419329D01*
G01X43252Y399750D02*
Y418852D01*
G01X-13533Y396282D02*
Y394234D01*
G01X-12383Y396282D02*
Y394711D01*
G01X-13533Y394234D02*
X-11539Y392240D01*
G01X-12383Y394711D02*
X-11062Y393390D01*
G01X-11539Y392240D02*
X31971D01*
G01X-11062Y393390D02*
X31494D01*
G01X31971Y392240D02*
X40112Y400381D01*
G01X31494Y393390D02*
X32449Y394345D01*
G01X31971Y392240D02*
X40112Y400381D01*
G01X33403Y396218D02*
X34322D01*
G01X31971Y392240D02*
X40112Y400381D01*
G01X34322Y396218D02*
X35277Y397173D01*
G01X31971Y392240D02*
X40112Y400381D01*
G01X36232Y399047D02*
X37151D01*
G01X31971Y392240D02*
X40112Y400381D01*
G01X37151Y399047D02*
X38962Y400858D01*
G01X40112Y400381D02*
Y416338D01*
G01X38962Y400858D02*
Y415861D01*
G01X37350Y402872D02*
Y413516D01*
G01X34592Y400114D02*
X37350Y402872D01*
G01X36200Y403349D02*
X34115Y401264D01*
G01X5560Y400114D02*
X34592D01*
G01X34115Y401264D02*
X5083D01*
G01X4512Y399066D02*
X5560Y400114D01*
G01X5083Y401264D02*
X3362Y399543D01*
G01X4512Y397182D02*
Y399066D01*
G01X3362Y399543D02*
Y397182D01*
G01X-12383Y396282D02*
Y394711D01*
G01X-13533Y396282D02*
Y394234D01*
G01X-12383Y394711D02*
X-11062Y393390D01*
G01X-13533Y394234D02*
X-11539Y392240D01*
G01X-11062Y393390D02*
X31494D01*
G01X-11539Y392240D02*
X31971D01*
G01X31494Y393390D02*
X32449Y394345D01*
G01X33403Y396218D02*
X34322D01*
G01D02*
X35277Y397173D01*
G01X36232Y399047D02*
X37151D01*
G01D02*
X38962Y400858D01*
G01X31971Y392240D02*
X40112Y400381D01*
G01X38962Y400858D02*
Y415861D01*
G01X40112Y400381D02*
Y416338D01*
G01X3362Y399543D02*
Y397182D01*
G01X4512D02*
Y399066D01*
G01X5083Y401264D02*
X3362Y399543D01*
G01X4512Y399066D02*
X5560Y400114D01*
G01X34115Y401264D02*
X5083D01*
G01X5560Y400114D02*
X34592D01*
G01X36200Y403349D02*
X34115Y401264D01*
G01X34592Y400114D02*
X37350Y402872D01*
G01D02*
Y413516D01*
G01X26166Y357812D02*
Y360013D01*
G01X25016Y357812D02*
Y360490D01*
G01X26166Y360013D02*
X26897Y360744D01*
G01X25016Y360490D02*
X26420Y361894D01*
G01X26897Y360744D02*
X31543D01*
G01X26420Y361894D02*
X31066D01*
G01X31543Y360744D02*
X41046Y370246D01*
G01X31066Y361894D02*
X40070Y370898D01*
G01X41046Y370246D02*
X50080Y392049D01*
G01X40070Y370898D02*
X49104Y392701D01*
G01X19898Y367418D02*
Y368364D01*
G01X21048Y365903D02*
Y367887D01*
G01X19898Y368364D02*
X21594Y370060D01*
G01X21048Y367887D02*
X22071Y368910D01*
G01X21594Y370060D02*
X34434D01*
G01X22071Y368910D02*
X26622D01*
G01X21594Y370060D02*
X34434D01*
G01X29272Y368910D02*
X30622D01*
G01X21594Y370060D02*
X34434D01*
G01X33202Y368910D02*
X34911D01*
G01X34434Y370060D02*
X38577Y374204D01*
G01X34911Y368910D02*
X39553Y373552D01*
G01X38577Y374204D02*
X48100Y397198D01*
G01X39553Y373552D02*
X49250Y396969D01*
G01X45095Y399216D02*
Y408732D01*
G01X40335Y387727D02*
X45095Y399216D01*
G01X46245Y398987D02*
X42843Y390774D01*
G01X40335Y387727D02*
X45095Y399216D01*
G01X41829Y388326D02*
X41312Y387079D01*
G01X29939Y377231D02*
X40335Y387727D01*
G01X41312Y387079D02*
X38864Y384607D01*
G01X29939Y377231D02*
X40335Y387727D01*
G01X36999Y382724D02*
X36049Y381765D01*
G01X29939Y377231D02*
X40335Y387727D01*
G01X34184Y379882D02*
X33234Y378923D01*
G01X29939Y377231D02*
X40335Y387727D01*
G01X31369Y377040D02*
X30419Y376081D01*
G01X26394Y377231D02*
X29939D01*
G01X30419Y376081D02*
X26870Y376080D01*
G01X25090Y375927D02*
X26394Y377231D01*
G01X26870Y376080D02*
X26240Y375450D01*
G01X25090Y374121D02*
Y375927D01*
G01X26240Y375450D02*
Y374290D01*
G01X9631Y356932D02*
Y354008D01*
G01X8481Y356932D02*
Y353531D01*
G01X9631Y354008D02*
X11590Y352049D01*
G01X8481Y353531D02*
X11113Y350899D01*
G01X11590Y352049D02*
X23159D01*
G01X25809D02*
X27159D01*
G01X29809D02*
X31159D01*
G01X33809D02*
X35159D01*
G01X11113Y350899D02*
X35636D01*
G01X35159Y352049D02*
X43521Y360411D01*
G01X35636Y350899D02*
X44671Y359934D01*
G01X43521Y360411D02*
Y362526D01*
G01Y364940D02*
Y369689D01*
G01X44671Y359934D02*
Y369480D01*
G01X43521Y369689D02*
X51628Y391327D01*
G01X44671Y369480D02*
X52618Y390690D01*
G01X25016Y357812D02*
Y360490D01*
G01X26166Y357812D02*
Y360013D01*
G01X25016Y360490D02*
X26420Y361894D01*
G01X26166Y360013D02*
X26897Y360744D01*
G01X26420Y361894D02*
X31066D01*
G01X26897Y360744D02*
X31543D01*
G01X31066Y361894D02*
X40070Y370898D01*
G01X31543Y360744D02*
X41046Y370246D01*
G01X40070Y370898D02*
X49104Y392701D01*
G01X41046Y370246D02*
X50080Y392049D01*
G01X21048Y365903D02*
Y367887D01*
G01X19898Y367418D02*
Y368364D01*
G01X21048Y367887D02*
X22071Y368910D01*
G01X19898Y368364D02*
X21594Y370060D01*
G01X22071Y368910D02*
X26622D01*
G01X29272D02*
X30622D01*
G01X33202D02*
X34911D01*
G01X21594Y370060D02*
X34434D01*
G01X34911Y368910D02*
X39553Y373552D01*
G01X34434Y370060D02*
X38577Y374204D01*
G01X39553Y373552D02*
X49250Y396969D01*
G01X38577Y374204D02*
X48100Y397198D01*
G01X26240Y375450D02*
Y374290D01*
G01X25090Y374121D02*
Y375927D01*
G01X26870Y376080D02*
X26240Y375450D01*
G01X25090Y375927D02*
X26394Y377231D01*
G01X30419Y376081D02*
X26870Y376080D01*
G01X26394Y377231D02*
X29939D01*
G01X41312Y387079D02*
X38864Y384607D01*
G01X36999Y382724D02*
X36049Y381765D01*
G01X34184Y379882D02*
X33234Y378923D01*
G01X31369Y377040D02*
X30419Y376081D01*
G01X29939Y377231D02*
X40335Y387727D01*
G01X46245Y398987D02*
X42843Y390774D01*
G01X41829Y388326D02*
X41312Y387079D01*
G01X40335Y387727D02*
X45095Y399216D01*
G01D02*
Y408732D01*
G01X8481Y356932D02*
Y353531D01*
G01X9631Y356932D02*
Y354008D01*
G01X8481Y353531D02*
X11113Y350899D01*
G01X9631Y354008D02*
X11590Y352049D01*
G01X11113Y350899D02*
X35636D01*
G01X11590Y352049D02*
X23159D01*
G01X11113Y350899D02*
X35636D01*
G01X25809Y352049D02*
X27159D01*
G01X11113Y350899D02*
X35636D01*
G01X29809Y352049D02*
X31159D01*
G01X11113Y350899D02*
X35636D01*
G01X33809Y352049D02*
X35159D01*
G01X35636Y350899D02*
X44671Y359934D01*
G01X35159Y352049D02*
X43521Y360411D01*
G01X44671Y359934D02*
Y369480D01*
G01X43521Y360411D02*
Y362526D01*
G01X44671Y359934D02*
Y369480D01*
G01X43521Y364940D02*
Y369689D01*
G01X44671Y369480D02*
X52618Y390690D01*
G01X43521Y369689D02*
X51628Y391327D01*
G01X43252Y418852D02*
X45320Y420920D01*
G01X42102Y419329D02*
X44843Y422070D01*
G01X45320Y420920D02*
X48815D01*
G01X44843Y422070D02*
X48815D01*
G01X42102Y419329D02*
X44843Y422070D01*
G01X43252Y418852D02*
X45320Y420920D01*
G01X44843Y422070D02*
X48815D01*
G01X45320Y420920D02*
X48815D01*
G01X39974Y427565D02*
X40348Y427250D01*
G01X39229Y426688D02*
X39924Y426100D01*
G01X40348Y427250D02*
X53722D01*
G01X39924Y426100D02*
X54199D01*
G01X39229Y426688D02*
X39924Y426100D01*
G01X39974Y427565D02*
X40348Y427250D01*
G01X39924Y426100D02*
X54199D01*
G01X40348Y427250D02*
X53722D01*
G01X40112Y416338D02*
X29960Y426490D01*
G01X38962Y415861D02*
X38007Y416816D01*
G01X40112Y416338D02*
X29960Y426490D01*
G01X38007Y416816D02*
X37088D01*
G01X40112Y416338D02*
X29960Y426490D01*
G01X36134Y418689D02*
X35179Y419644D01*
G01X40112Y416338D02*
X29960Y426490D01*
G01X35179Y419644D02*
X34260D01*
G01X40112Y416338D02*
X29960Y426490D01*
G01X33305Y421518D02*
X32350Y422473D01*
G01X40112Y416338D02*
X29960Y426490D01*
G01X32350Y422473D02*
X31431D01*
G01X40112Y416338D02*
X29960Y426490D01*
G01X30477Y424346D02*
X28810Y426013D01*
G01X29960Y426490D02*
Y441030D01*
G01X28810Y426013D02*
Y427363D01*
G01X29960Y426490D02*
Y441030D01*
G01X28810Y430013D02*
Y431363D01*
G01X29960Y426490D02*
Y441030D01*
G01X28810Y434013D02*
Y435363D01*
G01X29960Y426490D02*
Y441030D01*
G01X28810Y438013D02*
Y440553D01*
G01X29960Y441030D02*
X28331Y442659D01*
G01X28810Y440553D02*
X27854Y441509D01*
G01X28331Y442659D02*
X24897D01*
G01X27854Y441509D02*
X24897D01*
G01X13861Y440260D02*
Y441335D01*
G01X12711D02*
Y439783D01*
G01X14541Y439580D02*
X13861Y440260D01*
G01X12711Y439783D02*
X14064Y438430D01*
G01X18397Y439580D02*
X14541D01*
G01X14064Y438430D02*
X17920D01*
G01X20096Y437882D02*
X18397Y439580D01*
G01X17920Y438430D02*
X19120Y437230D01*
G01X25122Y425745D02*
X20096Y437882D01*
G01X19120Y437230D02*
X24146Y425093D01*
G01X37350Y413516D02*
X25122Y425745D01*
G01X24146Y425093D02*
X36200Y413039D01*
G01D02*
Y403349D01*
G01X38962Y415861D02*
X38007Y416816D01*
G01D02*
X37088D01*
G01X36134Y418689D02*
X35179Y419644D01*
G01D02*
X34260D01*
G01X33305Y421518D02*
X32350Y422473D01*
G01D02*
X31431D01*
G01X30477Y424346D02*
X28810Y426013D01*
G01X40112Y416338D02*
X29960Y426490D01*
G01X28810Y426013D02*
Y427363D01*
G01Y430013D02*
Y431363D01*
G01Y434013D02*
Y435363D01*
G01Y438013D02*
Y440553D01*
G01X29960Y426490D02*
Y441030D01*
G01X28810Y440553D02*
X27854Y441509D01*
G01X29960Y441030D02*
X28331Y442659D01*
G01X27854Y441509D02*
X24897D01*
G01X28331Y442659D02*
X24897D01*
G01X36200Y413039D02*
Y403349D01*
G01X24146Y425093D02*
X36200Y413039D01*
G01X37350Y413516D02*
X25122Y425745D01*
G01X19120Y437230D02*
X24146Y425093D01*
G01X25122Y425745D02*
X20096Y437882D01*
G01X17920Y438430D02*
X19120Y437230D01*
G01X20096Y437882D02*
X18397Y439580D01*
G01X14064Y438430D02*
X17920D01*
G01X18397Y439580D02*
X14541D01*
G01X12711Y439783D02*
X14064Y438430D01*
G01X14541Y439580D02*
X13861Y440260D01*
G01X12711Y441335D02*
Y439783D01*
G01X13861Y440260D02*
Y441335D01*
G01X45095Y408732D02*
X50573Y414210D01*
G01X45095Y408732D02*
X50573Y414210D01*
G01X48222Y410232D02*
X46245Y408255D01*
G01X48222Y410232D02*
X46245Y408255D01*
G01X45095Y408732D02*
X50573Y414210D01*
G01X15100Y422711D02*
Y424400D01*
G01X13950D02*
Y422388D01*
G01X16113Y421046D02*
X15100Y422711D01*
G01X13950Y422388D02*
X15360Y420070D01*
G01X29693Y416991D02*
X16113Y421046D01*
G01X15360Y420070D02*
X29085Y415972D01*
G01X32550Y414133D02*
X29693Y416991D01*
G01X29085Y415972D02*
X31400Y413656D01*
G01X32550Y410822D02*
Y414133D01*
G01X31400Y413656D02*
Y411299D01*
G01X29716Y407988D02*
X32550Y410822D01*
G01X31400Y411299D02*
X29239Y409138D01*
G01X-5614Y407988D02*
X29716D01*
G01X29239Y409138D02*
X-6091D01*
G01X-6905Y406697D02*
X-5614Y407988D01*
G01X-6091Y409138D02*
X-8055Y407174D01*
G01X-6905Y405056D02*
Y406697D01*
G01X-8055Y407174D02*
Y405056D01*
G01X5100Y420280D02*
Y424400D01*
G01X3950D02*
Y420757D01*
G01X4512Y419692D02*
X5100Y420280D01*
G01X3950Y420757D02*
X3362Y420169D01*
G01X4512Y412930D02*
Y419692D01*
G01X3362Y420169D02*
Y412930D01*
G01X-8055Y407174D02*
Y405056D01*
G01X-6905D02*
Y406697D01*
G01X-6091Y409138D02*
X-8055Y407174D01*
G01X-6905Y406697D02*
X-5614Y407988D01*
G01X29239Y409138D02*
X-6091D01*
G01X-5614Y407988D02*
X29716D01*
G01X31400Y411299D02*
X29239Y409138D01*
G01X29716Y407988D02*
X32550Y410822D01*
G01X31400Y413656D02*
Y411299D01*
G01X32550Y410822D02*
Y414133D01*
G01X29085Y415972D02*
X31400Y413656D01*
G01X32550Y414133D02*
X29693Y416991D01*
G01X15360Y420070D02*
X29085Y415972D01*
G01X29693Y416991D02*
X16113Y421046D01*
G01X13950Y422388D02*
X15360Y420070D01*
G01X16113Y421046D02*
X15100Y422711D01*
G01X13950Y424400D02*
Y422388D01*
G01X15100Y422711D02*
Y424400D01*
G01X3362Y420169D02*
Y412930D01*
G01X4512D02*
Y419692D01*
G01X3950Y420757D02*
X3362Y420169D01*
G01X4512Y419692D02*
X5100Y420280D01*
G01X3950Y424400D02*
Y420757D01*
G01X5100Y420280D02*
Y424400D01*
G01X69541Y170118D02*
X55419Y155996D01*
G01D02*
Y150993D01*
G01X54269Y156473D02*
Y151470D01*
G01X55419Y150993D02*
X51826Y147400D01*
G01X54269Y151470D02*
X51349Y148550D01*
G01X69541Y170118D02*
X55419Y155996D01*
G01X54269Y156473D02*
Y151470D01*
G01X55419Y155996D02*
Y150993D01*
G01X54269Y151470D02*
X51349Y148550D01*
G01X55419Y150993D02*
X51826Y147400D01*
G01X80594Y220258D02*
X75313Y214977D01*
G01X79444Y220735D02*
X74836Y216127D01*
G01X75313Y214977D02*
X58148D01*
G01X74836Y216127D02*
X57671D01*
G01X58148Y214977D02*
X54975Y211804D01*
G01X57671Y216127D02*
X53825Y212281D01*
G01X54975Y211804D02*
Y197142D01*
G01X53825Y212281D02*
Y196665D01*
G01X54975Y197142D02*
X56124Y195993D01*
G01X53825Y196665D02*
X55647Y194843D01*
G01X56124Y195993D02*
X64955D01*
G01X55647Y194843D02*
X64478D01*
G01X64955Y195993D02*
X69541Y191407D01*
G01X64478Y194843D02*
X68391Y190930D01*
G01X69541Y191407D02*
Y170118D01*
G01X68391Y190930D02*
Y170595D01*
G01D02*
X54269Y156473D01*
G01X79444Y220735D02*
X74836Y216127D01*
G01X80594Y220258D02*
X75313Y214977D01*
G01X74836Y216127D02*
X57671D01*
G01X75313Y214977D02*
X58148D01*
G01X57671Y216127D02*
X53825Y212281D01*
G01X58148Y214977D02*
X54975Y211804D01*
G01X53825Y212281D02*
Y196665D01*
G01X54975Y211804D02*
Y197142D01*
G01X53825Y196665D02*
X55647Y194843D01*
G01X54975Y197142D02*
X56124Y195993D01*
G01X55647Y194843D02*
X64478D01*
G01X56124Y195993D02*
X64955D01*
G01X64478Y194843D02*
X68391Y190930D01*
G01X64955Y195993D02*
X69541Y191407D01*
G01X68391Y190930D02*
Y170595D01*
G01X69541Y191407D02*
Y170118D01*
G01X68391Y170595D02*
X54269Y156473D01*
G01X56500Y308400D02*
Y278585D01*
G01X55350Y307923D02*
Y278108D01*
G01X56500Y278585D02*
X61002Y274083D01*
G01X55350Y278108D02*
X60525Y272933D01*
G01X61002Y274083D02*
X74228D01*
G01X60525Y272933D02*
X73751D01*
G01X74228Y274083D02*
X80594Y267717D01*
G01X73751Y272933D02*
X79444Y267240D01*
G01X80594Y267717D02*
Y220258D01*
G01X79444Y267240D02*
Y220735D01*
G01X55350Y307923D02*
Y278108D01*
G01X56500Y308400D02*
Y278585D01*
G01X55350Y278108D02*
X60525Y272933D01*
G01X56500Y278585D02*
X61002Y274083D01*
G01X60525Y272933D02*
X73751D01*
G01X61002Y274083D02*
X74228D01*
G01X73751Y272933D02*
X79444Y267240D01*
G01X74228Y274083D02*
X80594Y267717D01*
G01X79444Y267240D02*
Y220735D01*
G01X80594Y267717D02*
Y220258D01*
G01X55023Y343373D02*
X52000Y340350D01*
G01X53873Y343850D02*
X50850Y340827D01*
G01X52000Y340350D02*
Y339523D01*
G01X50850Y340827D02*
Y340000D01*
G01X52000Y339523D02*
X51127Y338650D01*
G01X50850Y340000D02*
X49977Y339127D01*
G01X51127Y338650D02*
Y332300D01*
G01X49977Y339127D02*
Y331823D01*
G01X51127Y332300D02*
X53127Y330300D01*
G01X49977Y331823D02*
X52650Y329150D01*
G01X53127Y330300D02*
X54000D01*
G01X52650Y329150D02*
X53523D01*
G01X54000Y330300D02*
X55900Y328400D01*
G01X53523Y329150D02*
X54750Y327923D01*
G01X55900Y328400D02*
Y322400D01*
G01X54750Y327923D02*
Y322877D01*
G01X55900Y322400D02*
X50100Y316600D01*
G01X54750Y322877D02*
X48950Y317077D01*
G01X50100Y316600D02*
Y313600D01*
G01X48950Y317077D02*
Y313123D01*
G01X50100Y313600D02*
X53601Y310099D01*
G01X48950Y313123D02*
X53124Y308949D01*
G01X53601Y310099D02*
X54801D01*
G01D02*
X56500Y308400D01*
G01X53124Y308949D02*
X54324D01*
G01X54801Y310099D02*
X56500Y308400D01*
G01X54324Y308949D02*
X55350Y307923D01*
G01X53873Y343850D02*
X50850Y340827D01*
G01X55023Y343373D02*
X52000Y340350D01*
G01X50850Y340827D02*
Y340000D01*
G01X52000Y340350D02*
Y339523D01*
G01X50850Y340000D02*
X49977Y339127D01*
G01X52000Y339523D02*
X51127Y338650D01*
G01X49977Y339127D02*
Y331823D01*
G01X51127Y338650D02*
Y332300D01*
G01X49977Y331823D02*
X52650Y329150D01*
G01X51127Y332300D02*
X53127Y330300D01*
G01X52650Y329150D02*
X53523D01*
G01X53127Y330300D02*
X54000D01*
G01X53523Y329150D02*
X54750Y327923D01*
G01X54000Y330300D02*
X55900Y328400D01*
G01X54750Y327923D02*
Y322877D01*
G01X55900Y328400D02*
Y322400D01*
G01X54750Y322877D02*
X48950Y317077D01*
G01X55900Y322400D02*
X50100Y316600D01*
G01X48950Y317077D02*
Y313123D01*
G01X50100Y316600D02*
Y313600D01*
G01X48950Y313123D02*
X53124Y308949D01*
G01X50100Y313600D02*
X53601Y310099D01*
G01X53124Y308949D02*
X54324D01*
G01X53601Y310099D02*
X54801D01*
G01X53124Y308949D02*
X54324D01*
G01D02*
X55350Y307923D01*
G01X54801Y310099D02*
X56500Y308400D01*
G01X74100Y422426D02*
Y394464D01*
G01Y422426D02*
Y394464D01*
G01Y422426D02*
Y394464D01*
G01X72950Y413949D02*
Y398941D01*
G01X74100Y422426D02*
Y394464D01*
G01X72950Y396291D02*
Y394941D01*
G01X74100Y394464D02*
X66586Y386950D01*
G01X72950Y394941D02*
X66109Y388100D01*
G01X66586Y386950D02*
X62650D01*
G01X66109Y388100D02*
X62173D01*
G01X62650Y386950D02*
X53675Y377974D01*
G01X62173Y388100D02*
X58355Y384282D01*
G01X62650Y386950D02*
X53675Y377974D01*
G01X56482Y382409D02*
X55527Y381454D01*
G01X62650Y386950D02*
X53675Y377974D01*
G01X53654Y379581D02*
X52699Y378626D01*
G01X53675Y377974D02*
X52022Y373984D01*
G01X52699Y378626D02*
X50872Y374213D01*
G01X52022Y373984D02*
Y363112D01*
G01X50872Y374213D02*
Y372863D01*
G01X52022Y373984D02*
Y363112D01*
G01X50872Y370213D02*
Y368863D01*
G01X52022Y373984D02*
Y363112D01*
G01X50872Y366213D02*
Y362635D01*
G01X52022Y363112D02*
X55023Y360111D01*
G01X50872Y362635D02*
X53873Y359634D01*
G01X55023Y360111D02*
Y343373D01*
G01X53873Y359634D02*
Y343850D01*
G01X72950Y413949D02*
Y398941D01*
G01Y396291D02*
Y394941D01*
G01X74100Y422426D02*
Y394464D01*
G01X72950Y394941D02*
X66109Y388100D01*
G01X74100Y394464D02*
X66586Y386950D01*
G01X66109Y388100D02*
X62173D01*
G01X66586Y386950D02*
X62650D01*
G01X62173Y388100D02*
X58355Y384282D01*
G01X56482Y382409D02*
X55527Y381454D01*
G01X53654Y379581D02*
X52699Y378626D01*
G01X62650Y386950D02*
X53675Y377974D01*
G01X52699Y378626D02*
X50872Y374213D01*
G01X53675Y377974D02*
X52022Y373984D01*
G01X50872Y374213D02*
Y372863D01*
G01Y370213D02*
Y368863D01*
G01Y366213D02*
Y362635D01*
G01X52022Y373984D02*
Y363112D01*
G01X50872Y362635D02*
X53873Y359634D01*
G01X52022Y363112D02*
X55023Y360111D01*
G01X53873Y359634D02*
Y343850D01*
G01X55023Y360111D02*
Y343373D01*
G01X50080Y392049D02*
X54243Y396212D01*
G01X49104Y392701D02*
X53591Y397188D01*
G01X54243Y396212D02*
X61573Y399250D01*
G01X53591Y397188D02*
X61344Y400400D01*
G01X61573Y399250D02*
X68938D01*
G01X61344Y400400D02*
X68461D01*
G01X68938Y399250D02*
X71000Y401312D01*
G01X68461Y400400D02*
X69850Y401789D01*
G01X71000Y401312D02*
Y410426D01*
G01X69850Y401789D02*
Y409949D01*
G01X48100Y397198D02*
Y406851D01*
G01X49250Y396969D02*
Y400310D01*
G01X48100Y397198D02*
Y406851D01*
G01X49250Y402890D02*
Y406374D01*
G01X46245Y408255D02*
Y398987D01*
G01X51628Y391327D02*
X55251Y394950D01*
G01X52618Y390690D02*
X55728Y393800D01*
G01X55251Y394950D02*
X63860D01*
G01X55728Y393800D02*
X63860D01*
G01X49104Y392701D02*
X53591Y397188D01*
G01X50080Y392049D02*
X54243Y396212D01*
G01X53591Y397188D02*
X61344Y400400D01*
G01X54243Y396212D02*
X61573Y399250D01*
G01X61344Y400400D02*
X68461D01*
G01X61573Y399250D02*
X68938D01*
G01X68461Y400400D02*
X69850Y401789D01*
G01X68938Y399250D02*
X71000Y401312D01*
G01X69850Y401789D02*
Y409949D01*
G01X71000Y401312D02*
Y410426D01*
G01X49250Y396969D02*
Y400310D01*
G01Y402890D02*
Y406374D01*
G01X48100Y397198D02*
Y406851D01*
G01X46245Y408255D02*
Y398987D01*
G01X52618Y390690D02*
X55728Y393800D01*
G01X51628Y391327D02*
X55251Y394950D01*
G01X55728Y393800D02*
X63860D01*
G01X55251Y394950D02*
X63860D01*
G01X53722Y427250D02*
X59522Y433050D01*
G01X54199Y426100D02*
X59999Y431900D01*
G01X59522Y433050D02*
X63476D01*
G01X59999Y431900D02*
X62999D01*
G01X63476Y433050D02*
X74100Y422426D01*
G01X62999Y431900D02*
X65425Y429474D01*
G01X63476Y433050D02*
X74100Y422426D01*
G01X66380Y427600D02*
X67299D01*
G01X63476Y433050D02*
X74100Y422426D01*
G01X67299Y427600D02*
X68254Y426645D01*
G01X63476Y433050D02*
X74100Y422426D01*
G01X69208Y424772D02*
X70127D01*
G01X63476Y433050D02*
X74100Y422426D01*
G01X70127Y424772D02*
X72950Y421949D01*
G01D02*
Y420599D01*
G01Y417949D02*
Y416599D01*
G01X54199Y426100D02*
X59999Y431900D01*
G01X53722Y427250D02*
X59522Y433050D01*
G01X59999Y431900D02*
X62999D01*
G01X59522Y433050D02*
X63476D01*
G01X62999Y431900D02*
X65425Y429474D01*
G01X66380Y427600D02*
X67299D01*
G01D02*
X68254Y426645D01*
G01X69208Y424772D02*
X70127D01*
G01D02*
X72950Y421949D01*
G01X63476Y433050D02*
X74100Y422426D01*
G01X72950Y421949D02*
Y420599D01*
G01Y417949D02*
Y416599D01*
G01X71000Y410426D02*
X68199Y413227D01*
G01X66325Y415101D02*
X65370Y416056D01*
G01X63496Y417930D02*
X62541Y418885D01*
G01X60668Y420758D02*
X58800Y422626D01*
G01X69850Y409949D02*
X57650Y422149D01*
G01X58800Y422626D02*
Y424925D01*
G01X57650Y422149D02*
Y425402D01*
G01X58800Y424925D02*
X60105Y426230D01*
G01D02*
X60555D01*
G01X57650Y425402D02*
X59628Y427380D01*
G01X60105Y426230D02*
X60555D01*
G01X59628Y427380D02*
X60555D01*
G01X48100Y406851D02*
X50199Y408950D01*
G01X49250Y406374D02*
X50676Y407800D01*
G01X50199Y408950D02*
X53669D01*
G01X50676Y407800D02*
X53192D01*
G01X53669Y408950D02*
X54456Y408163D01*
G01D02*
X56383D01*
G01X53192Y407800D02*
X54244Y406748D01*
G01X67078Y405931D02*
X65384Y404237D01*
G01X65156Y405636D02*
X65928Y406408D01*
G01X67078Y409490D02*
Y405931D01*
G01X65928Y406408D02*
Y409013D01*
G01X62358Y414210D02*
X67078Y409490D01*
G01X65928Y409013D02*
X64709Y410232D01*
G01X62358Y414210D02*
X67078Y409490D01*
G01X62836Y412105D02*
X61881Y413060D01*
G01X50573Y414210D02*
X62358D01*
G01X61881Y413060D02*
X60531D01*
G01X50573Y414210D02*
X62358D01*
G01X57881Y413060D02*
X55050D01*
G01X50573Y414210D02*
X62358D01*
G01X52400Y413060D02*
X51050D01*
G01D02*
X50095Y412105D01*
G01X69850Y409949D02*
X57650Y422149D01*
G01X71000Y410426D02*
X68199Y413227D01*
G01X69850Y409949D02*
X57650Y422149D01*
G01X66325Y415101D02*
X65370Y416056D01*
G01X69850Y409949D02*
X57650Y422149D01*
G01X63496Y417930D02*
X62541Y418885D01*
G01X69850Y409949D02*
X57650Y422149D01*
G01X60668Y420758D02*
X58800Y422626D01*
G01X57650Y422149D02*
Y425402D01*
G01X58800Y422626D02*
Y424925D01*
G01X57650Y425402D02*
X59628Y427380D01*
G01X58800Y424925D02*
X60105Y426230D01*
G01X57650Y425402D02*
X59628Y427380D01*
G01D02*
X60555D01*
G01X60105Y426230D02*
X60555D01*
G01X49250Y406374D02*
X50676Y407800D01*
G01X48100Y406851D02*
X50199Y408950D01*
G01X50676Y407800D02*
X53192D01*
G01X50199Y408950D02*
X53669D01*
G01X53192Y407800D02*
X54244Y406748D01*
G01X53669Y408950D02*
X54456Y408163D01*
G01X53192Y407800D02*
X54244Y406748D01*
G01X54456Y408163D02*
X56383D01*
G01X51050Y413060D02*
X50095Y412105D01*
G01X61881Y413060D02*
X60531D01*
G01X57881D02*
X55050D01*
G01X52400D02*
X51050D01*
G01X50573Y414210D02*
X62358D01*
G01X65928Y409013D02*
X64709Y410232D01*
G01X62836Y412105D02*
X61881Y413060D01*
G01X62358Y414210D02*
X67078Y409490D01*
G01X65928Y406408D02*
Y409013D01*
G01X67078Y409490D02*
Y405931D01*
G01X65156Y405636D02*
X65928Y406408D01*
G01X67078Y405931D02*
X65384Y404237D01*
G01X479062Y643863D02*
X478153Y645164D01*
G01X476680Y654676D02*
X474990Y645095D01*
G01X477731Y654008D02*
X476040Y644426D01*
G01X474990Y645095D02*
X474470Y644731D01*
G01D02*
X473436Y644913D01*
G01X476040Y644426D02*
X474740Y643515D01*
G01X474470Y644731D02*
X473436Y644913D01*
G01X474740Y643515D02*
X472766Y643862D01*
G01X473436Y644913D02*
X473072Y645434D01*
G01X472766Y643862D02*
X471856Y645165D01*
G01X473072Y645434D02*
X474572Y653945D01*
G01X471856Y645165D02*
X473356Y653674D01*
G01X470385Y654681D02*
X468702Y645129D01*
G01X471435Y654011D02*
X469753Y644459D01*
G01X468702Y645129D02*
X468179Y644764D01*
G01D02*
X467145Y644946D01*
G01X469753Y644459D02*
X468449Y643549D01*
G01X468179Y644764D02*
X467145Y644946D01*
G01X468449Y643549D02*
X466475Y643895D01*
G01X467145Y644946D02*
X466781Y645467D01*
G01X466475Y643895D02*
X465565Y645198D01*
G01X466781Y645467D02*
X468272Y653923D01*
G01X465565Y645198D02*
X467056Y653654D01*
G01X464085Y654662D02*
X462407Y645128D01*
G01X465136Y653992D02*
X463457Y644458D01*
G01X462407Y645128D02*
X461884Y644763D01*
G01D02*
X460849Y644945D01*
G01X463457Y644458D02*
X462153Y643548D01*
G01X461884Y644763D02*
X460849Y644945D01*
G01X462153Y643548D02*
X460179Y643894D01*
G01X460849Y644945D02*
X460485Y645466D01*
G01X460179Y643894D02*
X459269Y645197D01*
G01X460485Y645466D02*
X461977Y653919D01*
G01X459269Y645197D02*
X460761Y653651D01*
G01X457790Y654658D02*
X456106Y645108D01*
G01X458841Y653989D02*
X457156Y644439D01*
G01X456106Y645108D02*
X455587Y644745D01*
G01D02*
X454553Y644928D01*
G01X457156Y644439D02*
X455856Y643529D01*
G01X455587Y644745D02*
X454553Y644928D01*
G01X455856Y643529D02*
X453883Y643878D01*
G01X454553Y644928D02*
X454186Y645452D01*
G01X453883Y643878D02*
X452970Y645182D01*
G01X454186Y645452D02*
X455670Y653858D01*
G01X452970Y645182D02*
X454454Y653589D01*
G01X451954Y651057D02*
X450973Y649749D01*
G01X450273Y650734D02*
X447169Y649747D01*
G01X450973Y649749D02*
X447302Y648582D01*
G01X447169Y649747D02*
X442894Y650089D01*
G01X447302Y648582D02*
X442847Y648939D01*
G01D02*
X441106D01*
G01X479062Y643863D02*
X478153Y645164D01*
G01X477731Y654008D02*
X476040Y644426D01*
G01X476680Y654676D02*
X474990Y645095D01*
G01X476040Y644426D02*
X474740Y643515D01*
G01X474990Y645095D02*
X474470Y644731D01*
G01X476040Y644426D02*
X474740Y643515D01*
G01D02*
X472766Y643862D01*
G01X474470Y644731D02*
X473436Y644913D01*
G01X472766Y643862D02*
X471856Y645165D01*
G01X473436Y644913D02*
X473072Y645434D01*
G01X471856Y645165D02*
X473356Y653674D01*
G01X473072Y645434D02*
X474572Y653945D01*
G01X471435Y654011D02*
X469753Y644459D01*
G01X470385Y654681D02*
X468702Y645129D01*
G01X469753Y644459D02*
X468449Y643549D01*
G01X468702Y645129D02*
X468179Y644764D01*
G01X469753Y644459D02*
X468449Y643549D01*
G01D02*
X466475Y643895D01*
G01X468179Y644764D02*
X467145Y644946D01*
G01X466475Y643895D02*
X465565Y645198D01*
G01X467145Y644946D02*
X466781Y645467D01*
G01X465565Y645198D02*
X467056Y653654D01*
G01X466781Y645467D02*
X468272Y653923D01*
G01X465136Y653992D02*
X463457Y644458D01*
G01X464085Y654662D02*
X462407Y645128D01*
G01X463457Y644458D02*
X462153Y643548D01*
G01X462407Y645128D02*
X461884Y644763D01*
G01X463457Y644458D02*
X462153Y643548D01*
G01D02*
X460179Y643894D01*
G01X461884Y644763D02*
X460849Y644945D01*
G01X460179Y643894D02*
X459269Y645197D01*
G01X460849Y644945D02*
X460485Y645466D01*
G01X459269Y645197D02*
X460761Y653651D01*
G01X460485Y645466D02*
X461977Y653919D01*
G01X458841Y653989D02*
X457156Y644439D01*
G01X457790Y654658D02*
X456106Y645108D01*
G01X457156Y644439D02*
X455856Y643529D01*
G01X456106Y645108D02*
X455587Y644745D01*
G01X457156Y644439D02*
X455856Y643529D01*
G01D02*
X453883Y643878D01*
G01X455587Y644745D02*
X454553Y644928D01*
G01X453883Y643878D02*
X452970Y645182D01*
G01X454553Y644928D02*
X454186Y645452D01*
G01X452970Y645182D02*
X454454Y653589D01*
G01X454186Y645452D02*
X455670Y653858D01*
G01X451954Y651057D02*
X450973Y649749D01*
G01D02*
X447302Y648582D01*
G01X450273Y650734D02*
X447169Y649747D01*
G01X447302Y648582D02*
X442847Y648939D01*
G01X447169Y649747D02*
X442894Y650089D01*
G01X442847Y648939D02*
X441106D01*
G01X479957Y655243D02*
X477983Y655592D01*
G01D02*
X476680Y654676D01*
G01X477983Y655592D02*
X476680Y654676D01*
G01X478254Y654376D02*
X477731Y654008D01*
G01X474572Y653945D02*
X473657Y655245D01*
G01X473356Y653674D02*
X472990Y654194D01*
G01X473657Y655245D02*
X471688Y655590D01*
G01D02*
X470385Y654681D01*
G01X472990Y654194D02*
X471957Y654375D01*
G01X471688Y655590D02*
X470385Y654681D01*
G01X471957Y654375D02*
X471435Y654011D01*
G01X468272Y653923D02*
X467360Y655227D01*
G01X467056Y653654D02*
X466691Y654176D01*
G01X467360Y655227D02*
X465388Y655572D01*
G01D02*
X464085Y654662D01*
G01X466691Y654176D02*
X465658Y654357D01*
G01X465388Y655572D02*
X464085Y654662D01*
G01X465658Y654357D02*
X465136Y653992D01*
G01X461977Y653919D02*
X461068Y655224D01*
G01X460761Y653651D02*
X460397Y654174D01*
G01X461068Y655224D02*
X459094Y655572D01*
G01D02*
X457790Y654658D01*
G01X460397Y654174D02*
X459364Y654356D01*
G01X459094Y655572D02*
X457790Y654658D01*
G01X459364Y654356D02*
X458841Y653989D01*
G01X455670Y653858D02*
X454759Y655162D01*
G01X454454Y653589D02*
X454089Y654111D01*
G01X454759Y655162D02*
X452785Y655509D01*
G01D02*
X451483Y654597D01*
G01X454089Y654111D02*
X453055Y654293D01*
G01X452785Y655509D02*
X451483Y654597D01*
G01X453055Y654293D02*
X452534Y653928D01*
G01X451483Y654597D02*
X451072Y652260D01*
G01X452534Y653928D02*
X452198Y652018D01*
G01X451072Y652260D02*
X450895Y651564D01*
G01X452198Y652018D02*
X451954Y651057D01*
G01X450895Y651564D02*
X450273Y650734D01*
G01X442894Y650089D02*
X441106D01*
G01X479957Y655243D02*
X477983Y655592D01*
G01X478254Y654376D02*
X477731Y654008D01*
G01X477983Y655592D02*
X476680Y654676D01*
G01X473356Y653674D02*
X472990Y654194D01*
G01X474572Y653945D02*
X473657Y655245D01*
G01X472990Y654194D02*
X471957Y654375D01*
G01X473657Y655245D02*
X471688Y655590D01*
G01X472990Y654194D02*
X471957Y654375D01*
G01D02*
X471435Y654011D01*
G01X471688Y655590D02*
X470385Y654681D01*
G01X467056Y653654D02*
X466691Y654176D01*
G01X468272Y653923D02*
X467360Y655227D01*
G01X466691Y654176D02*
X465658Y654357D01*
G01X467360Y655227D02*
X465388Y655572D01*
G01X466691Y654176D02*
X465658Y654357D01*
G01D02*
X465136Y653992D01*
G01X465388Y655572D02*
X464085Y654662D01*
G01X460761Y653651D02*
X460397Y654174D01*
G01X461977Y653919D02*
X461068Y655224D01*
G01X460397Y654174D02*
X459364Y654356D01*
G01X461068Y655224D02*
X459094Y655572D01*
G01X460397Y654174D02*
X459364Y654356D01*
G01D02*
X458841Y653989D01*
G01X459094Y655572D02*
X457790Y654658D01*
G01X454454Y653589D02*
X454089Y654111D01*
G01X455670Y653858D02*
X454759Y655162D01*
G01X454089Y654111D02*
X453055Y654293D01*
G01X454759Y655162D02*
X452785Y655509D01*
G01X454089Y654111D02*
X453055Y654293D01*
G01D02*
X452534Y653928D01*
G01X452785Y655509D02*
X451483Y654597D01*
G01X452534Y653928D02*
X452198Y652018D01*
G01X451483Y654597D02*
X451072Y652260D01*
G01X452198Y652018D02*
X451954Y651057D01*
G01X451072Y652260D02*
X450895Y651564D01*
G01D02*
X450273Y650734D01*
G01X442894Y650089D02*
X441106D01*
G01X539582Y654326D02*
X537891Y644744D01*
G01X540632Y653657D02*
X538942Y644076D01*
G01X537891Y644744D02*
X537368Y644376D01*
G01D02*
X536334Y644559D01*
G01X538942Y644076D02*
X537639Y643160D01*
G01X537368Y644376D02*
X536334Y644559D01*
G01X537639Y643160D02*
X535665Y643509D01*
G01X536334Y644559D02*
X535969Y645080D01*
G01X535665Y643509D02*
X534753Y644810D01*
G01X535969Y645080D02*
X537469Y653588D01*
G01X534753Y644810D02*
X536253Y653317D01*
G01X533284Y654327D02*
X531615Y644857D01*
G01X534334Y653657D02*
X532666Y644188D01*
G01X531615Y644857D02*
X531092Y644490D01*
G01D02*
X530059Y644671D01*
G01X532666Y644188D02*
X531363Y643274D01*
G01X531092Y644490D02*
X530059Y644671D01*
G01X531363Y643274D02*
X529389Y643620D01*
G01X530059Y644671D02*
X529695Y645193D01*
G01X529389Y643620D02*
X528479Y644925D01*
G01X529695Y645193D02*
X531172Y653570D01*
G01X528479Y644925D02*
X529956Y653301D01*
G01X526986Y654309D02*
X525317Y644853D01*
G01X528036Y653639D02*
X526367Y644183D01*
G01X525317Y644853D02*
X524796Y644489D01*
G01D02*
X523764Y644671D01*
G01X526367Y644183D02*
X525065Y643273D01*
G01X524796Y644489D02*
X523764Y644671D01*
G01X525065Y643273D02*
X523094Y643620D01*
G01X523764Y644671D02*
X523399Y645193D01*
G01X523094Y643620D02*
X522183Y644924D01*
G01X523399Y645193D02*
X524877Y653568D01*
G01X522183Y644924D02*
X523661Y653299D01*
G01X520689Y654309D02*
X519022Y644837D01*
G01X521739Y653639D02*
X520073Y644166D01*
G01X519022Y644837D02*
X518498Y644472D01*
G01D02*
X517466Y644652D01*
G01X520073Y644166D02*
X518767Y643257D01*
G01X518498Y644472D02*
X517466Y644652D01*
G01X518767Y643257D02*
X516796Y643601D01*
G01X517466Y644652D02*
X517101Y645176D01*
G01X516796Y643601D02*
X515885Y644908D01*
G01X517101Y645176D02*
X518587Y653601D01*
G01X515885Y644908D02*
X517371Y653332D01*
G01X514399Y654342D02*
X512733Y644885D01*
G01X515449Y653672D02*
X513783Y644216D01*
G01X512733Y644885D02*
X512173Y644493D01*
G01D02*
X511205Y644663D01*
G01X513783Y644216D02*
X512443Y643277D01*
G01X512173Y644493D02*
X511205Y644663D01*
G01X512443Y643277D02*
X510535Y643612D01*
G01X511205Y644663D02*
X510814Y645223D01*
G01X510535Y643612D02*
X509598Y644954D01*
G01X510814Y645223D02*
X512291Y653601D01*
G01X509598Y644954D02*
X511075Y653332D01*
G01X508105Y654341D02*
X506467Y645081D01*
G01X509155Y653671D02*
X507517Y644411D01*
G01X506467Y645081D02*
X505945Y644716D01*
G01D02*
X504911Y644898D01*
G01X507517Y644411D02*
X506214Y643501D01*
G01X505945Y644716D02*
X504911Y644898D01*
G01X506214Y643501D02*
X504241Y643848D01*
G01X504911Y644898D02*
X504547Y645420D01*
G01X504241Y643848D02*
X503331Y645151D01*
G01X504547Y645420D02*
X506024Y653798D01*
G01X503331Y645151D02*
X504808Y653529D01*
G01X501839Y654536D02*
X500173Y645080D01*
G01X502889Y653867D02*
X501223Y644410D01*
G01X500173Y645080D02*
X499651Y644716D01*
G01D02*
X498616Y644898D01*
G01X501223Y644410D02*
X499920Y643501D01*
G01X499651Y644716D02*
X498616Y644898D01*
G01X499920Y643501D02*
X497946Y643847D01*
G01X498616Y644898D02*
X498251Y645420D01*
G01X497946Y643847D02*
X497035Y645151D01*
G01X498251Y645420D02*
X499737Y653844D01*
G01X497035Y645151D02*
X498521Y653576D01*
G01X495549Y654586D02*
X493883Y645113D01*
G01X496600Y653915D02*
X494933Y644443D01*
G01X493883Y645113D02*
X493361Y644749D01*
G01D02*
X492326Y644931D01*
G01X494933Y644443D02*
X493630Y643534D01*
G01X493361Y644749D02*
X492326Y644931D01*
G01X493630Y643534D02*
X491656Y643880D01*
G01X492326Y644931D02*
X491961Y645453D01*
G01X491656Y643880D02*
X490745Y645184D01*
G01X491961Y645453D02*
X493439Y653828D01*
G01X490745Y645184D02*
X492223Y653559D01*
G01X489255Y654569D02*
X487586Y645113D01*
G01X490305Y653899D02*
X488636Y644443D01*
G01X487586Y645113D02*
X487064Y644749D01*
G01D02*
X486030Y644930D01*
G01X488636Y644443D02*
X487333Y643534D01*
G01X487064Y644749D02*
X486030Y644930D01*
G01X487333Y643534D02*
X485360Y643879D01*
G01X486030Y644930D02*
X485666Y645451D01*
G01X485360Y643879D02*
X484450Y645182D01*
G01X485666Y645451D02*
X487143Y653827D01*
G01X484450Y645182D02*
X485927Y653559D01*
G01X482956Y654564D02*
X481288Y645095D01*
G01X484007Y653895D02*
X482338Y644425D01*
G01X481288Y645095D02*
X480766Y644730D01*
G01D02*
X479732Y644913D01*
G01X482338Y644425D02*
X481035Y643515D01*
G01X480766Y644730D02*
X479732Y644913D01*
G01X481035Y643515D02*
X479062Y643863D01*
G01X479732Y644913D02*
X479369Y645435D01*
G01D02*
X480869Y653942D01*
G01X478153Y645164D02*
X479653Y653672D01*
G01X540632Y653657D02*
X538942Y644076D01*
G01X539582Y654326D02*
X537891Y644744D01*
G01X538942Y644076D02*
X537639Y643160D01*
G01X537891Y644744D02*
X537368Y644376D01*
G01X538942Y644076D02*
X537639Y643160D01*
G01D02*
X535665Y643509D01*
G01X537368Y644376D02*
X536334Y644559D01*
G01X535665Y643509D02*
X534753Y644810D01*
G01X536334Y644559D02*
X535969Y645080D01*
G01X534753Y644810D02*
X536253Y653317D01*
G01X535969Y645080D02*
X537469Y653588D01*
G01X534334Y653657D02*
X532666Y644188D01*
G01X533284Y654327D02*
X531615Y644857D01*
G01X532666Y644188D02*
X531363Y643274D01*
G01X531615Y644857D02*
X531092Y644490D01*
G01X532666Y644188D02*
X531363Y643274D01*
G01D02*
X529389Y643620D01*
G01X531092Y644490D02*
X530059Y644671D01*
G01X529389Y643620D02*
X528479Y644925D01*
G01X530059Y644671D02*
X529695Y645193D01*
G01X528479Y644925D02*
X529956Y653301D01*
G01X529695Y645193D02*
X531172Y653570D01*
G01X528036Y653639D02*
X526367Y644183D01*
G01X526986Y654309D02*
X525317Y644853D01*
G01X526367Y644183D02*
X525065Y643273D01*
G01X525317Y644853D02*
X524796Y644489D01*
G01X526367Y644183D02*
X525065Y643273D01*
G01D02*
X523094Y643620D01*
G01X524796Y644489D02*
X523764Y644671D01*
G01X523094Y643620D02*
X522183Y644924D01*
G01X523764Y644671D02*
X523399Y645193D01*
G01X522183Y644924D02*
X523661Y653299D01*
G01X523399Y645193D02*
X524877Y653568D01*
G01X521739Y653639D02*
X520073Y644166D01*
G01X520689Y654309D02*
X519022Y644837D01*
G01X520073Y644166D02*
X518767Y643257D01*
G01X519022Y644837D02*
X518498Y644472D01*
G01X520073Y644166D02*
X518767Y643257D01*
G01D02*
X516796Y643601D01*
G01X518498Y644472D02*
X517466Y644652D01*
G01X516796Y643601D02*
X515885Y644908D01*
G01X517466Y644652D02*
X517101Y645176D01*
G01X515885Y644908D02*
X517371Y653332D01*
G01X517101Y645176D02*
X518587Y653601D01*
G01X515449Y653672D02*
X513783Y644216D01*
G01X514399Y654342D02*
X512733Y644885D01*
G01X513783Y644216D02*
X512443Y643277D01*
G01X512733Y644885D02*
X512173Y644493D01*
G01X513783Y644216D02*
X512443Y643277D01*
G01D02*
X510535Y643612D01*
G01X512173Y644493D02*
X511205Y644663D01*
G01X510535Y643612D02*
X509598Y644954D01*
G01X511205Y644663D02*
X510814Y645223D01*
G01X509598Y644954D02*
X511075Y653332D01*
G01X510814Y645223D02*
X512291Y653601D01*
G01X509155Y653671D02*
X507517Y644411D01*
G01X508105Y654341D02*
X506467Y645081D01*
G01X507517Y644411D02*
X506214Y643501D01*
G01X506467Y645081D02*
X505945Y644716D01*
G01X507517Y644411D02*
X506214Y643501D01*
G01D02*
X504241Y643848D01*
G01X505945Y644716D02*
X504911Y644898D01*
G01X504241Y643848D02*
X503331Y645151D01*
G01X504911Y644898D02*
X504547Y645420D01*
G01X503331Y645151D02*
X504808Y653529D01*
G01X504547Y645420D02*
X506024Y653798D01*
G01X502889Y653867D02*
X501223Y644410D01*
G01X501839Y654536D02*
X500173Y645080D01*
G01X501223Y644410D02*
X499920Y643501D01*
G01X500173Y645080D02*
X499651Y644716D01*
G01X501223Y644410D02*
X499920Y643501D01*
G01D02*
X497946Y643847D01*
G01X499651Y644716D02*
X498616Y644898D01*
G01X497946Y643847D02*
X497035Y645151D01*
G01X498616Y644898D02*
X498251Y645420D01*
G01X497035Y645151D02*
X498521Y653576D01*
G01X498251Y645420D02*
X499737Y653844D01*
G01X496600Y653915D02*
X494933Y644443D01*
G01X495549Y654586D02*
X493883Y645113D01*
G01X494933Y644443D02*
X493630Y643534D01*
G01X493883Y645113D02*
X493361Y644749D01*
G01X494933Y644443D02*
X493630Y643534D01*
G01D02*
X491656Y643880D01*
G01X493361Y644749D02*
X492326Y644931D01*
G01X491656Y643880D02*
X490745Y645184D01*
G01X492326Y644931D02*
X491961Y645453D01*
G01X490745Y645184D02*
X492223Y653559D01*
G01X491961Y645453D02*
X493439Y653828D01*
G01X490305Y653899D02*
X488636Y644443D01*
G01X489255Y654569D02*
X487586Y645113D01*
G01X488636Y644443D02*
X487333Y643534D01*
G01X487586Y645113D02*
X487064Y644749D01*
G01X488636Y644443D02*
X487333Y643534D01*
G01D02*
X485360Y643879D01*
G01X487064Y644749D02*
X486030Y644930D01*
G01X485360Y643879D02*
X484450Y645182D01*
G01X486030Y644930D02*
X485666Y645451D01*
G01X484450Y645182D02*
X485927Y653559D01*
G01X485666Y645451D02*
X487143Y653827D01*
G01X484007Y653895D02*
X482338Y644425D01*
G01X482956Y654564D02*
X481288Y645095D01*
G01X482338Y644425D02*
X481035Y643515D01*
G01X481288Y645095D02*
X480766Y644730D01*
G01X482338Y644425D02*
X481035Y643515D01*
G01D02*
X479062Y643863D01*
G01X480766Y644730D02*
X479732Y644913D01*
G01D02*
X479369Y645435D01*
G01X478153Y645164D02*
X479653Y653672D01*
G01X479369Y645435D02*
X480869Y653942D01*
G01X540882Y655237D02*
X539582Y654326D01*
G01X540882Y655237D02*
X539582Y654326D01*
G01X537469Y653588D02*
X536560Y654889D01*
G01X536253Y653317D02*
X535890Y653839D01*
G01X536560Y654889D02*
X534587Y655237D01*
G01D02*
X533284Y654327D01*
G01X535890Y653839D02*
X534856Y654022D01*
G01X534587Y655237D02*
X533284Y654327D01*
G01X534856Y654022D02*
X534334Y653657D01*
G01X531172Y653570D02*
X530262Y654873D01*
G01X529956Y653301D02*
X529592Y653822D01*
G01X530262Y654873D02*
X528289Y655218D01*
G01D02*
X526986Y654309D01*
G01X529592Y653822D02*
X528558Y654003D01*
G01X528289Y655218D02*
X526986Y654309D01*
G01X528558Y654003D02*
X528036Y653639D01*
G01X524877Y653568D02*
X523966Y654872D01*
G01X523661Y653299D02*
X523296Y653821D01*
G01X523966Y654872D02*
X521992Y655218D01*
G01D02*
X520689Y654309D01*
G01X523296Y653821D02*
X522261Y654003D01*
G01X521992Y655218D02*
X520689Y654309D01*
G01X522261Y654003D02*
X521739Y653639D01*
G01X518587Y653601D02*
X517676Y654905D01*
G01X517371Y653332D02*
X517006Y653854D01*
G01X517676Y654905D02*
X515702Y655251D01*
G01D02*
X514399Y654342D01*
G01X517006Y653854D02*
X515971Y654036D01*
G01X515702Y655251D02*
X514399Y654342D01*
G01X515971Y654036D02*
X515449Y653672D01*
G01X512291Y653601D02*
X511381Y654904D01*
G01X511075Y653332D02*
X510711Y653854D01*
G01X511381Y654904D02*
X509408Y655251D01*
G01D02*
X508105Y654341D01*
G01X510711Y653854D02*
X509677Y654036D01*
G01X509408Y655251D02*
X508105Y654341D01*
G01X509677Y654036D02*
X509155Y653671D01*
G01X506024Y653798D02*
X505087Y655140D01*
G01X504808Y653529D02*
X504417Y654089D01*
G01X505087Y655140D02*
X503179Y655475D01*
G01D02*
X501839Y654536D01*
G01X504417Y654089D02*
X503449Y654259D01*
G01X503179Y655475D02*
X501839Y654536D01*
G01X503449Y654259D02*
X502889Y653867D01*
G01X499737Y653844D02*
X498826Y655151D01*
G01X498521Y653576D02*
X498156Y654100D01*
G01X498826Y655151D02*
X496855Y655495D01*
G01D02*
X495549Y654586D01*
G01X498156Y654100D02*
X497124Y654280D01*
G01X496855Y655495D02*
X495549Y654586D01*
G01X497124Y654280D02*
X496600Y653915D01*
G01X493439Y653828D02*
X492528Y655132D01*
G01X492223Y653559D02*
X491858Y654081D01*
G01X492528Y655132D02*
X490557Y655479D01*
G01D02*
X489255Y654569D01*
G01X491858Y654081D02*
X490826Y654263D01*
G01X490557Y655479D02*
X489255Y654569D01*
G01X490826Y654263D02*
X490305Y653899D01*
G01X487143Y653827D02*
X486233Y655132D01*
G01X485927Y653559D02*
X485563Y654081D01*
G01X486233Y655132D02*
X484259Y655478D01*
G01D02*
X482956Y654564D01*
G01X485563Y654081D02*
X484530Y654262D01*
G01X484259Y655478D02*
X482956Y654564D01*
G01X484530Y654262D02*
X484007Y653895D01*
G01X480869Y653942D02*
X479957Y655243D01*
G01X479653Y653672D02*
X479288Y654193D01*
G01D02*
X478254Y654376D01*
G01X540882Y655237D02*
X539582Y654326D01*
G01X536253Y653317D02*
X535890Y653839D01*
G01X537469Y653588D02*
X536560Y654889D01*
G01X535890Y653839D02*
X534856Y654022D01*
G01X536560Y654889D02*
X534587Y655237D01*
G01X535890Y653839D02*
X534856Y654022D01*
G01D02*
X534334Y653657D01*
G01X534587Y655237D02*
X533284Y654327D01*
G01X529956Y653301D02*
X529592Y653822D01*
G01X531172Y653570D02*
X530262Y654873D01*
G01X529592Y653822D02*
X528558Y654003D01*
G01X530262Y654873D02*
X528289Y655218D01*
G01X529592Y653822D02*
X528558Y654003D01*
G01D02*
X528036Y653639D01*
G01X528289Y655218D02*
X526986Y654309D01*
G01X523661Y653299D02*
X523296Y653821D01*
G01X524877Y653568D02*
X523966Y654872D01*
G01X523296Y653821D02*
X522261Y654003D01*
G01X523966Y654872D02*
X521992Y655218D01*
G01X523296Y653821D02*
X522261Y654003D01*
G01D02*
X521739Y653639D01*
G01X521992Y655218D02*
X520689Y654309D01*
G01X517371Y653332D02*
X517006Y653854D01*
G01X518587Y653601D02*
X517676Y654905D01*
G01X517006Y653854D02*
X515971Y654036D01*
G01X517676Y654905D02*
X515702Y655251D01*
G01X517006Y653854D02*
X515971Y654036D01*
G01D02*
X515449Y653672D01*
G01X515702Y655251D02*
X514399Y654342D01*
G01X511075Y653332D02*
X510711Y653854D01*
G01X512291Y653601D02*
X511381Y654904D01*
G01X510711Y653854D02*
X509677Y654036D01*
G01X511381Y654904D02*
X509408Y655251D01*
G01X510711Y653854D02*
X509677Y654036D01*
G01D02*
X509155Y653671D01*
G01X509408Y655251D02*
X508105Y654341D01*
G01X504808Y653529D02*
X504417Y654089D01*
G01X506024Y653798D02*
X505087Y655140D01*
G01X504417Y654089D02*
X503449Y654259D01*
G01X505087Y655140D02*
X503179Y655475D01*
G01X504417Y654089D02*
X503449Y654259D01*
G01D02*
X502889Y653867D01*
G01X503179Y655475D02*
X501839Y654536D01*
G01X498521Y653576D02*
X498156Y654100D01*
G01X499737Y653844D02*
X498826Y655151D01*
G01X498156Y654100D02*
X497124Y654280D01*
G01X498826Y655151D02*
X496855Y655495D01*
G01X498156Y654100D02*
X497124Y654280D01*
G01D02*
X496600Y653915D01*
G01X496855Y655495D02*
X495549Y654586D01*
G01X492223Y653559D02*
X491858Y654081D01*
G01X493439Y653828D02*
X492528Y655132D01*
G01X491858Y654081D02*
X490826Y654263D01*
G01X492528Y655132D02*
X490557Y655479D01*
G01X491858Y654081D02*
X490826Y654263D01*
G01D02*
X490305Y653899D01*
G01X490557Y655479D02*
X489255Y654569D01*
G01X485927Y653559D02*
X485563Y654081D01*
G01X487143Y653827D02*
X486233Y655132D01*
G01X485563Y654081D02*
X484530Y654262D01*
G01X486233Y655132D02*
X484259Y655478D01*
G01X485563Y654081D02*
X484530Y654262D01*
G01D02*
X484007Y653895D01*
G01X484259Y655478D02*
X482956Y654564D01*
G01X479653Y653672D02*
X479288Y654193D01*
G01X480869Y653942D02*
X479957Y655243D01*
G01X479288Y654193D02*
X478254Y654376D01*
G01X479288Y654193D02*
X478254Y654376D01*
G01X602069Y276999D02*
X600895D01*
G01X602546Y275849D02*
X600418D01*
G01X600895Y276999D02*
X600483Y277411D01*
G01X600418Y275849D02*
X599333Y276934D01*
G01X600483Y277411D02*
Y300741D01*
G01X599333Y276934D02*
Y300264D01*
G01X596133Y300741D02*
Y277422D01*
G01X597283Y300264D02*
Y276945D01*
G01X596133Y277422D02*
X595710Y276999D01*
G01X597283Y276945D02*
X596187Y275849D01*
G01X595710Y276999D02*
X594560D01*
G01X596187Y275849D02*
X594083D01*
G01X594560Y276999D02*
X594083Y277476D01*
G01Y275849D02*
X592933Y276999D01*
G01X594083Y277476D02*
Y300741D01*
G01X592933Y276999D02*
Y300264D01*
G01X589733Y300741D02*
Y277519D01*
G01X590883Y300264D02*
Y277042D01*
G01X589733Y277519D02*
X589213Y276999D01*
G01X590883Y277042D02*
X589690Y275849D01*
G01X589213Y276999D02*
X588096D01*
G01X589690Y275849D02*
X587619D01*
G01X588096Y276999D02*
X587683Y277412D01*
G01X587619Y275849D02*
X586533Y276935D01*
G01X587683Y277412D02*
Y300741D01*
G01X586533Y276935D02*
Y300264D01*
G01X583333Y300741D02*
Y277590D01*
G01X584483Y300264D02*
Y277113D01*
G01X583333Y277590D02*
X582762Y277019D01*
G01X584483Y277113D02*
X583239Y275869D01*
G01X582762Y277019D02*
X581706D01*
G01X583239Y275869D02*
X581229D01*
G01X581706Y277019D02*
X581283Y277442D01*
G01X581229Y275869D02*
X580133Y276965D01*
G01X581283Y277442D02*
Y300741D01*
G01X580133Y276965D02*
Y300264D01*
G01X576933Y300741D02*
Y277595D01*
G01X578083Y300264D02*
Y277118D01*
G01X576933Y277595D02*
X576523Y277185D01*
G01X578083Y277118D02*
X577000Y276035D01*
G01X576523Y277185D02*
X575321D01*
G01X577000Y276035D02*
X574844D01*
G01X575321Y277185D02*
X574883Y277623D01*
G01X574844Y276035D02*
X573733Y277146D01*
G01X574883Y277623D02*
Y300741D01*
G01X573733Y277146D02*
Y300264D01*
G01X602546Y275849D02*
X600418D01*
G01X602069Y276999D02*
X600895D01*
G01X600418Y275849D02*
X599333Y276934D01*
G01X600895Y276999D02*
X600483Y277411D01*
G01X599333Y276934D02*
Y300264D01*
G01X600483Y277411D02*
Y300741D01*
G01X597283Y300264D02*
Y276945D01*
G01X596133Y300741D02*
Y277422D01*
G01X597283Y276945D02*
X596187Y275849D01*
G01X596133Y277422D02*
X595710Y276999D01*
G01X596187Y275849D02*
X594083D01*
G01X595710Y276999D02*
X594560D01*
G01X594083Y275849D02*
X592933Y276999D01*
G01X594560D02*
X594083Y277476D01*
G01X592933Y276999D02*
Y300264D01*
G01X594083Y277476D02*
Y300741D01*
G01X590883Y300264D02*
Y277042D01*
G01X589733Y300741D02*
Y277519D01*
G01X590883Y277042D02*
X589690Y275849D01*
G01X589733Y277519D02*
X589213Y276999D01*
G01X589690Y275849D02*
X587619D01*
G01X589213Y276999D02*
X588096D01*
G01X587619Y275849D02*
X586533Y276935D01*
G01X588096Y276999D02*
X587683Y277412D01*
G01X586533Y276935D02*
Y300264D01*
G01X587683Y277412D02*
Y300741D01*
G01X584483Y300264D02*
Y277113D01*
G01X583333Y300741D02*
Y277590D01*
G01X584483Y277113D02*
X583239Y275869D01*
G01X583333Y277590D02*
X582762Y277019D01*
G01X583239Y275869D02*
X581229D01*
G01X582762Y277019D02*
X581706D01*
G01X581229Y275869D02*
X580133Y276965D01*
G01X581706Y277019D02*
X581283Y277442D01*
G01X580133Y276965D02*
Y300264D01*
G01X581283Y277442D02*
Y300741D01*
G01X578083Y300264D02*
Y277118D01*
G01X576933Y300741D02*
Y277595D01*
G01X578083Y277118D02*
X577000Y276035D01*
G01X576933Y277595D02*
X576523Y277185D01*
G01X577000Y276035D02*
X574844D01*
G01X576523Y277185D02*
X575321D01*
G01X574844Y276035D02*
X573733Y277146D01*
G01X575321Y277185D02*
X574883Y277623D01*
G01X573733Y277146D02*
Y300264D01*
G01X574883Y277623D02*
Y300741D01*
G01X558225Y296961D02*
Y310866D01*
G01X559375Y296961D02*
Y298311D01*
G01X558225Y296961D02*
Y310866D01*
G01X559375Y300961D02*
Y302311D01*
G01X558225Y296961D02*
Y310866D01*
G01X559375Y304961D02*
Y306311D01*
G01X558225Y296961D02*
Y310866D01*
G01X559375Y308961D02*
Y310389D01*
G01X558225Y310866D02*
X563713Y316354D01*
G01X559375Y310389D02*
X564863Y315877D01*
G01X563713Y316354D02*
Y328713D01*
G01X564863Y315877D02*
Y328236D01*
G01X563713Y328713D02*
X582253Y347253D01*
G01X564863Y328236D02*
X582730Y346103D01*
G01X582416Y342851D02*
Y340826D01*
G01X583566Y341303D02*
X584016Y340853D01*
G01X582416Y340826D02*
X583539Y339703D01*
G01X584016Y340853D02*
X608324D01*
G01X583539Y339703D02*
X607847D01*
G01X608324Y336503D02*
X578049D01*
G01X607847Y337653D02*
X577572D01*
G01X578049Y336503D02*
X577546Y336000D01*
G01X577572Y337653D02*
X576396Y336477D01*
G01X577546Y336000D02*
Y334930D01*
G01X576396Y336477D02*
Y334453D01*
G01X577546Y334930D02*
X578023Y334453D01*
G01X576396D02*
X577546Y333303D01*
G01X578023Y334453D02*
X608324D01*
G01X577546Y333303D02*
X607847D01*
G01X608324Y330103D02*
X571416D01*
G01X607847Y331253D02*
X570939D01*
G01X571416Y330103D02*
X570879Y329566D01*
G01X570939Y331253D02*
X569729Y330043D01*
G01X570879Y329566D02*
Y328490D01*
G01X569729Y330043D02*
Y328013D01*
G01X570879Y328490D02*
X571316Y328053D01*
G01X569729Y328013D02*
X570839Y326903D01*
G01X571316Y328053D02*
X611046D01*
G01X570839Y326903D02*
X611523D01*
G01X559375Y296961D02*
Y298311D01*
G01Y300961D02*
Y302311D01*
G01Y304961D02*
Y306311D01*
G01Y308961D02*
Y310389D01*
G01X558225Y296961D02*
Y310866D01*
G01X559375Y310389D02*
X564863Y315877D01*
G01X558225Y310866D02*
X563713Y316354D01*
G01X564863Y315877D02*
Y328236D01*
G01X563713Y316354D02*
Y328713D01*
G01X564863Y328236D02*
X582730Y346103D01*
G01X563713Y328713D02*
X582253Y347253D01*
G01X582416Y342851D02*
Y340826D01*
G01D02*
X583539Y339703D01*
G01X583566Y341303D02*
X584016Y340853D01*
G01X583539Y339703D02*
X607847D01*
G01X584016Y340853D02*
X608324D01*
G01X607847Y337653D02*
X577572D01*
G01X608324Y336503D02*
X578049D01*
G01X577572Y337653D02*
X576396Y336477D01*
G01X578049Y336503D02*
X577546Y336000D01*
G01X576396Y336477D02*
Y334453D01*
G01X577546Y336000D02*
Y334930D01*
G01X576396Y334453D02*
X577546Y333303D01*
G01Y334930D02*
X578023Y334453D01*
G01X577546Y333303D02*
X607847D01*
G01X578023Y334453D02*
X608324D01*
G01X607847Y331253D02*
X570939D01*
G01X608324Y330103D02*
X571416D01*
G01X570939Y331253D02*
X569729Y330043D01*
G01X571416Y330103D02*
X570879Y329566D01*
G01X569729Y330043D02*
Y328013D01*
G01X570879Y329566D02*
Y328490D01*
G01X569729Y328013D02*
X570839Y326903D01*
G01X570879Y328490D02*
X571316Y328053D01*
G01X570839Y326903D02*
X611523D01*
G01X571316Y328053D02*
X611046D01*
G01X600483Y300741D02*
X599360Y301864D01*
G01X599333Y300264D02*
X598883Y300714D01*
G01X599360Y301864D02*
X597256D01*
G01D02*
X596133Y300741D01*
G01X598883Y300714D02*
X597733D01*
G01X597256Y301864D02*
X596133Y300741D01*
G01X597733Y300714D02*
X597283Y300264D01*
G01X594083Y300741D02*
X592960Y301864D01*
G01X592933Y300264D02*
X592483Y300714D01*
G01X592960Y301864D02*
X590856D01*
G01D02*
X589733Y300741D01*
G01X592483Y300714D02*
X591333D01*
G01X590856Y301864D02*
X589733Y300741D01*
G01X591333Y300714D02*
X590883Y300264D01*
G01X587683Y300741D02*
X586560Y301864D01*
G01X586533Y300264D02*
X586083Y300714D01*
G01X586560Y301864D02*
X584456D01*
G01D02*
X583333Y300741D01*
G01X586083Y300714D02*
X584933D01*
G01X584456Y301864D02*
X583333Y300741D01*
G01X584933Y300714D02*
X584483Y300264D01*
G01X581283Y300741D02*
X580160Y301864D01*
G01X580133Y300264D02*
X579683Y300714D01*
G01X580160Y301864D02*
X578056D01*
G01D02*
X576933Y300741D01*
G01X579683Y300714D02*
X578533D01*
G01X578056Y301864D02*
X576933Y300741D01*
G01X578533Y300714D02*
X578083Y300264D01*
G01X574883Y300741D02*
X573760Y301864D01*
G01X573733Y300264D02*
X573283Y300714D01*
G01X573760Y301864D02*
X566990D01*
G01X573283Y300714D02*
X567467D01*
G01X566990Y301864D02*
X565844Y300718D01*
G01X567467Y300714D02*
X566994Y300241D01*
G01X565844Y300718D02*
Y283844D01*
G01X566994Y300241D02*
Y298891D01*
G01X565844Y300718D02*
Y283844D01*
G01X566994Y296241D02*
Y294891D01*
G01X565844Y300718D02*
Y283844D01*
G01X566994Y292241D02*
Y290891D01*
G01X565844Y300718D02*
Y283844D01*
G01X566994Y288241D02*
Y283367D01*
G01X565844Y283844D02*
X565072Y283072D01*
G01X566994Y283367D02*
X565549Y281922D01*
G01X565072Y283072D02*
X561647D01*
G01X565549Y281922D02*
X561647D01*
G01X599333Y300264D02*
X598883Y300714D01*
G01X600483Y300741D02*
X599360Y301864D01*
G01X598883Y300714D02*
X597733D01*
G01X599360Y301864D02*
X597256D01*
G01X598883Y300714D02*
X597733D01*
G01D02*
X597283Y300264D01*
G01X597256Y301864D02*
X596133Y300741D01*
G01X592933Y300264D02*
X592483Y300714D01*
G01X594083Y300741D02*
X592960Y301864D01*
G01X592483Y300714D02*
X591333D01*
G01X592960Y301864D02*
X590856D01*
G01X592483Y300714D02*
X591333D01*
G01D02*
X590883Y300264D01*
G01X590856Y301864D02*
X589733Y300741D01*
G01X586533Y300264D02*
X586083Y300714D01*
G01X587683Y300741D02*
X586560Y301864D01*
G01X586083Y300714D02*
X584933D01*
G01X586560Y301864D02*
X584456D01*
G01X586083Y300714D02*
X584933D01*
G01D02*
X584483Y300264D01*
G01X584456Y301864D02*
X583333Y300741D01*
G01X580133Y300264D02*
X579683Y300714D01*
G01X581283Y300741D02*
X580160Y301864D01*
G01X579683Y300714D02*
X578533D01*
G01X580160Y301864D02*
X578056D01*
G01X579683Y300714D02*
X578533D01*
G01D02*
X578083Y300264D01*
G01X578056Y301864D02*
X576933Y300741D01*
G01X573733Y300264D02*
X573283Y300714D01*
G01X574883Y300741D02*
X573760Y301864D01*
G01X573283Y300714D02*
X567467D01*
G01X573760Y301864D02*
X566990D01*
G01X567467Y300714D02*
X566994Y300241D01*
G01X566990Y301864D02*
X565844Y300718D01*
G01X566994Y300241D02*
Y298891D01*
G01Y296241D02*
Y294891D01*
G01Y292241D02*
Y290891D01*
G01Y288241D02*
Y283367D01*
G01X565844Y300718D02*
Y283844D01*
G01X566994Y283367D02*
X565549Y281922D01*
G01X565844Y283844D02*
X565072Y283072D01*
G01X565549Y281922D02*
X561647D01*
G01X565072Y283072D02*
X561647D01*
G01X579590Y348988D02*
X566323Y335721D01*
G01X580740Y348511D02*
X566800Y334571D01*
G01X566323Y335721D02*
X564554D01*
G01X566800Y334571D02*
X564554D01*
G01X580740Y348511D02*
X566800Y334571D01*
G01X579590Y348988D02*
X566323Y335721D01*
G01X566800Y334571D02*
X564554D01*
G01X566323Y335721D02*
X564554D01*
G01X614621Y305465D02*
X567108D01*
G01X615098Y304315D02*
X566631D01*
G01X567108Y305465D02*
X566605Y305968D01*
G01X566631Y304315D02*
X565455Y305491D01*
G01X566605Y305968D02*
Y307065D01*
G01X565455Y305491D02*
Y307542D01*
G01X566605Y307065D02*
X567055Y307515D01*
G01X565455Y307542D02*
X566578Y308665D01*
G01X567055Y307515D02*
X613077D01*
G01X566578Y308665D02*
X612600D01*
G01X613025Y311865D02*
X571949D01*
G01X612548Y310715D02*
X571472D01*
G01X571949Y311865D02*
X571499Y312315D01*
G01X571472Y310715D02*
X570349Y311838D01*
G01X571499Y312315D02*
Y313465D01*
G01X570349Y311838D02*
Y313942D01*
G01X571499Y313465D02*
X571949Y313915D01*
G01X570349Y313942D02*
X571472Y315065D01*
G01X571949Y313915D02*
X619791D01*
G01X571472Y315065D02*
X619314D01*
G01X619698Y318265D02*
X571949D01*
G01X619221Y317115D02*
X571472D01*
G01X571949Y318265D02*
X571499Y318715D01*
G01X571472Y317115D02*
X570349Y318238D01*
G01X571499Y318715D02*
Y319865D01*
G01X570349Y318238D02*
Y320342D01*
G01X571499Y319865D02*
X571949Y320315D01*
G01X570349Y320342D02*
X571472Y321465D01*
G01X571949Y320315D02*
X613015D01*
G01X571472Y321465D02*
X612538D01*
G01X613094Y324665D02*
X568722D01*
G01X612617Y323515D02*
X569199D01*
G01X568722Y324665D02*
X567548Y323491D01*
G01X569199Y323515D02*
X568698Y323014D01*
G01X567548Y323491D02*
Y315368D01*
G01X568698Y323014D02*
Y314891D01*
G01X567548Y315368D02*
X562156Y309976D01*
G01X568698Y314891D02*
X563306Y309499D01*
G01X562156Y309976D02*
Y302279D01*
G01X563306Y309499D02*
Y302279D01*
G01X615098Y304315D02*
X566631D01*
G01X614621Y305465D02*
X567108D01*
G01X566631Y304315D02*
X565455Y305491D01*
G01X567108Y305465D02*
X566605Y305968D01*
G01X565455Y305491D02*
Y307542D01*
G01X566605Y305968D02*
Y307065D01*
G01X565455Y307542D02*
X566578Y308665D01*
G01X566605Y307065D02*
X567055Y307515D01*
G01X566578Y308665D02*
X612600D01*
G01X567055Y307515D02*
X613077D01*
G01X612548Y310715D02*
X571472D01*
G01X613025Y311865D02*
X571949D01*
G01X571472Y310715D02*
X570349Y311838D01*
G01X571949Y311865D02*
X571499Y312315D01*
G01X570349Y311838D02*
Y313942D01*
G01X571499Y312315D02*
Y313465D01*
G01X570349Y313942D02*
X571472Y315065D01*
G01X571499Y313465D02*
X571949Y313915D01*
G01X571472Y315065D02*
X619314D01*
G01X571949Y313915D02*
X619791D01*
G01X619221Y317115D02*
X571472D01*
G01X619698Y318265D02*
X571949D01*
G01X571472Y317115D02*
X570349Y318238D01*
G01X571949Y318265D02*
X571499Y318715D01*
G01X570349Y318238D02*
Y320342D01*
G01X571499Y318715D02*
Y319865D01*
G01X570349Y320342D02*
X571472Y321465D01*
G01X571499Y319865D02*
X571949Y320315D01*
G01X571472Y321465D02*
X612538D01*
G01X571949Y320315D02*
X613015D01*
G01X612617Y323515D02*
X569199D01*
G01X613094Y324665D02*
X568722D01*
G01X569199Y323515D02*
X568698Y323014D01*
G01X568722Y324665D02*
X567548Y323491D01*
G01X568698Y323014D02*
Y314891D01*
G01X567548Y323491D02*
Y315368D01*
G01X568698Y314891D02*
X563306Y309499D01*
G01X567548Y315368D02*
X562156Y309976D01*
G01X563306Y309499D02*
Y302279D01*
G01X562156Y309976D02*
Y302279D01*
G01X582253Y347253D02*
X608324D01*
G01X582730Y346103D02*
X607847D01*
G01X608324Y342903D02*
X584095D01*
G01X607847Y344053D02*
X583618D01*
G01X584095Y342903D02*
X583566Y342374D01*
G01X583618Y344053D02*
X582416Y342851D01*
G01X583566Y342374D02*
Y341303D01*
G01X582730Y346103D02*
X607847D01*
G01X582253Y347253D02*
X608324D01*
G01X607847Y344053D02*
X583618D01*
G01X608324Y342903D02*
X584095D01*
G01X583618Y344053D02*
X582416Y342851D01*
G01X584095Y342903D02*
X583566Y342374D01*
G01D02*
Y341303D01*
G01X567062Y353253D02*
Y405078D01*
G01X568212Y353253D02*
Y358925D01*
G01X567062Y353253D02*
Y405078D01*
G01X568212Y361575D02*
Y362925D01*
G01X567062Y353253D02*
Y405078D01*
G01X568212Y365575D02*
Y366925D01*
G01X567062Y353253D02*
Y405078D01*
G01X568212Y369575D02*
Y370925D01*
G01X567062Y353253D02*
Y405078D01*
G01X568212Y373575D02*
Y388601D01*
G01X567062Y353253D02*
Y405078D01*
G01X568212Y391251D02*
Y392601D01*
G01X567062Y353253D02*
Y405078D01*
G01X568212Y395251D02*
Y396601D01*
G01X567062Y353253D02*
Y405078D01*
G01X568212Y399251D02*
Y404601D01*
G01Y353253D02*
Y358925D01*
G01Y361575D02*
Y362925D01*
G01Y365575D02*
Y366925D01*
G01Y369575D02*
Y370925D01*
G01Y373575D02*
Y388601D01*
G01Y391251D02*
Y392601D01*
G01Y395251D02*
Y396601D01*
G01Y399251D02*
Y404601D01*
G01X567062Y353253D02*
Y405078D01*
G01X565348Y346271D02*
X570971D01*
G01X565348Y347421D02*
X570494D01*
G01X570971Y346271D02*
X575100Y350400D01*
G01X570494Y347421D02*
X573950Y350877D01*
G01X575100Y350400D02*
Y398733D01*
G01X573950Y350877D02*
Y399210D01*
G01X575100Y398733D02*
X575594Y399227D01*
G01X573950Y399210D02*
X575117Y400377D01*
G01X575594Y399227D02*
X576687D01*
G01X575117Y400377D02*
X577164D01*
G01X576687Y399227D02*
X577150Y398764D01*
G01X577164Y400377D02*
X578300Y399241D01*
G01X577150Y398764D02*
Y364770D01*
G01X578300Y399241D02*
Y365247D01*
G01X577150Y364770D02*
X578273Y363647D01*
G01X578300Y365247D02*
X578750Y364797D01*
G01X578273Y363647D02*
X580377D01*
G01X578750Y364797D02*
X579900D01*
G01X580377Y363647D02*
X581500Y364770D01*
G01X579900Y364797D02*
X580350Y365247D01*
G01X581500Y364770D02*
Y398315D01*
G01X580350Y365247D02*
Y398792D01*
G01X581500Y398315D02*
X581950Y398765D01*
G01X580350Y398792D02*
X581473Y399915D01*
G01X581950Y398765D02*
X583043D01*
G01X581473Y399915D02*
X583520D01*
G01X583043Y398765D02*
X583550Y398258D01*
G01X583520Y399915D02*
X584700Y398735D01*
G01X583550Y398258D02*
Y381624D01*
G01X584700Y398735D02*
Y382101D01*
G01X583550Y381624D02*
X584673Y380501D01*
G01X584700Y382101D02*
X585150Y381651D01*
G01X584673Y380501D02*
X586777D01*
G01X585150Y381651D02*
X586300D01*
G01X586777Y380501D02*
X587900Y381624D01*
G01X586300Y381651D02*
X586750Y382101D01*
G01X587900Y381624D02*
Y395965D01*
G01X586750Y382101D02*
Y396442D01*
G01X587900Y395965D02*
X590746Y398811D01*
G01X586750Y396442D02*
X590269Y399961D01*
G01X590746Y398811D02*
X609602D01*
G01X590269Y399961D02*
X609125D01*
G01X609153Y402011D02*
X579888D01*
G01D02*
X578765Y403134D01*
G01X618985Y350239D02*
X584426D01*
G01X618508Y349089D02*
X583949D01*
G01X584426Y350239D02*
X583870Y350795D01*
G01X583949Y349089D02*
X582720Y350318D01*
G01X583870Y350795D02*
Y351705D01*
G01X582720Y350318D02*
Y352182D01*
G01X583870Y351705D02*
X584454Y352289D01*
G01X582720Y352182D02*
X583977Y353439D01*
G01X584454Y352289D02*
X618845D01*
G01X583977Y353439D02*
X618368D01*
G01X618912Y356639D02*
X588653D01*
G01X618435Y355489D02*
X588176D01*
G01X588653Y356639D02*
X588176Y357116D01*
G01Y355489D02*
X587026Y356639D01*
G01X588176Y357116D02*
Y358239D01*
G01X587026Y356639D02*
Y358716D01*
G01X588176Y358239D02*
X588626Y358689D01*
G01X587026Y358716D02*
X588149Y359839D01*
G01X588626Y358689D02*
X618894D01*
G01X588149Y359839D02*
X618417D01*
G01X618974Y363039D02*
X589665D01*
G01X618497Y361889D02*
X589188D01*
G01X589665Y363039D02*
X589215Y363489D01*
G01X589188Y361889D02*
X588065Y363012D01*
G01X589215Y363489D02*
Y364532D01*
G01X588065Y363012D02*
Y365009D01*
G01X589215Y364532D02*
X589772Y365089D01*
G01X588065Y365009D02*
X589295Y366239D01*
G01X589772Y365089D02*
X618611D01*
G01X589295Y366239D02*
X618134D01*
G01X618548Y369439D02*
X590293D01*
G01X618071Y368289D02*
X589816D01*
G01X590293Y369439D02*
X589843Y369889D01*
G01X589816Y368289D02*
X588693Y369412D01*
G01X589843Y369889D02*
Y371039D01*
G01X588693Y369412D02*
Y371516D01*
G01X589843Y371039D02*
X590293Y371489D01*
G01X588693Y371516D02*
X589816Y372639D01*
G01X590293Y371489D02*
X618974D01*
G01X589816Y372639D02*
X618497D01*
G01X618840Y375839D02*
X588115D01*
G01X618363Y374689D02*
X588592D01*
G01X588115Y375839D02*
X584702Y372426D01*
G01X588592Y374689D02*
X585852Y371949D01*
G01X584702Y372426D02*
Y361370D01*
G01X585852Y371949D02*
Y360893D01*
G01X584702Y361370D02*
X579590Y356258D01*
G01X585852Y360893D02*
X580740Y355781D01*
G01X579590Y356258D02*
Y348988D01*
G01X580740Y355781D02*
Y348511D01*
G01X618508Y349089D02*
X583949D01*
G01X618985Y350239D02*
X584426D01*
G01X583949Y349089D02*
X582720Y350318D01*
G01X584426Y350239D02*
X583870Y350795D01*
G01X582720Y350318D02*
Y352182D01*
G01X583870Y350795D02*
Y351705D01*
G01X582720Y352182D02*
X583977Y353439D01*
G01X583870Y351705D02*
X584454Y352289D01*
G01X583977Y353439D02*
X618368D01*
G01X584454Y352289D02*
X618845D01*
G01X618435Y355489D02*
X588176D01*
G01X618912Y356639D02*
X588653D01*
G01X588176Y355489D02*
X587026Y356639D01*
G01X588653D02*
X588176Y357116D01*
G01X587026Y356639D02*
Y358716D01*
G01X588176Y357116D02*
Y358239D01*
G01X587026Y358716D02*
X588149Y359839D01*
G01X588176Y358239D02*
X588626Y358689D01*
G01X588149Y359839D02*
X618417D01*
G01X588626Y358689D02*
X618894D01*
G01X618497Y361889D02*
X589188D01*
G01X618974Y363039D02*
X589665D01*
G01X589188Y361889D02*
X588065Y363012D01*
G01X589665Y363039D02*
X589215Y363489D01*
G01X588065Y363012D02*
Y365009D01*
G01X589215Y363489D02*
Y364532D01*
G01X588065Y365009D02*
X589295Y366239D01*
G01X589215Y364532D02*
X589772Y365089D01*
G01X589295Y366239D02*
X618134D01*
G01X589772Y365089D02*
X618611D01*
G01X618071Y368289D02*
X589816D01*
G01X618548Y369439D02*
X590293D01*
G01X589816Y368289D02*
X588693Y369412D01*
G01X590293Y369439D02*
X589843Y369889D01*
G01X588693Y369412D02*
Y371516D01*
G01X589843Y369889D02*
Y371039D01*
G01X588693Y371516D02*
X589816Y372639D01*
G01X589843Y371039D02*
X590293Y371489D01*
G01X589816Y372639D02*
X618497D01*
G01X590293Y371489D02*
X618974D01*
G01X618363Y374689D02*
X588592D01*
G01X618840Y375839D02*
X588115D01*
G01X588592Y374689D02*
X585852Y371949D01*
G01X588115Y375839D02*
X584702Y372426D01*
G01X585852Y371949D02*
Y360893D01*
G01X584702Y372426D02*
Y361370D01*
G01X585852Y360893D02*
X580740Y355781D01*
G01X584702Y361370D02*
X579590Y356258D01*
G01X580740Y355781D02*
Y348511D01*
G01X579590Y356258D02*
Y348988D01*
G01X565348Y347421D02*
X570494D01*
G01X565348Y346271D02*
X570971D01*
G01X570494Y347421D02*
X573950Y350877D01*
G01X570971Y346271D02*
X575100Y350400D01*
G01X573950Y350877D02*
Y399210D01*
G01X575100Y350400D02*
Y398733D01*
G01X573950Y399210D02*
X575117Y400377D01*
G01X575100Y398733D02*
X575594Y399227D01*
G01X575117Y400377D02*
X577164D01*
G01X575594Y399227D02*
X576687D01*
G01X577164Y400377D02*
X578300Y399241D01*
G01X576687Y399227D02*
X577150Y398764D01*
G01X578300Y399241D02*
Y365247D01*
G01X577150Y398764D02*
Y364770D01*
G01X578300Y365247D02*
X578750Y364797D01*
G01X577150Y364770D02*
X578273Y363647D01*
G01X578750Y364797D02*
X579900D01*
G01X578273Y363647D02*
X580377D01*
G01X579900Y364797D02*
X580350Y365247D01*
G01X580377Y363647D02*
X581500Y364770D01*
G01X580350Y365247D02*
Y398792D01*
G01X581500Y364770D02*
Y398315D01*
G01X580350Y398792D02*
X581473Y399915D01*
G01X581500Y398315D02*
X581950Y398765D01*
G01X581473Y399915D02*
X583520D01*
G01X581950Y398765D02*
X583043D01*
G01X583520Y399915D02*
X584700Y398735D01*
G01X583043Y398765D02*
X583550Y398258D01*
G01X584700Y398735D02*
Y382101D01*
G01X583550Y398258D02*
Y381624D01*
G01X584700Y382101D02*
X585150Y381651D01*
G01X583550Y381624D02*
X584673Y380501D01*
G01X585150Y381651D02*
X586300D01*
G01X584673Y380501D02*
X586777D01*
G01X586300Y381651D02*
X586750Y382101D01*
G01X586777Y380501D02*
X587900Y381624D01*
G01X586750Y382101D02*
Y396442D01*
G01X587900Y381624D02*
Y395965D01*
G01X586750Y396442D02*
X590269Y399961D01*
G01X587900Y395965D02*
X590746Y398811D01*
G01X590269Y399961D02*
X609125D01*
G01X590746Y398811D02*
X609602D01*
G01X609153Y402011D02*
X579888D01*
G01D02*
X578765Y403134D01*
G01X567062Y405078D02*
X571901Y409917D01*
G01X568212Y404601D02*
X572378Y408767D01*
G01X571901Y409917D02*
X610386D01*
G01X572378Y408767D02*
X610863D01*
G01X610400Y411967D02*
X571933D01*
G01X610877Y413117D02*
X572410D01*
G01X571933Y411967D02*
X570810Y413090D01*
G01X572410Y413117D02*
X571960Y413567D01*
G01X570810Y413090D02*
Y415194D01*
G01X571960Y413567D02*
Y414717D01*
G01X570810Y415194D02*
X571933Y416317D01*
G01X571960Y414717D02*
X572410Y415167D01*
G01X571933Y416317D02*
X613649D01*
G01X572410Y415167D02*
X613172D01*
G01X568212Y404601D02*
X572378Y408767D01*
G01X567062Y405078D02*
X571901Y409917D01*
G01X572378Y408767D02*
X610863D01*
G01X571901Y409917D02*
X610386D01*
G01X610877Y413117D02*
X572410D01*
G01X610400Y411967D02*
X571933D01*
G01X572410Y413117D02*
X571960Y413567D01*
G01X571933Y411967D02*
X570810Y413090D01*
G01X571960Y413567D02*
Y414717D01*
G01X570810Y413090D02*
Y415194D01*
G01X571960Y414717D02*
X572410Y415167D01*
G01X570810Y415194D02*
X571933Y416317D01*
G01X572410Y415167D02*
X613172D01*
G01X571933Y416317D02*
X613649D01*
G01X609630Y403161D02*
X580365D01*
G01D02*
X579915Y403611D01*
G01D02*
Y404761D01*
G01X578765Y403134D02*
Y405238D01*
G01X579915Y404761D02*
X580365Y405211D01*
G01X578765Y405238D02*
X579888Y406361D01*
G01X580365Y405211D02*
X612296D01*
G01X579888Y406361D02*
X612773D01*
G01X609630Y403161D02*
X580365D01*
G01D02*
X579915Y403611D01*
G01X578765Y403134D02*
Y405238D01*
G01X579915Y403611D02*
Y404761D01*
G01X578765Y405238D02*
X579888Y406361D01*
G01X579915Y404761D02*
X580365Y405211D01*
G01X579888Y406361D02*
X612773D01*
G01X580365Y405211D02*
X612296D01*
G01X574516Y648663D02*
X572728D01*
G01X572775Y649813D02*
X568320Y650170D01*
G01X572728Y648663D02*
X568453Y649005D01*
G01X568320Y650170D02*
X564649Y649003D01*
G01X568453Y649005D02*
X565349Y648018D01*
G01X564649Y649003D02*
X563668Y647695D01*
G01X565349Y648018D02*
X564727Y647188D01*
G01X563668Y647695D02*
X563424Y646734D01*
G01X564727Y647188D02*
X564550Y646492D01*
G01X563424Y646734D02*
X563088Y644824D01*
G01X564550Y646492D02*
X564139Y644155D01*
G01X563088Y644824D02*
X562567Y644459D01*
G01D02*
X561533Y644641D01*
G01X564139Y644155D02*
X562837Y643243D01*
G01X562567Y644459D02*
X561533Y644641D01*
G01X562837Y643243D02*
X560863Y643590D01*
G01X561533Y644641D02*
X561168Y645163D01*
G01X560863Y643590D02*
X559952Y644894D01*
G01X561168Y645163D02*
X562652Y653570D01*
G01X559952Y644894D02*
X561436Y653300D01*
G01X558466Y654313D02*
X556781Y644763D01*
G01X559516Y653644D02*
X557832Y644094D01*
G01X556781Y644763D02*
X556258Y644396D01*
G01D02*
X555225Y644578D01*
G01X557832Y644094D02*
X556528Y643180D01*
G01X556258Y644396D02*
X555225Y644578D01*
G01X556528Y643180D02*
X554554Y643528D01*
G01X555225Y644578D02*
X554861Y645101D01*
G01X554554Y643528D02*
X553645Y644833D01*
G01X554861Y645101D02*
X556353Y653555D01*
G01X553645Y644833D02*
X555137Y653286D01*
G01X552165Y654294D02*
X550486Y644760D01*
G01X553215Y653624D02*
X551537Y644090D01*
G01X550486Y644760D02*
X549964Y644395D01*
G01D02*
X548931Y644576D01*
G01X551537Y644090D02*
X550234Y643180D01*
G01X549964Y644395D02*
X548931Y644576D01*
G01X550234Y643180D02*
X548262Y643525D01*
G01X548931Y644576D02*
X548566Y645098D01*
G01X548262Y643525D02*
X547350Y644829D01*
G01X548566Y645098D02*
X550057Y653554D01*
G01X547350Y644829D02*
X548841Y653285D01*
G01X545869Y654293D02*
X544187Y644741D01*
G01X546920Y653623D02*
X545237Y644071D01*
G01X544187Y644741D02*
X543665Y644377D01*
G01D02*
X542632Y644558D01*
G01X545237Y644071D02*
X543934Y643162D01*
G01X543665Y644377D02*
X542632Y644558D01*
G01X543934Y643162D02*
X541965Y643507D01*
G01X542632Y644558D02*
X542266Y645078D01*
G01X541965Y643507D02*
X541050Y644807D01*
G01X542266Y645078D02*
X543766Y653587D01*
G01X541050Y644807D02*
X542550Y653318D01*
G01X574516Y648663D02*
X572728D01*
G01D02*
X568453Y649005D01*
G01X572775Y649813D02*
X568320Y650170D01*
G01X568453Y649005D02*
X565349Y648018D01*
G01X568320Y650170D02*
X564649Y649003D01*
G01X565349Y648018D02*
X564727Y647188D01*
G01X564649Y649003D02*
X563668Y647695D01*
G01X564727Y647188D02*
X564550Y646492D01*
G01X563668Y647695D02*
X563424Y646734D01*
G01X564550Y646492D02*
X564139Y644155D01*
G01X563424Y646734D02*
X563088Y644824D01*
G01X564139Y644155D02*
X562837Y643243D01*
G01X563088Y644824D02*
X562567Y644459D01*
G01X564139Y644155D02*
X562837Y643243D01*
G01D02*
X560863Y643590D01*
G01X562567Y644459D02*
X561533Y644641D01*
G01X560863Y643590D02*
X559952Y644894D01*
G01X561533Y644641D02*
X561168Y645163D01*
G01X559952Y644894D02*
X561436Y653300D01*
G01X561168Y645163D02*
X562652Y653570D01*
G01X559516Y653644D02*
X557832Y644094D01*
G01X558466Y654313D02*
X556781Y644763D01*
G01X557832Y644094D02*
X556528Y643180D01*
G01X556781Y644763D02*
X556258Y644396D01*
G01X557832Y644094D02*
X556528Y643180D01*
G01D02*
X554554Y643528D01*
G01X556258Y644396D02*
X555225Y644578D01*
G01X554554Y643528D02*
X553645Y644833D01*
G01X555225Y644578D02*
X554861Y645101D01*
G01X553645Y644833D02*
X555137Y653286D01*
G01X554861Y645101D02*
X556353Y653555D01*
G01X553215Y653624D02*
X551537Y644090D01*
G01X552165Y654294D02*
X550486Y644760D01*
G01X551537Y644090D02*
X550234Y643180D01*
G01X550486Y644760D02*
X549964Y644395D01*
G01X551537Y644090D02*
X550234Y643180D01*
G01D02*
X548262Y643525D01*
G01X549964Y644395D02*
X548931Y644576D01*
G01X548262Y643525D02*
X547350Y644829D01*
G01X548931Y644576D02*
X548566Y645098D01*
G01X547350Y644829D02*
X548841Y653285D01*
G01X548566Y645098D02*
X550057Y653554D01*
G01X546920Y653623D02*
X545237Y644071D01*
G01X545869Y654293D02*
X544187Y644741D01*
G01X545237Y644071D02*
X543934Y643162D01*
G01X544187Y644741D02*
X543665Y644377D01*
G01X545237Y644071D02*
X543934Y643162D01*
G01D02*
X541965Y643507D01*
G01X543665Y644377D02*
X542632Y644558D01*
G01X541965Y643507D02*
X541050Y644807D01*
G01X542632Y644558D02*
X542266Y645078D01*
G01X541050Y644807D02*
X542550Y653318D01*
G01X542266Y645078D02*
X543766Y653587D01*
G01X574516Y649813D02*
X572775D01*
G01X562652Y653570D02*
X561739Y654874D01*
G01X561436Y653300D02*
X561069Y653824D01*
G01X561739Y654874D02*
X559766Y655223D01*
G01D02*
X558466Y654313D01*
G01X561069Y653824D02*
X560035Y654007D01*
G01X559766Y655223D02*
X558466Y654313D01*
G01X560035Y654007D02*
X559516Y653644D01*
G01X556353Y653555D02*
X555443Y654858D01*
G01X555137Y653286D02*
X554773Y653807D01*
G01X555443Y654858D02*
X553469Y655204D01*
G01D02*
X552165Y654294D01*
G01X554773Y653807D02*
X553738Y653989D01*
G01X553469Y655204D02*
X552165Y654294D01*
G01X553738Y653989D02*
X553215Y653624D01*
G01X550057Y653554D02*
X549147Y654857D01*
G01X548841Y653285D02*
X548477Y653806D01*
G01X549147Y654857D02*
X547173Y655203D01*
G01D02*
X545869Y654293D01*
G01X548477Y653806D02*
X547443Y653988D01*
G01X547173Y655203D02*
X545869Y654293D01*
G01X547443Y653988D02*
X546920Y653623D01*
G01X543766Y653587D02*
X542856Y654890D01*
G01X542550Y653318D02*
X542186Y653839D01*
G01X542856Y654890D02*
X540882Y655237D01*
G01X542186Y653839D02*
X541152Y654021D01*
G01D02*
X540632Y653657D01*
G01X574516Y649813D02*
X572775D01*
G01X561436Y653300D02*
X561069Y653824D01*
G01X562652Y653570D02*
X561739Y654874D01*
G01X561069Y653824D02*
X560035Y654007D01*
G01X561739Y654874D02*
X559766Y655223D01*
G01X561069Y653824D02*
X560035Y654007D01*
G01D02*
X559516Y653644D01*
G01X559766Y655223D02*
X558466Y654313D01*
G01X555137Y653286D02*
X554773Y653807D01*
G01X556353Y653555D02*
X555443Y654858D01*
G01X554773Y653807D02*
X553738Y653989D01*
G01X555443Y654858D02*
X553469Y655204D01*
G01X554773Y653807D02*
X553738Y653989D01*
G01D02*
X553215Y653624D01*
G01X553469Y655204D02*
X552165Y654294D01*
G01X548841Y653285D02*
X548477Y653806D01*
G01X550057Y653554D02*
X549147Y654857D01*
G01X548477Y653806D02*
X547443Y653988D01*
G01X549147Y654857D02*
X547173Y655203D01*
G01X548477Y653806D02*
X547443Y653988D01*
G01D02*
X546920Y653623D01*
G01X547173Y655203D02*
X545869Y654293D01*
G01X542550Y653318D02*
X542186Y653839D01*
G01X543766Y653587D02*
X542856Y654890D01*
G01X542186Y653839D02*
X541152Y654021D01*
G01X542856Y654890D02*
X540882Y655237D01*
G01X542186Y653839D02*
X541152Y654021D01*
G01D02*
X540632Y653657D01*
G01X614102Y112950D02*
X615650D01*
G01X614102Y114100D02*
X616127D01*
G01X615650Y112950D02*
X619300Y109300D01*
G01X616127Y114100D02*
X619777Y110450D01*
G01X619300Y109300D02*
X629786D01*
G01X619777Y110450D02*
X629309D01*
G01X629786Y109300D02*
X630909Y110423D01*
G01X629309Y110450D02*
X629759Y110900D01*
G01X630909Y110423D02*
Y112864D01*
G01X629759Y110900D02*
Y113341D01*
G01X630909Y112864D02*
X631359Y113314D01*
G01X629759Y113341D02*
X630882Y114464D01*
G01X631359Y113314D02*
X633909D01*
G01X630882Y114464D02*
X634386D01*
G01X633909Y113314D02*
X634359Y112864D01*
G01X634386Y114464D02*
X635509Y113341D01*
G01X634359Y112864D02*
Y100023D01*
G01X635509Y113341D02*
Y100500D01*
G01X634359Y100023D02*
X635482Y98900D01*
G01X635509Y100500D02*
X635959Y100050D01*
G01X635482Y98900D02*
X638986D01*
G01X635959Y100050D02*
X638509D01*
G01X638986Y98900D02*
X640109Y100023D01*
G01X638509Y100050D02*
X638959Y100500D01*
G01X640109Y100023D02*
Y112650D01*
G01X638959Y100500D02*
Y113127D01*
G01X640109Y112650D02*
X640559Y113100D01*
G01X638959Y113127D02*
X640082Y114250D01*
G01X640559Y113100D02*
X643109D01*
G01X640082Y114250D02*
X643586D01*
G01X643109Y113100D02*
X643559Y112650D01*
G01X643586Y114250D02*
X644709Y113127D01*
G01X643559Y112650D02*
Y100123D01*
G01X644709Y113127D02*
Y100600D01*
G01X643559Y100123D02*
X644682Y99000D01*
G01X644709Y100600D02*
X645159Y100150D01*
G01X644682Y99000D02*
X648186D01*
G01X645159Y100150D02*
X647709D01*
G01X648186Y99000D02*
X649309Y100123D01*
G01X647709Y100150D02*
X648159Y100600D01*
G01X649309Y100123D02*
Y111751D01*
G01X648159Y100600D02*
Y112228D01*
G01X649309Y111751D02*
X649759Y112201D01*
G01X648159Y112228D02*
X649282Y113351D01*
G01X649759Y112201D02*
X663828D01*
G01X649282Y113351D02*
X663351D01*
G01X614102Y114100D02*
X616127D01*
G01X614102Y112950D02*
X615650D01*
G01X616127Y114100D02*
X619777Y110450D01*
G01X615650Y112950D02*
X619300Y109300D01*
G01X619777Y110450D02*
X629309D01*
G01X619300Y109300D02*
X629786D01*
G01X629309Y110450D02*
X629759Y110900D01*
G01X629786Y109300D02*
X630909Y110423D01*
G01X629759Y110900D02*
Y113341D01*
G01X630909Y110423D02*
Y112864D01*
G01X629759Y113341D02*
X630882Y114464D01*
G01X630909Y112864D02*
X631359Y113314D01*
G01X630882Y114464D02*
X634386D01*
G01X631359Y113314D02*
X633909D01*
G01X634386Y114464D02*
X635509Y113341D01*
G01X633909Y113314D02*
X634359Y112864D01*
G01X635509Y113341D02*
Y100500D01*
G01X634359Y112864D02*
Y100023D01*
G01X635509Y100500D02*
X635959Y100050D01*
G01X634359Y100023D02*
X635482Y98900D01*
G01X635959Y100050D02*
X638509D01*
G01X635482Y98900D02*
X638986D01*
G01X638509Y100050D02*
X638959Y100500D01*
G01X638986Y98900D02*
X640109Y100023D01*
G01X638959Y100500D02*
Y113127D01*
G01X640109Y100023D02*
Y112650D01*
G01X638959Y113127D02*
X640082Y114250D01*
G01X640109Y112650D02*
X640559Y113100D01*
G01X640082Y114250D02*
X643586D01*
G01X640559Y113100D02*
X643109D01*
G01X643586Y114250D02*
X644709Y113127D01*
G01X643109Y113100D02*
X643559Y112650D01*
G01X644709Y113127D02*
Y100600D01*
G01X643559Y112650D02*
Y100123D01*
G01X644709Y100600D02*
X645159Y100150D01*
G01X643559Y100123D02*
X644682Y99000D01*
G01X645159Y100150D02*
X647709D01*
G01X644682Y99000D02*
X648186D01*
G01X647709Y100150D02*
X648159Y100600D01*
G01X648186Y99000D02*
X649309Y100123D01*
G01X648159Y100600D02*
Y112228D01*
G01X649309Y100123D02*
Y111751D01*
G01X648159Y112228D02*
X649282Y113351D01*
G01X649309Y111751D02*
X649759Y112201D01*
G01X649282Y113351D02*
X663351D01*
G01X649759Y112201D02*
X663828D01*
G01X608933Y300741D02*
Y279300D01*
G01X610083Y300264D02*
Y278823D01*
G01X608933Y279300D02*
X608377Y278744D01*
G01X610083Y278823D02*
X608854Y277594D01*
G01X608377Y278744D02*
X607360D01*
G01X608854Y277594D02*
X606883D01*
G01X607360Y278744D02*
X606883Y279221D01*
G01Y277594D02*
X605733Y278744D01*
G01X606883Y279221D02*
Y300741D01*
G01X605733Y278744D02*
Y300264D01*
G01X602533Y300741D02*
Y277463D01*
G01X603683Y300264D02*
Y276986D01*
G01X602533Y277463D02*
X602069Y276999D01*
G01X603683Y276986D02*
X602546Y275849D01*
G01X610083Y300264D02*
Y278823D01*
G01X608933Y300741D02*
Y279300D01*
G01X610083Y278823D02*
X608854Y277594D01*
G01X608933Y279300D02*
X608377Y278744D01*
G01X608854Y277594D02*
X606883D01*
G01X608377Y278744D02*
X607360D01*
G01X606883Y277594D02*
X605733Y278744D01*
G01X607360D02*
X606883Y279221D01*
G01X605733Y278744D02*
Y300264D01*
G01X606883Y279221D02*
Y300741D01*
G01X603683Y300264D02*
Y276986D01*
G01X602533Y300741D02*
Y277463D01*
G01X603683Y276986D02*
X602546Y275849D01*
G01X602533Y277463D02*
X602069Y276999D01*
G01X608324Y340853D02*
X609447Y339730D01*
G01X607847Y339703D02*
X608297Y339253D01*
G01X609447Y339730D02*
Y337626D01*
G01X608297Y339253D02*
Y338103D01*
G01X609447Y337626D02*
X608324Y336503D01*
G01X608297Y338103D02*
X607847Y337653D01*
G01X608324Y334453D02*
X609447Y333330D01*
G01X607847Y333303D02*
X608297Y332853D01*
G01X609447Y333330D02*
Y331226D01*
G01X608297Y332853D02*
Y331703D01*
G01X609447Y331226D02*
X608324Y330103D01*
G01X608297Y331703D02*
X607847Y331253D01*
G01X611046Y328053D02*
X611497Y328504D01*
G01X611523Y326903D02*
X612647Y328027D01*
G01X611497Y328504D02*
Y346130D01*
G01X612647Y328027D02*
Y345653D01*
G01X617253Y345993D02*
Y325248D01*
G01X616103Y345516D02*
Y324771D01*
G01X617253Y325248D02*
X626611Y315890D01*
G01D02*
X627511D01*
G01X616103Y324771D02*
X626134Y314740D01*
G01X626611Y315890D02*
X627511D01*
G01X626134Y314740D02*
X627988D01*
G01X627511Y315890D02*
X628080Y316459D01*
G01X627988Y314740D02*
X629230Y315982D01*
G01X628080Y316459D02*
Y317322D01*
G01X629230Y315982D02*
Y317799D01*
G01X628080Y317322D02*
X619734Y325668D01*
G01X629230Y317799D02*
X620884Y326145D01*
G01X619734Y325668D02*
Y327255D01*
G01X620884Y326145D02*
Y326778D01*
G01X619734Y327255D02*
X621172Y328693D01*
G01X620884Y326778D02*
X621649Y327543D01*
G01X619734Y327255D02*
X621172Y328693D01*
G01D02*
X622866D01*
G01D02*
X636472Y315087D01*
G01X621649Y327543D02*
X622389D01*
G01X622866Y328693D02*
X636472Y315087D01*
G01X622389Y327543D02*
X635995Y313937D01*
G01X636472Y315087D02*
X637111D01*
G01X635995Y313937D02*
X637099D01*
G01X607847Y339703D02*
X608297Y339253D01*
G01X608324Y340853D02*
X609447Y339730D01*
G01X608297Y339253D02*
Y338103D01*
G01X609447Y339730D02*
Y337626D01*
G01X608297Y338103D02*
X607847Y337653D01*
G01X609447Y337626D02*
X608324Y336503D01*
G01X607847Y333303D02*
X608297Y332853D01*
G01X608324Y334453D02*
X609447Y333330D01*
G01X608297Y332853D02*
Y331703D01*
G01X609447Y333330D02*
Y331226D01*
G01X608297Y331703D02*
X607847Y331253D01*
G01X609447Y331226D02*
X608324Y330103D01*
G01X611523Y326903D02*
X612647Y328027D01*
G01X611046Y328053D02*
X611497Y328504D01*
G01X612647Y328027D02*
Y345653D01*
G01X611497Y328504D02*
Y346130D01*
G01X616103Y345516D02*
Y324771D01*
G01X617253Y345993D02*
Y325248D01*
G01X616103Y324771D02*
X626134Y314740D01*
G01X617253Y325248D02*
X626611Y315890D01*
G01X616103Y324771D02*
X626134Y314740D01*
G01D02*
X627988D01*
G01X626611Y315890D02*
X627511D01*
G01X627988Y314740D02*
X629230Y315982D01*
G01X627511Y315890D02*
X628080Y316459D01*
G01X629230Y315982D02*
Y317799D01*
G01X628080Y316459D02*
Y317322D01*
G01X629230Y317799D02*
X620884Y326145D01*
G01X628080Y317322D02*
X619734Y325668D01*
G01X620884Y326145D02*
Y326778D01*
G01X619734Y325668D02*
Y327255D01*
G01X620884Y326778D02*
X621649Y327543D01*
G01D02*
X622389D01*
G01X619734Y327255D02*
X621172Y328693D01*
G01X621649Y327543D02*
X622389D01*
G01X621172Y328693D02*
X622866D01*
G01X621649Y327543D02*
X622389D01*
G01D02*
X635995Y313937D01*
G01X622866Y328693D02*
X636472Y315087D01*
G01X635995Y313937D02*
X637099D01*
G01X636472Y315087D02*
X637111D01*
G01X624150Y384300D02*
Y336523D01*
G01X625300Y384777D02*
Y337000D01*
G01X624150Y336523D02*
X625273Y335400D01*
G01X625300Y337000D02*
X625750Y336550D01*
G01X625273Y335400D02*
X627377D01*
G01X625750Y336550D02*
X626900D01*
G01X627377Y335400D02*
X628500Y336523D01*
G01X626900Y336550D02*
X627350Y337000D01*
G01X628500Y336523D02*
Y382758D01*
G01X627350Y337000D02*
Y383235D01*
G01X631250Y382604D02*
Y335773D01*
G01X632400Y383081D02*
Y336250D01*
G01X631250Y335773D02*
X632773Y334250D01*
G01X632400Y336250D02*
X633250Y335400D01*
G01X632773Y334250D02*
X637201D01*
G01X633250Y335400D02*
X637101D01*
G01X645928Y344900D02*
X642370Y341342D01*
G01X641220Y341819D02*
Y299147D01*
G01X642370Y341342D02*
Y339992D01*
G01X641220Y341819D02*
Y299147D01*
G01X642377Y339985D02*
Y339349D01*
G01X641220Y341819D02*
Y299147D01*
G01X642370Y339342D02*
Y298670D01*
G01X641220Y299147D02*
X639623Y297550D01*
G01X642370Y298670D02*
X640100Y296400D01*
G01X639623Y297550D02*
X627216D01*
G01X640100Y296400D02*
X634739D01*
G01X639623Y297550D02*
X627216D01*
G01X632089Y296400D02*
X630739D01*
G01X639623Y297550D02*
X627216D01*
G01X628089Y296400D02*
X626739D01*
G01X627216Y297550D02*
X626766Y298000D01*
G01X626739Y296400D02*
X625616Y297523D01*
G01X626766Y298000D02*
Y307707D01*
G01X625616Y297523D02*
Y307230D01*
G01X626766Y307707D02*
X625643Y308830D01*
G01X625616Y307230D02*
X625166Y307680D01*
G01X625643Y308830D02*
X623619D01*
G01X625166Y307680D02*
X624096D01*
G01X623619Y308830D02*
X622416Y307627D01*
G01X624096Y307680D02*
X623566Y307150D01*
G01X622416Y307627D02*
Y303297D01*
G01X623566Y307150D02*
Y302820D01*
G01X622416Y303297D02*
X620983Y301864D01*
G01X623566Y302820D02*
X621460Y300714D01*
G01X620983Y301864D02*
X616456D01*
G01X621460Y300714D02*
X616933D01*
G01X616456Y301864D02*
X615333Y300741D01*
G01X616933Y300714D02*
X616483Y300264D01*
G01X615333Y300741D02*
Y291341D01*
G01X616483Y300264D02*
Y290864D01*
G01X615333Y291341D02*
X614883Y290891D01*
G01X616483Y290864D02*
X615360Y289741D01*
G01X614883Y290891D02*
X613867D01*
G01X615360Y289741D02*
X613390D01*
G01X613867Y290891D02*
X613283Y291475D01*
G01X613390Y289741D02*
X612133Y290998D01*
G01X613283Y291475D02*
Y300741D01*
G01X612133Y290998D02*
Y300264D01*
G01X613283Y300741D02*
X612160Y301864D01*
G01X612133Y300264D02*
X611683Y300714D01*
G01X612160Y301864D02*
X610056D01*
G01D02*
X608933Y300741D01*
G01X611683Y300714D02*
X610533D01*
G01X610056Y301864D02*
X608933Y300741D01*
G01X610533Y300714D02*
X610083Y300264D01*
G01X606883Y300741D02*
X605760Y301864D01*
G01X605733Y300264D02*
X605283Y300714D01*
G01X605760Y301864D02*
X603656D01*
G01D02*
X602533Y300741D01*
G01X605283Y300714D02*
X604133D01*
G01X603656Y301864D02*
X602533Y300741D01*
G01X604133Y300714D02*
X603683Y300264D01*
G01X645928Y344900D02*
X642370Y341342D01*
G01D02*
Y339992D01*
G01X642377Y339985D02*
Y339349D01*
G01X642370Y339342D02*
Y298670D01*
G01X641220Y341819D02*
Y299147D01*
G01X642370Y298670D02*
X640100Y296400D01*
G01X641220Y299147D02*
X639623Y297550D01*
G01X640100Y296400D02*
X634739D01*
G01X632089D02*
X630739D01*
G01X628089D02*
X626739D01*
G01X639623Y297550D02*
X627216D01*
G01X626739Y296400D02*
X625616Y297523D01*
G01X627216Y297550D02*
X626766Y298000D01*
G01X625616Y297523D02*
Y307230D01*
G01X626766Y298000D02*
Y307707D01*
G01X625616Y307230D02*
X625166Y307680D01*
G01X626766Y307707D02*
X625643Y308830D01*
G01X625166Y307680D02*
X624096D01*
G01X625643Y308830D02*
X623619D01*
G01X624096Y307680D02*
X623566Y307150D01*
G01X623619Y308830D02*
X622416Y307627D01*
G01X623566Y307150D02*
Y302820D01*
G01X622416Y307627D02*
Y303297D01*
G01X623566Y302820D02*
X621460Y300714D01*
G01X622416Y303297D02*
X620983Y301864D01*
G01X621460Y300714D02*
X616933D01*
G01X620983Y301864D02*
X616456D01*
G01X616933Y300714D02*
X616483Y300264D01*
G01X616456Y301864D02*
X615333Y300741D01*
G01X616483Y300264D02*
Y290864D01*
G01X615333Y300741D02*
Y291341D01*
G01X616483Y290864D02*
X615360Y289741D01*
G01X615333Y291341D02*
X614883Y290891D01*
G01X615360Y289741D02*
X613390D01*
G01X614883Y290891D02*
X613867D01*
G01X613390Y289741D02*
X612133Y290998D01*
G01X613867Y290891D02*
X613283Y291475D01*
G01X612133Y290998D02*
Y300264D01*
G01X613283Y291475D02*
Y300741D01*
G01X612133Y300264D02*
X611683Y300714D01*
G01X613283Y300741D02*
X612160Y301864D01*
G01X611683Y300714D02*
X610533D01*
G01X612160Y301864D02*
X610056D01*
G01X611683Y300714D02*
X610533D01*
G01D02*
X610083Y300264D01*
G01X610056Y301864D02*
X608933Y300741D01*
G01X605733Y300264D02*
X605283Y300714D01*
G01X606883Y300741D02*
X605760Y301864D01*
G01X605283Y300714D02*
X604133D01*
G01X605760Y301864D02*
X603656D01*
G01X605283Y300714D02*
X604133D01*
G01D02*
X603683Y300264D01*
G01X603656Y301864D02*
X602533Y300741D01*
G01X636693Y325075D02*
X631028D01*
G01X636693Y323925D02*
X630551D01*
G01X631028Y325075D02*
X620609Y335494D01*
G01X630551Y323925D02*
X619459Y335017D01*
G01X620609Y335494D02*
Y348615D01*
G01X619459Y335017D02*
Y348138D01*
G01X636693Y323925D02*
X630551D01*
G01X636693Y325075D02*
X631028D01*
G01X630551Y323925D02*
X619459Y335017D01*
G01X631028Y325075D02*
X620609Y335494D01*
G01X619459Y335017D02*
Y348138D01*
G01X620609Y335494D02*
Y348615D01*
G01X637150Y305075D02*
X633926D01*
G01X637150Y303925D02*
X633449D01*
G01X633926Y305075D02*
X633476Y305525D01*
G01X633449Y303925D02*
X632326Y305048D01*
G01X633476Y305525D02*
Y311567D01*
G01X632326Y305048D02*
Y311090D01*
G01X633476Y311567D02*
X632353Y312690D01*
G01X632326Y311090D02*
X631876Y311540D01*
G01X632353Y312690D02*
X621846D01*
G01X631876Y311540D02*
X626323D01*
G01X632353Y312690D02*
X621846D01*
G01X623673Y311540D02*
X622323D01*
G01X621846Y312690D02*
X614621Y305465D01*
G01X622323Y311540D02*
X620755Y309972D01*
G01X621846Y312690D02*
X614621Y305465D01*
G01X618881Y308098D02*
X617926Y307143D01*
G01X621846Y312690D02*
X614621Y305465D01*
G01X616053Y305270D02*
X615098Y304315D01*
G01X613077Y307515D02*
X614240Y308678D01*
G01X612600Y308665D02*
X613090Y309155D01*
G01X614240Y308678D02*
Y310650D01*
G01X613090Y309155D02*
Y310173D01*
G01X614240Y310650D02*
X613025Y311865D01*
G01X613090Y310173D02*
X612548Y310715D01*
G01X619791Y313915D02*
X620914Y315038D01*
G01X619314Y315065D02*
X619764Y315515D01*
G01X620914Y315038D02*
Y317049D01*
G01X619764Y315515D02*
Y316572D01*
G01X620914Y317049D02*
X619698Y318265D01*
G01X619764Y316572D02*
X619221Y317115D01*
G01X613015Y320315D02*
X614217Y321517D01*
G01X612538Y321465D02*
X613067Y321994D01*
G01X614217Y321517D02*
Y323542D01*
G01X613067Y321994D02*
Y323065D01*
G01X614217Y323542D02*
X613094Y324665D01*
G01X613067Y323065D02*
X612617Y323515D01*
G01X637150Y303925D02*
X633449D01*
G01X637150Y305075D02*
X633926D01*
G01X633449Y303925D02*
X632326Y305048D01*
G01X633926Y305075D02*
X633476Y305525D01*
G01X632326Y305048D02*
Y311090D01*
G01X633476Y305525D02*
Y311567D01*
G01X632326Y311090D02*
X631876Y311540D01*
G01X633476Y311567D02*
X632353Y312690D01*
G01X631876Y311540D02*
X626323D01*
G01X623673D02*
X622323D01*
G01X632353Y312690D02*
X621846D01*
G01X622323Y311540D02*
X620755Y309972D01*
G01X618881Y308098D02*
X617926Y307143D01*
G01X616053Y305270D02*
X615098Y304315D01*
G01X621846Y312690D02*
X614621Y305465D01*
G01X612600Y308665D02*
X613090Y309155D01*
G01X613077Y307515D02*
X614240Y308678D01*
G01X613090Y309155D02*
Y310173D01*
G01X614240Y308678D02*
Y310650D01*
G01X613090Y310173D02*
X612548Y310715D01*
G01X614240Y310650D02*
X613025Y311865D01*
G01X619314Y315065D02*
X619764Y315515D01*
G01X619791Y313915D02*
X620914Y315038D01*
G01X619764Y315515D02*
Y316572D01*
G01X620914Y315038D02*
Y317049D01*
G01X619764Y316572D02*
X619221Y317115D01*
G01X620914Y317049D02*
X619698Y318265D01*
G01X612538Y321465D02*
X613067Y321994D01*
G01X613015Y320315D02*
X614217Y321517D01*
G01X613067Y321994D02*
Y323065D01*
G01X614217Y321517D02*
Y323542D01*
G01X613067Y323065D02*
X612617Y323515D01*
G01X614217Y323542D02*
X613094Y324665D01*
G01X625300Y384777D02*
Y337000D01*
G01X624150Y384300D02*
Y336523D01*
G01X625300Y337000D02*
X625750Y336550D01*
G01X624150Y336523D02*
X625273Y335400D01*
G01X625750Y336550D02*
X626900D01*
G01X625273Y335400D02*
X627377D01*
G01X626900Y336550D02*
X627350Y337000D01*
G01X627377Y335400D02*
X628500Y336523D01*
G01X627350Y337000D02*
Y383235D01*
G01X628500Y336523D02*
Y382758D01*
G01X632400Y383081D02*
Y336250D01*
G01X631250Y382604D02*
Y335773D01*
G01X632400Y336250D02*
X633250Y335400D01*
G01X631250Y335773D02*
X632773Y334250D01*
G01X633250Y335400D02*
X637101D01*
G01X632773Y334250D02*
X637201D01*
G01X608324Y347253D02*
X609447Y346130D01*
G01X607847Y346103D02*
X608297Y345653D01*
G01X609447Y346130D02*
Y344026D01*
G01X608297Y345653D02*
Y344503D01*
G01X609447Y344026D02*
X608324Y342903D01*
G01X608297Y344503D02*
X607847Y344053D01*
G01X611497Y346130D02*
X612620Y347253D01*
G01X612647Y345653D02*
X613097Y346103D01*
G01X612620Y347253D02*
X615993D01*
G01X613097Y346103D02*
X615516D01*
G01X615993Y347253D02*
X617253Y345993D01*
G01X615516Y346103D02*
X616103Y345516D01*
G01X607847Y346103D02*
X608297Y345653D01*
G01X608324Y347253D02*
X609447Y346130D01*
G01X608297Y345653D02*
Y344503D01*
G01X609447Y346130D02*
Y344026D01*
G01X608297Y344503D02*
X607847Y344053D01*
G01X609447Y344026D02*
X608324Y342903D01*
G01X612647Y345653D02*
X613097Y346103D01*
G01X611497Y346130D02*
X612620Y347253D01*
G01X613097Y346103D02*
X615516D01*
G01X612620Y347253D02*
X615993D01*
G01X615516Y346103D02*
X616103Y345516D01*
G01X615993Y347253D02*
X617253Y345993D01*
G01X621199Y412423D02*
X641189Y392433D01*
G01X620722Y411273D02*
X640037Y391958D01*
G01X641189Y392433D02*
Y390845D01*
G01X640037Y391958D02*
Y391320D01*
G01X641189Y390845D02*
X639698Y389354D01*
G01X640037Y391320D02*
X639223Y390506D01*
G01X641189Y390845D02*
X639698Y389354D01*
G01D02*
X638110D01*
G01X639223Y390506D02*
X638585D01*
G01X638110Y389354D02*
X619981Y407483D01*
G01X638585Y390506D02*
X620458Y408633D01*
G01X618369Y406195D02*
X637454Y387110D01*
G01X617219Y405718D02*
X636304Y386633D01*
G01X637454Y387110D02*
Y352200D01*
G01X636304Y386633D02*
Y351723D01*
G01X637454Y352200D02*
X637904Y351750D01*
G01X636304Y351723D02*
X637427Y350600D01*
G01X637904Y351750D02*
X640300D01*
G01X637427Y350600D02*
X640777D01*
G01X640300Y351750D02*
X640750Y352200D01*
G01X640777Y350600D02*
X641900Y351723D01*
G01X640750Y352200D02*
Y384127D01*
G01X641900Y351723D02*
Y383650D01*
G01X640750Y384127D02*
X641873Y385250D01*
G01X641900Y383650D02*
X642350Y384100D01*
G01X641873Y385250D02*
X644177D01*
G01X642350Y384100D02*
X643700D01*
G01X644177Y385250D02*
X645300Y384127D01*
G01X643700Y384100D02*
X644150Y383650D01*
G01X645300Y384127D02*
Y353750D01*
G01X644150Y383650D02*
Y353273D01*
G01X645300Y353750D02*
X645750Y353300D01*
G01X644150Y353273D02*
X645273Y352150D01*
G01X645750Y353300D02*
X646800D01*
G01X645273Y352150D02*
X647277D01*
G01X646800Y353300D02*
X647250Y353750D01*
G01X647277Y352150D02*
X648400Y353273D01*
G01X647250Y353750D02*
Y383603D01*
G01X648400Y353273D02*
Y383126D01*
G01X647250Y383603D02*
X648595Y384948D01*
G01X648400Y383126D02*
X649072Y383798D01*
G01X648595Y384948D02*
X650879D01*
G01X649072Y383798D02*
X650402D01*
G01X650879Y384948D02*
X652275Y383552D01*
G01X650402Y383798D02*
X651125Y383075D01*
G01X652275Y383552D02*
Y353125D01*
G01X651125Y383075D02*
Y353137D01*
G01X620722Y411273D02*
X640037Y391958D01*
G01X621199Y412423D02*
X641189Y392433D01*
G01X640037Y391958D02*
Y391320D01*
G01X641189Y392433D02*
Y390845D01*
G01X640037Y391320D02*
X639223Y390506D01*
G01D02*
X638585D01*
G01X641189Y390845D02*
X639698Y389354D01*
G01X639223Y390506D02*
X638585D01*
G01X639698Y389354D02*
X638110D01*
G01X638585Y390506D02*
X620458Y408633D01*
G01X638110Y389354D02*
X619981Y407483D01*
G01X638585Y390506D02*
X620458Y408633D01*
G01X617219Y405718D02*
X636304Y386633D01*
G01X618369Y406195D02*
X637454Y387110D01*
G01X636304Y386633D02*
Y351723D01*
G01X637454Y387110D02*
Y352200D01*
G01X636304Y351723D02*
X637427Y350600D01*
G01X637454Y352200D02*
X637904Y351750D01*
G01X637427Y350600D02*
X640777D01*
G01X637904Y351750D02*
X640300D01*
G01X640777Y350600D02*
X641900Y351723D01*
G01X640300Y351750D02*
X640750Y352200D01*
G01X641900Y351723D02*
Y383650D01*
G01X640750Y352200D02*
Y384127D01*
G01X641900Y383650D02*
X642350Y384100D01*
G01X640750Y384127D02*
X641873Y385250D01*
G01X642350Y384100D02*
X643700D01*
G01X641873Y385250D02*
X644177D01*
G01X643700Y384100D02*
X644150Y383650D01*
G01X644177Y385250D02*
X645300Y384127D01*
G01X644150Y383650D02*
Y353273D01*
G01X645300Y384127D02*
Y353750D01*
G01X644150Y353273D02*
X645273Y352150D01*
G01X645300Y353750D02*
X645750Y353300D01*
G01X645273Y352150D02*
X647277D01*
G01X645750Y353300D02*
X646800D01*
G01X647277Y352150D02*
X648400Y353273D01*
G01X646800Y353300D02*
X647250Y353750D01*
G01X648400Y353273D02*
Y383126D01*
G01X647250Y353750D02*
Y383603D01*
G01X648400Y383126D02*
X649072Y383798D01*
G01X647250Y383603D02*
X648595Y384948D01*
G01X649072Y383798D02*
X650402D01*
G01X648595Y384948D02*
X650879D01*
G01X650402Y383798D02*
X651125Y383075D01*
G01X650879Y384948D02*
X652275Y383552D01*
G01X651125Y383075D02*
Y353137D01*
G01X652275Y383552D02*
Y353125D01*
G01X609602Y398811D02*
X610753Y399962D01*
G01X609125Y399961D02*
X609603Y400439D01*
G01X610753Y399962D02*
Y402038D01*
G01X609603Y400439D02*
Y401561D01*
G01X610753Y402038D02*
X609630Y403161D01*
G01X609603Y401561D02*
X609153Y402011D01*
G01X612296Y405211D02*
X627884Y389623D01*
G01X612773Y406361D02*
X629034Y390100D01*
G01X627884Y389623D02*
Y388945D01*
G01X629034Y390100D02*
Y388468D01*
G01X627884Y388945D02*
X627110Y388171D01*
G01D02*
X626433D01*
G01X629034Y388468D02*
X627586Y387020D01*
G01X627110Y388171D02*
X626433D01*
G01X627586Y387020D02*
X625957D01*
G01X626433Y388171D02*
X616802Y397802D01*
G01X625957Y387020D02*
X616325Y396652D01*
G01X616802Y397802D02*
X615100D01*
G01D02*
X613669Y396371D01*
G01X616325Y396652D02*
X615577D01*
G01X615100Y397802D02*
X613669Y396371D01*
G01X615577Y396652D02*
X614819Y395894D01*
G01X613669Y396371D02*
Y394781D01*
G01X614819Y395894D02*
Y395258D01*
G01X613669Y394781D02*
X624150Y384300D01*
G01X614819Y395258D02*
X625300Y384777D01*
G01X628500Y382758D02*
X628950Y383208D01*
G01X627350Y383235D02*
X628473Y384358D01*
G01X628950Y383208D02*
X630646D01*
G01X628473Y384358D02*
X631123D01*
G01X628950Y383208D02*
X630646D01*
G01D02*
X631250Y382604D01*
G01X631123Y384358D02*
X632400Y383081D01*
G01X662369Y351656D02*
Y353717D01*
G01X661219Y351980D02*
Y353240D01*
G01X662369Y353717D02*
X661090Y354996D01*
G01X661219Y353240D02*
X660613Y353846D01*
G01X661090Y354996D02*
X658097D01*
G01X660613Y353846D02*
X658574D01*
G01X658097Y354996D02*
X656450Y353349D01*
G01X658574Y353846D02*
X657600Y352872D01*
G01X656450Y353349D02*
Y350704D01*
G01X657600Y352872D02*
Y350227D01*
G01X656450Y350704D02*
X655850Y350104D01*
G01X657600Y350227D02*
X657000Y349627D01*
G01X655850Y350104D02*
Y347078D01*
G01X657000Y349627D02*
Y346601D01*
G01X655850Y347078D02*
X654822Y346050D01*
G01X657000Y346601D02*
X655299Y344900D01*
G01X654822Y346050D02*
X645451D01*
G01X655299Y344900D02*
X645928D01*
G01X645451Y346050D02*
X641220Y341819D01*
G01X661219Y351980D02*
Y353240D01*
G01X662369Y351656D02*
Y353717D01*
G01X661219Y353240D02*
X660613Y353846D01*
G01X662369Y353717D02*
X661090Y354996D01*
G01X660613Y353846D02*
X658574D01*
G01X661090Y354996D02*
X658097D01*
G01X658574Y353846D02*
X657600Y352872D01*
G01X658097Y354996D02*
X656450Y353349D01*
G01X657600Y352872D02*
Y350227D01*
G01X656450Y353349D02*
Y350704D01*
G01X657600Y350227D02*
X657000Y349627D01*
G01X656450Y350704D02*
X655850Y350104D01*
G01X657000Y349627D02*
Y346601D01*
G01X655850Y350104D02*
Y347078D01*
G01X657000Y346601D02*
X655299Y344900D01*
G01X655850Y347078D02*
X654822Y346050D01*
G01X655299Y344900D02*
X645928D01*
G01X654822Y346050D02*
X645451D01*
G01D02*
X641220Y341819D01*
G01X620609Y348615D02*
X618985Y350239D01*
G01X619459Y348138D02*
X618508Y349089D01*
G01X618845Y352289D02*
X620048Y353492D01*
G01X618368Y353439D02*
X618898Y353969D01*
G01X620048Y353492D02*
Y355503D01*
G01X618898Y353969D02*
Y355026D01*
G01X620048Y355503D02*
X618912Y356639D01*
G01X618898Y355026D02*
X618435Y355489D01*
G01X618894Y358689D02*
X620097Y359892D01*
G01X618417Y359839D02*
X618947Y360369D01*
G01X620097Y359892D02*
Y361916D01*
G01X618947Y360369D02*
Y361439D01*
G01X620097Y361916D02*
X618974Y363039D01*
G01X618947Y361439D02*
X618497Y361889D01*
G01X618611Y365089D02*
X619734Y366212D01*
G01X618134Y366239D02*
X618584Y366689D01*
G01X619734Y366212D02*
Y368253D01*
G01X618584Y366689D02*
Y367776D01*
G01X619734Y368253D02*
X618548Y369439D01*
G01X618584Y367776D02*
X618071Y368289D01*
G01X618974Y371489D02*
X620097Y372612D01*
G01X618497Y372639D02*
X618947Y373089D01*
G01X620097Y372612D02*
Y374582D01*
G01X618947Y373089D02*
Y374105D01*
G01X620097Y374582D02*
X618840Y375839D01*
G01X618947Y374105D02*
X618363Y374689D01*
G01X619459Y348138D02*
X618508Y349089D01*
G01X620609Y348615D02*
X618985Y350239D01*
G01X618368Y353439D02*
X618898Y353969D01*
G01X618845Y352289D02*
X620048Y353492D01*
G01X618898Y353969D02*
Y355026D01*
G01X620048Y353492D02*
Y355503D01*
G01X618898Y355026D02*
X618435Y355489D01*
G01X620048Y355503D02*
X618912Y356639D01*
G01X618417Y359839D02*
X618947Y360369D01*
G01X618894Y358689D02*
X620097Y359892D01*
G01X618947Y360369D02*
Y361439D01*
G01X620097Y359892D02*
Y361916D01*
G01X618947Y361439D02*
X618497Y361889D01*
G01X620097Y361916D02*
X618974Y363039D01*
G01X618134Y366239D02*
X618584Y366689D01*
G01X618611Y365089D02*
X619734Y366212D01*
G01X618584Y366689D02*
Y367776D01*
G01X619734Y366212D02*
Y368253D01*
G01X618584Y367776D02*
X618071Y368289D01*
G01X619734Y368253D02*
X618548Y369439D01*
G01X618497Y372639D02*
X618947Y373089D01*
G01X618974Y371489D02*
X620097Y372612D01*
G01X618947Y373089D02*
Y374105D01*
G01X620097Y372612D02*
Y374582D01*
G01X618947Y374105D02*
X618363Y374689D01*
G01X620097Y374582D02*
X618840Y375839D01*
G01X609125Y399961D02*
X609603Y400439D01*
G01X609602Y398811D02*
X610753Y399962D01*
G01X609603Y400439D02*
Y401561D01*
G01X610753Y399962D02*
Y402038D01*
G01X609603Y401561D02*
X609153Y402011D01*
G01X610753Y402038D02*
X609630Y403161D01*
G01X612773Y406361D02*
X629034Y390100D01*
G01X612296Y405211D02*
X627884Y389623D01*
G01X629034Y390100D02*
Y388468D01*
G01X627884Y389623D02*
Y388945D01*
G01X629034Y388468D02*
X627586Y387020D01*
G01X627884Y388945D02*
X627110Y388171D01*
G01X629034Y388468D02*
X627586Y387020D01*
G01D02*
X625957D01*
G01X627110Y388171D02*
X626433D01*
G01X625957Y387020D02*
X616325Y396652D01*
G01X626433Y388171D02*
X616802Y397802D01*
G01X616325Y396652D02*
X615577D01*
G01X616802Y397802D02*
X615100D01*
G01X616325Y396652D02*
X615577D01*
G01D02*
X614819Y395894D01*
G01X615100Y397802D02*
X613669Y396371D01*
G01X614819Y395894D02*
Y395258D01*
G01X613669Y396371D02*
Y394781D01*
G01X614819Y395258D02*
X625300Y384777D01*
G01X613669Y394781D02*
X624150Y384300D01*
G01X627350Y383235D02*
X628473Y384358D01*
G01X628500Y382758D02*
X628950Y383208D01*
G01X628473Y384358D02*
X631123D01*
G01D02*
X632400Y383081D01*
G01X628950Y383208D02*
X630646D01*
G01X631123Y384358D02*
X632400Y383081D01*
G01X630646Y383208D02*
X631250Y382604D01*
G01X610386Y409917D02*
X610850Y410381D01*
G01X610863Y408767D02*
X612000Y409904D01*
G01X610850Y410381D02*
Y411517D01*
G01X612000Y409904D02*
Y411994D01*
G01X610850Y411517D02*
X610400Y411967D01*
G01X612000Y411994D02*
X610877Y413117D01*
G01X613649Y416317D02*
X617543Y412423D01*
G01X613172Y415167D02*
X617066Y411273D01*
G01X617543Y412423D02*
X621199D01*
G01X617066Y411273D02*
X620722D01*
G01X619981Y407483D02*
X619022D01*
G01X619981D02*
X619022D01*
G01X620458Y408633D02*
X618545D01*
G01X619981Y407483D02*
X619022D01*
G01D02*
X618369Y406830D01*
G01X618545Y408633D02*
X617219Y407307D01*
G01X618369Y406830D02*
Y406195D01*
G01X617219Y407307D02*
Y405718D01*
G01X610863Y408767D02*
X612000Y409904D01*
G01X610386Y409917D02*
X610850Y410381D01*
G01X612000Y409904D02*
Y411994D01*
G01X610850Y410381D02*
Y411517D01*
G01X612000Y411994D02*
X610877Y413117D01*
G01X610850Y411517D02*
X610400Y411967D01*
G01X613172Y415167D02*
X617066Y411273D01*
G01X613649Y416317D02*
X617543Y412423D01*
G01X617066Y411273D02*
X620722D01*
G01X617543Y412423D02*
X621199D01*
G01X620458Y408633D02*
X618545D01*
G01D02*
X617219Y407307D01*
G01X619981Y407483D02*
X619022D01*
G01X618545Y408633D02*
X617219Y407307D01*
G01X619022Y407483D02*
X618369Y406830D01*
G01X617219Y407307D02*
Y405718D01*
G01X618369Y406830D02*
Y406195D01*
G01X663828Y112201D02*
X666550Y114923D01*
G01X663351Y113351D02*
X665400Y115400D01*
G01X666550Y114923D02*
Y134123D01*
G01X665400Y115400D02*
Y118600D01*
G01X666550Y114923D02*
Y134123D01*
G01X665400Y121250D02*
Y122600D01*
G01X666550Y114923D02*
Y134123D01*
G01X665400Y125250D02*
Y126600D01*
G01X666550Y114923D02*
Y134123D01*
G01X665400Y129250D02*
Y130600D01*
G01X666550Y114923D02*
Y134123D01*
G01X665400Y133250D02*
Y134600D01*
G01X666550Y134123D02*
X673899Y141472D01*
G01X665400Y134600D02*
X672749Y141949D01*
G01X673899Y141472D02*
Y146777D01*
G01X672749Y141949D02*
Y146300D01*
G01X673899Y146777D02*
X672164Y148512D01*
G01X672749Y146300D02*
X671687Y147362D01*
G01X672164Y148512D02*
X670838D01*
G01X671687Y147362D02*
X671050D01*
G01X663351Y113351D02*
X665400Y115400D01*
G01X663828Y112201D02*
X666550Y114923D01*
G01X665400Y115400D02*
Y118600D01*
G01Y121250D02*
Y122600D01*
G01Y125250D02*
Y126600D01*
G01Y129250D02*
Y130600D01*
G01Y133250D02*
Y134600D01*
G01X666550Y114923D02*
Y134123D01*
G01X665400Y134600D02*
X672749Y141949D01*
G01X666550Y134123D02*
X673899Y141472D01*
G01X672749Y141949D02*
Y146300D01*
G01X673899Y141472D02*
Y146777D01*
G01X672749Y146300D02*
X671687Y147362D01*
G01X673899Y146777D02*
X672164Y148512D01*
G01X671687Y147362D02*
X671050D01*
G01X672164Y148512D02*
X670838D01*
G01X668549Y297851D02*
Y296151D01*
G01X669699Y297299D02*
Y296628D01*
G01X668549Y296151D02*
X669987Y294713D01*
G01X669699Y296628D02*
X670464Y295863D01*
G01X669987Y294713D02*
X673360D01*
G01X670464Y295863D02*
X673837D01*
G01X673360Y294713D02*
X674423Y293650D01*
G01X673837Y295863D02*
X674900Y294800D01*
G01X674423Y293650D02*
X685601D01*
G01X674900Y294800D02*
X685124D01*
G01X685601Y293650D02*
X689381Y297430D01*
G01X685124Y294800D02*
X688406Y298082D01*
G01X689381Y297430D02*
X695554Y312321D01*
G01X688406Y298082D02*
X694578Y312973D01*
G01X695554Y312321D02*
X701555Y318323D01*
G01X694578Y312973D02*
X700579Y318975D01*
G01X701555Y318323D02*
X710669Y340324D01*
G01X700579Y318975D02*
X709519Y340553D01*
G01X710669Y340324D02*
Y353593D01*
G01X709519Y340553D02*
Y353719D01*
G01X669699Y297299D02*
Y296628D01*
G01X668549Y297851D02*
Y296151D01*
G01X669699Y296628D02*
X670464Y295863D01*
G01X668549Y296151D02*
X669987Y294713D01*
G01X670464Y295863D02*
X673837D01*
G01X669987Y294713D02*
X673360D01*
G01X673837Y295863D02*
X674900Y294800D01*
G01X673360Y294713D02*
X674423Y293650D01*
G01X674900Y294800D02*
X685124D01*
G01X674423Y293650D02*
X685601D01*
G01X685124Y294800D02*
X688406Y298082D01*
G01X685601Y293650D02*
X689381Y297430D01*
G01X688406Y298082D02*
X694578Y312973D01*
G01X689381Y297430D02*
X695554Y312321D01*
G01X694578Y312973D02*
X700579Y318975D01*
G01X695554Y312321D02*
X701555Y318323D01*
G01X700579Y318975D02*
X709519Y340553D01*
G01X701555Y318323D02*
X710669Y340324D01*
G01X709519Y340553D02*
Y353719D01*
G01X710669Y340324D02*
Y353593D01*
G01D02*
X717367Y383808D01*
G01X709519Y353719D02*
X716217Y383934D01*
G01X717367Y383808D02*
Y410630D01*
G01X716217Y383934D02*
Y411107D01*
G01X709519Y353719D02*
X716217Y383934D01*
G01X710669Y353593D02*
X717367Y383808D01*
G01X716217Y383934D02*
Y411107D01*
G01X717367Y383808D02*
Y410630D01*
G01D02*
X718138Y411401D01*
G01X716217Y411107D02*
X716988Y411878D01*
G01X718138Y411401D02*
Y422335D01*
G01X716988Y411878D02*
Y422473D01*
G01X718138Y422335D02*
X734341Y489101D01*
G01X716988Y422473D02*
X717318Y423834D01*
G01X718138Y422335D02*
X734341Y489101D01*
G01X717955Y426457D02*
X718285Y427818D01*
G01X718138Y422335D02*
X734341Y489101D01*
G01X718922Y430442D02*
X719252Y431802D01*
G01X718138Y422335D02*
X734341Y489101D01*
G01X719889Y434426D02*
X733191Y489239D01*
G01X716217Y411107D02*
X716988Y411878D01*
G01X717367Y410630D02*
X718138Y411401D01*
G01X716988Y411878D02*
Y422473D01*
G01X718138Y411401D02*
Y422335D01*
G01X716988Y422473D02*
X717318Y423834D01*
G01X717955Y426457D02*
X718285Y427818D01*
G01X718922Y430442D02*
X719252Y431802D01*
G01X719889Y434426D02*
X733191Y489239D01*
G01X718138Y422335D02*
X734341Y489101D01*
G01D02*
Y501063D01*
G01X733191Y489239D02*
Y501178D01*
G01X734341Y501063D02*
X736336Y510962D01*
G01X733191Y501178D02*
X735186Y511077D01*
G01X736336Y510962D02*
Y517577D01*
G01X735186Y511077D02*
Y518054D01*
G01X736336Y517577D02*
X740673Y521914D01*
G01X735186Y518054D02*
X740196Y523064D01*
G01X740673Y521914D02*
X746277D01*
G01X740196Y523064D02*
X746754D01*
G01X746277Y521914D02*
X748895Y519296D01*
G01X746754Y523064D02*
X749372Y520446D01*
G01X748895Y519296D02*
X752225D01*
G01X749372Y520446D02*
X752225D01*
G01X733191Y489239D02*
Y501178D01*
G01X734341Y489101D02*
Y501063D01*
G01X733191Y501178D02*
X735186Y511077D01*
G01X734341Y501063D02*
X736336Y510962D01*
G01X735186Y511077D02*
Y518054D01*
G01X736336Y510962D02*
Y517577D01*
G01X735186Y518054D02*
X740196Y523064D01*
G01X736336Y517577D02*
X740673Y521914D01*
G01X740196Y523064D02*
X746754D01*
G01X740673Y521914D02*
X746277D01*
G01X746754Y523064D02*
X749372Y520446D01*
G01X746277Y521914D02*
X748895Y519296D01*
G01X749372Y520446D02*
X752225D01*
G01X748895Y519296D02*
X752225D01*
G01X906382Y-46482D02*
X843409D01*
G01X905905Y-47632D02*
X843409D01*
G01X905905D02*
X843409D01*
G01X906382Y-46482D02*
X843409D01*
G01X1109042Y-49950D02*
X909850D01*
G01X1109042Y-51100D02*
X909373D01*
G01X909850Y-49950D02*
X906382Y-46482D01*
G01X909373Y-51100D02*
X905905Y-47632D01*
G01X1109042Y-51100D02*
X909373D01*
G01X1109042Y-49950D02*
X909850D01*
G01X909373Y-51100D02*
X905905Y-47632D01*
G01X909850Y-49950D02*
X906382Y-46482D01*
G01X1109142Y-42550D02*
X914500D01*
G01X1109142Y-43700D02*
X914500D01*
G01Y-42550D02*
G03Y-47400I0J-2425D01*
G01Y-43700D02*
G03Y-46250I0J-1275D01*
G01Y-47400D02*
X1109042D01*
G01X914500Y-46250D02*
X1109042D01*
G01X1109142Y-43700D02*
X914500D01*
G01X1109142Y-42550D02*
X914500D01*
G01Y-43700D02*
G03Y-46250I0J-1275D01*
G01Y-42550D02*
G03Y-47400I0J-2425D01*
G01Y-46250D02*
X1109042D01*
G01X914500Y-47400D02*
X1109042D01*
G01D02*
G02Y-49950I0J-1275D01*
G01Y-46250D02*
G02Y-51100I0J-2425D01*
G01Y-46250D02*
G02Y-51100I0J-2425D01*
G01Y-47400D02*
G02Y-49950I0J-1275D01*
G01X1240681Y137250D02*
X1177687Y200244D01*
G01X1240204Y136100D02*
X1177210Y199094D01*
G01X1177687Y200244D02*
X1173002D01*
G01X1177210Y199094D02*
X1172525D01*
G01X1173002Y200244D02*
X1169646Y203600D01*
G01X1172525Y199094D02*
X1169169Y202450D01*
G01X1169646Y203600D02*
X1160927D01*
G01X1169169Y202450D02*
X1160450D01*
G01X1160927Y203600D02*
X1159150Y205377D01*
G01X1160450Y202450D02*
X1158000Y204900D01*
G01X1159150Y205377D02*
Y206500D01*
G01X1158000Y204900D02*
Y206500D01*
G01X1240204Y136100D02*
X1177210Y199094D01*
G01X1240681Y137250D02*
X1177687Y200244D01*
G01X1177210Y199094D02*
X1172525D01*
G01X1177687Y200244D02*
X1173002D01*
G01X1172525Y199094D02*
X1169169Y202450D01*
G01X1173002Y200244D02*
X1169646Y203600D01*
G01X1169169Y202450D02*
X1160450D01*
G01X1169646Y203600D02*
X1160927D01*
G01X1160450Y202450D02*
X1158000Y204900D01*
G01X1160927Y203600D02*
X1159150Y205377D01*
G01X1158000Y204900D02*
Y206500D01*
G01X1159150Y205377D02*
Y206500D01*
G01X1217542Y199030D02*
X1239005Y181709D01*
G01X1239504Y182785D02*
X1218405Y199812D01*
G01X1215910Y201515D02*
X1217542Y199030D01*
G01X1218405Y199812D02*
X1216971Y201996D01*
G01X1214722Y205798D02*
X1215910Y201515D01*
G01X1216971Y201996D02*
X1215830Y206106D01*
G01X1214733Y208370D02*
X1214676Y205963D01*
G01X1215830Y206106D02*
X1215885Y208412D01*
G01X1213876Y217132D02*
X1214733Y208370D01*
G01X1215885Y208412D02*
X1215048Y216972D01*
G01X1215030Y220118D02*
X1213876Y217132D01*
G01X1215048Y216972D02*
X1216004Y219448D01*
G01X1219464Y200704D02*
X1218254Y202533D01*
G01D02*
X1217534Y205062D01*
G01D02*
X1217481Y207691D01*
G01Y207782D02*
X1217695Y209759D01*
G01D02*
X1222299Y214664D01*
G01X1215048Y216972D02*
X1216004Y219448D01*
G01X1215030Y220118D02*
X1213876Y217132D01*
G01X1215885Y208412D02*
X1215048Y216972D01*
G01X1213876Y217132D02*
X1214733Y208370D01*
G01X1215830Y206106D02*
X1215885Y208412D01*
G01X1214733Y208370D02*
X1214676Y205963D01*
G01X1216971Y201996D02*
X1215830Y206106D01*
G01X1214722Y205798D02*
X1215910Y201515D01*
G01X1218405Y199812D02*
X1216971Y201996D01*
G01X1215910Y201515D02*
X1217542Y199030D01*
G01X1239504Y182785D02*
X1218405Y199812D01*
G01X1217542Y199030D02*
X1239005Y181709D01*
G01X1193000Y197500D02*
X1195310Y195191D01*
G01D02*
X1196600Y193901D01*
G01Y193900D02*
X1205500Y185000D01*
G01X1192186Y196687D02*
X1204350Y184523D01*
G01X1205500Y185000D02*
Y181300D01*
G01X1204350Y184523D02*
Y180823D01*
G01X1205500Y181300D02*
X1235500Y151300D01*
G01X1204350Y180823D02*
X1229366Y155807D01*
G01X1205500Y181300D02*
X1235500Y151300D01*
G01X1205500Y181300D02*
X1235500Y151300D01*
G01X1192186Y196687D02*
X1204350Y184523D01*
G01X1193000Y197500D02*
X1195310Y195191D01*
G01X1192186Y196687D02*
X1204350Y184523D01*
G01X1195310Y195191D02*
X1196600Y193901D01*
G01X1192186Y196687D02*
X1204350Y184523D01*
G01X1196600Y193900D02*
X1205500Y185000D01*
G01X1204350Y184523D02*
Y180823D01*
G01X1205500Y185000D02*
Y181300D01*
G01X1204350Y180823D02*
X1229366Y155807D01*
G01X1205500Y181300D02*
X1235500Y151300D01*
G01X1219464Y200704D02*
X1218254Y202533D01*
G01D02*
X1217534Y205062D01*
G01D02*
X1217481Y207691D01*
G01Y207782D02*
X1217695Y209759D01*
G01D02*
X1222299Y214664D01*
G01X1217280Y222153D02*
X1215030Y220118D01*
G01X1216004Y219448D02*
X1218156Y221394D01*
G01X1220383Y226762D02*
X1217280Y222153D01*
G01X1218156Y221394D02*
X1221389Y226197D01*
G01X1212033Y259304D02*
X1221257Y250192D01*
G01X1222259Y250819D02*
X1213046Y259920D01*
G01X1210470Y264338D02*
X1212033Y259304D01*
G01X1213046Y259920D02*
X1211642Y264443D01*
G01X1211021Y268836D02*
X1210470Y264338D01*
G01X1211642Y264443D02*
X1212129Y268419D01*
G01X1214826Y274429D02*
X1211021Y268836D01*
G01X1212129Y268419D02*
X1215909Y273975D01*
G01X1215484Y277723D02*
X1214826Y274429D01*
G01X1215909Y273975D02*
X1216681Y277840D01*
G01X1211008Y288529D02*
X1215484Y277723D01*
G01X1216681Y277840D02*
X1211987Y289174D01*
G01X1221801Y271340D02*
X1213424Y291563D01*
G01X1220610Y271208D02*
X1212428Y290959D01*
G01X1216681Y277840D02*
X1211987Y289174D01*
G01X1211008Y288529D02*
X1215484Y277723D01*
G01X1215909Y273975D02*
X1216681Y277840D01*
G01X1215484Y277723D02*
X1214826Y274429D01*
G01X1212129Y268419D02*
X1215909Y273975D01*
G01X1214826Y274429D02*
X1211021Y268836D01*
G01X1211642Y264443D02*
X1212129Y268419D01*
G01X1211021Y268836D02*
X1210470Y264338D01*
G01X1213046Y259920D02*
X1211642Y264443D01*
G01X1210470Y264338D02*
X1212033Y259304D01*
G01X1222259Y250819D02*
X1213046Y259920D01*
G01X1212033Y259304D02*
X1221257Y250192D01*
G01X1218156Y221394D02*
X1221389Y226197D01*
G01X1220383Y226762D02*
X1217280Y222153D01*
G01X1216004Y219448D02*
X1218156Y221394D01*
G01X1217280Y222153D02*
X1215030Y220118D01*
G01X1220610Y271208D02*
X1212428Y290959D01*
G01X1221801Y271340D02*
X1213424Y291563D01*
G01X1207947Y291671D02*
X1211008Y288529D01*
G01X1211987Y289174D02*
X1208433Y292821D01*
G01X1206867Y291671D02*
X1207947D01*
G01X1208433Y292821D02*
X1206867D01*
G01X1213424Y291563D02*
X1209102Y296721D01*
G01X1212428Y290959D02*
X1208565Y295571D01*
G01X1209102Y296721D02*
X1207738D01*
G01X1208565Y295571D02*
X1207738D01*
G01X1208433Y292821D02*
X1206867D01*
G01Y291671D02*
X1207947D01*
G01X1211987Y289174D02*
X1208433Y292821D01*
G01X1207947Y291671D02*
X1211008Y288529D01*
G01X1212428Y290959D02*
X1208565Y295571D01*
G01X1213424Y291563D02*
X1209102Y296721D01*
G01X1208565Y295571D02*
X1207738D01*
G01X1209102Y296721D02*
X1207738D01*
G01X1222298Y297636D02*
X1215875Y305463D01*
G01X1223296Y298234D02*
X1216708Y306263D01*
G01X1215875Y305463D02*
X1211027Y309860D01*
G01X1216708Y306263D02*
X1211737Y310770D01*
G01X1211027Y309860D02*
X1209797Y310682D01*
G01D02*
X1208963D01*
G01X1211737Y310770D02*
X1210146Y311832D01*
G01X1209797Y310682D02*
X1208963D01*
G01X1210146Y311832D02*
X1208963D01*
G01X1220441Y295524D02*
X1212993Y304599D01*
G01X1221439Y296122D02*
X1213775Y305460D01*
G01X1212993Y304599D02*
X1208994Y307272D01*
G01X1213775Y305460D02*
X1209343Y308422D01*
G01X1208994Y307272D02*
X1206987D01*
G01X1209343Y308422D02*
X1206987D01*
G01X1233884Y255778D02*
X1217928Y294306D01*
G01D02*
X1211215Y301549D01*
G01X1218912Y294937D02*
X1211918Y302484D01*
G01X1211215Y301549D02*
X1208250Y303050D01*
G01D02*
X1207171D01*
G01X1211918Y302484D02*
X1208525Y304200D01*
G01X1208250Y303050D02*
X1207171D01*
G01X1208525Y304200D02*
X1207171D01*
G01X1232336Y255984D02*
X1217578Y291611D01*
G01X1232336Y255984D02*
X1217578Y291611D01*
G01X1230937Y256356D02*
X1216588Y290993D01*
G01X1217578Y291611D02*
X1210447Y299698D01*
G01X1216588Y290993D02*
X1209710Y298793D01*
G01X1210447Y299698D02*
X1208690Y300700D01*
G01X1209710Y298793D02*
X1208384Y299550D01*
G01X1210447Y299698D02*
X1208690Y300700D01*
G01D02*
X1208025D01*
G01X1208384Y299550D02*
X1208025D01*
G01X1212087Y339800D02*
X1216063D01*
G01X1212087Y340950D02*
X1216421D01*
G01X1216063Y339800D02*
X1219120Y337699D01*
G01X1216421Y340950D02*
X1219950Y338524D01*
G01X1216689Y336027D02*
X1217869Y335132D01*
G01X1217384Y336944D02*
X1218723Y335928D01*
G01X1217869Y335132D02*
X1219704Y332314D01*
G01X1214644Y333970D02*
X1215153Y333599D01*
G01X1215321Y334900D02*
X1215903Y334477D01*
G01X1215153Y333599D02*
X1217613Y331140D01*
G01X1215903Y334477D02*
X1218514Y331866D01*
G01X1217613Y331140D02*
X1218516Y329734D01*
G01X1218514Y331866D02*
X1219300Y330642D01*
G01X1217613Y331140D02*
X1218516Y329734D01*
G01D02*
X1222176Y326073D01*
G01X1207232Y329512D02*
X1213563D01*
G01X1207232Y330662D02*
X1213912D01*
G01X1213563Y329512D02*
X1217284Y327026D01*
G01X1213912Y330662D02*
X1217994Y327935D01*
G01X1217284Y327026D02*
X1228108Y317214D01*
G01X1217994Y327935D02*
X1228950Y318005D01*
G01X1210188Y326850D02*
X1212665D01*
G01X1210188Y328000D02*
X1213015D01*
G01X1212665Y326850D02*
X1214018Y325945D01*
G01X1213015Y328000D02*
X1214727Y326855D01*
G01X1214018Y325945D02*
X1227347Y313864D01*
G01X1214727Y326855D02*
X1228176Y314667D01*
G01X1212122Y325204D02*
X1226771Y311928D01*
G01X1225932Y311136D02*
X1211678Y324054D01*
G01X1210883Y325204D02*
X1212122D01*
G01D02*
X1226771Y311928D01*
G01X1211678Y324054D02*
X1210883D01*
G01X1223415Y309679D02*
X1211015Y320920D01*
G01D02*
X1210096D01*
G01X1224251Y310476D02*
X1211459Y322070D01*
G01X1211015Y320920D02*
X1210096D01*
G01X1211459Y322070D02*
X1210096D01*
G01X1209321Y316462D02*
X1211888D01*
G01X1209321Y317612D02*
X1212333D01*
G01X1209321Y316462D02*
X1211888D01*
G01D02*
X1220672Y308503D01*
G01X1212333Y317612D02*
X1212661Y317315D01*
G01X1211888Y316462D02*
X1220672Y308503D01*
G01X1212661Y317314D02*
X1221510Y309298D01*
G01X1208852Y313702D02*
X1210761D01*
G01X1208852Y314852D02*
X1211111D01*
G01X1210761Y313702D02*
X1211796Y313010D01*
G01X1211111Y314852D02*
X1212506Y313919D01*
G01X1211796Y313010D02*
X1217098Y308204D01*
G01X1212506Y313919D02*
X1217934Y309000D01*
G01X1217098Y308204D02*
X1224332Y299387D01*
G01X1217934Y309000D02*
X1225330Y299985D01*
G01X1216795Y342300D02*
X1219300Y340655D01*
G01X1223296Y298234D02*
X1216708Y306263D01*
G01X1222298Y297636D02*
X1215875Y305463D01*
G01X1216708Y306263D02*
X1211737Y310770D01*
G01X1215875Y305463D02*
X1211027Y309860D01*
G01X1211737Y310770D02*
X1210146Y311832D01*
G01X1211027Y309860D02*
X1209797Y310682D01*
G01X1211737Y310770D02*
X1210146Y311832D01*
G01D02*
X1208963D01*
G01X1209797Y310682D02*
X1208963D01*
G01X1221439Y296122D02*
X1213775Y305460D01*
G01X1220441Y295524D02*
X1212993Y304599D01*
G01X1213775Y305460D02*
X1209343Y308422D01*
G01X1212993Y304599D02*
X1208994Y307272D01*
G01X1209343Y308422D02*
X1206987D01*
G01X1208994Y307272D02*
X1206987D01*
G01X1233884Y255778D02*
X1217928Y294306D01*
G01X1218912Y294937D02*
X1211918Y302484D01*
G01X1217928Y294306D02*
X1211215Y301549D01*
G01X1211918Y302484D02*
X1208525Y304200D01*
G01X1211215Y301549D02*
X1208250Y303050D01*
G01X1211918Y302484D02*
X1208525Y304200D01*
G01D02*
X1207171D01*
G01X1208250Y303050D02*
X1207171D01*
G01X1230937Y256356D02*
X1216588Y290993D01*
G01X1232336Y255984D02*
X1217578Y291611D01*
G01X1216588Y290993D02*
X1209710Y298793D01*
G01X1217578Y291611D02*
X1210447Y299698D01*
G01X1209710Y298793D02*
X1208384Y299550D01*
G01D02*
X1208025D01*
G01X1210447Y299698D02*
X1208690Y300700D01*
G01X1208384Y299550D02*
X1208025D01*
G01X1208690Y300700D02*
X1208025D01*
G01X1212087Y340950D02*
X1216421D01*
G01X1212087Y339800D02*
X1216063D01*
G01X1216421Y340950D02*
X1219950Y338524D01*
G01X1216063Y339800D02*
X1219120Y337699D01*
G01X1217384Y336944D02*
X1218723Y335928D01*
G01X1216689Y336027D02*
X1217869Y335132D01*
G01D02*
X1219704Y332314D01*
G01X1215321Y334900D02*
X1215903Y334477D01*
G01X1214644Y333970D02*
X1215153Y333599D01*
G01X1215903Y334477D02*
X1218514Y331866D01*
G01X1215153Y333599D02*
X1217613Y331140D01*
G01X1218514Y331866D02*
X1219300Y330642D01*
G01X1217613Y331140D02*
X1218516Y329734D01*
G01D02*
X1222176Y326073D01*
G01X1207232Y330662D02*
X1213912D01*
G01X1207232Y329512D02*
X1213563D01*
G01X1213912Y330662D02*
X1217994Y327935D01*
G01X1213563Y329512D02*
X1217284Y327026D01*
G01X1217994Y327935D02*
X1228950Y318005D01*
G01X1217284Y327026D02*
X1228108Y317214D01*
G01X1210188Y328000D02*
X1213015D01*
G01X1210188Y326850D02*
X1212665D01*
G01X1213015Y328000D02*
X1214727Y326855D01*
G01X1212665Y326850D02*
X1214018Y325945D01*
G01X1214727Y326855D02*
X1228176Y314667D01*
G01X1214018Y325945D02*
X1227347Y313864D01*
G01X1211678Y324054D02*
X1210883D01*
G01Y325204D02*
X1212122D01*
G01X1225932Y311136D02*
X1211678Y324054D01*
G01D02*
X1210883D01*
G01X1212122Y325204D02*
X1226771Y311928D01*
G01X1224251Y310476D02*
X1211459Y322070D01*
G01X1223415Y309679D02*
X1211015Y320920D01*
G01X1224251Y310476D02*
X1211459Y322070D01*
G01D02*
X1210096D01*
G01X1211015Y320920D02*
X1210096D01*
G01X1209321Y317612D02*
X1212333D01*
G01D02*
X1212661Y317315D01*
G01X1209321Y316462D02*
X1211888D01*
G01X1212333Y317612D02*
X1212661Y317315D01*
G01Y317314D02*
X1221510Y309298D01*
G01X1211888Y316462D02*
X1220672Y308503D01*
G01X1208852Y314852D02*
X1211111D01*
G01X1208852Y313702D02*
X1210761D01*
G01X1211111Y314852D02*
X1212506Y313919D01*
G01X1210761Y313702D02*
X1211796Y313010D01*
G01X1212506Y313919D02*
X1217934Y309000D01*
G01X1211796Y313010D02*
X1217098Y308204D01*
G01X1217934Y309000D02*
X1225330Y299985D01*
G01X1217098Y308204D02*
X1224332Y299387D01*
G01X1216795Y342300D02*
X1219300Y340655D01*
G01X1221789Y368583D02*
X1211455Y378917D01*
G01D02*
X1210059D01*
G01X1259619Y332382D02*
X1211932Y380067D01*
G01X1211455Y378917D02*
X1210059D01*
G01X1211932Y380067D02*
X1210059D01*
G01X1208187Y376000D02*
X1210800D01*
G01X1208187Y377150D02*
X1211277D01*
G01X1210800Y376000D02*
X1256419Y330382D01*
G01X1211277Y377150D02*
X1257395Y331034D01*
G01X1208520Y366961D02*
X1213790Y364779D01*
G01X1208959Y368024D02*
X1214335Y365799D01*
G01X1213790Y364779D02*
X1216817Y362755D01*
G01X1214335Y365799D02*
X1217551Y363649D01*
G01X1216817Y362755D02*
X1252016Y327556D01*
G01X1217551Y363649D02*
X1252992Y328208D01*
G01X1259619Y332382D02*
X1211932Y380067D01*
G01X1259619Y332382D02*
X1211932Y380067D01*
G01X1221789Y368583D02*
X1211455Y378917D01*
G01X1259619Y332382D02*
X1211932Y380067D01*
G01D02*
X1210059D01*
G01X1211455Y378917D02*
X1210059D01*
G01X1208187Y377150D02*
X1211277D01*
G01X1208187Y376000D02*
X1210800D01*
G01X1211277Y377150D02*
X1257395Y331034D01*
G01X1210800Y376000D02*
X1256419Y330382D01*
G01X1208959Y368024D02*
X1214335Y365799D01*
G01X1208520Y366961D02*
X1213790Y364779D01*
G01X1214335Y365799D02*
X1217551Y363649D01*
G01X1213790Y364779D02*
X1216817Y362755D01*
G01X1217551Y363649D02*
X1252992Y328208D01*
G01X1216817Y362755D02*
X1252016Y327556D01*
G01X1213724Y343450D02*
X1217139D01*
G01X1213724Y342300D02*
X1216795D01*
G01X1217139Y343450D02*
X1222366Y340020D01*
G01X1217139Y343450D02*
X1222366Y340020D01*
G01X1213724Y342300D02*
X1216795D01*
G01X1213724Y343450D02*
X1217139D01*
G01D02*
X1222366Y340020D01*
G01X1211093Y371622D02*
X1211550D01*
G01X1211093Y372772D02*
X1212027D01*
G01X1211093Y371622D02*
X1211550D01*
G01D02*
X1254195Y328979D01*
G01X1212027Y372772D02*
X1255171Y329631D01*
G01X1220969Y345116D02*
X1216876Y346556D01*
G01X1220457Y344077D02*
X1216494Y345471D01*
G01X1222801Y345999D02*
X1213744Y349750D01*
G01X1223453Y346975D02*
X1213973Y350900D01*
G01X1213744Y349750D02*
X1211108D01*
G01X1213973Y350900D02*
X1211585D01*
G01X1211108Y349750D02*
X1206916Y353941D01*
G01X1211585Y350900D02*
X1207730Y354755D01*
G01X1215944Y358084D02*
X1248471Y325557D01*
G01X1215130Y357270D02*
X1247495Y324905D01*
G01X1215327Y360673D02*
X1249847Y326153D01*
G01X1250823Y326805D02*
X1215979Y361649D01*
G01X1210387Y362300D02*
X1211400D01*
G01D02*
X1215327Y360673D01*
G01X1215979Y361649D02*
X1211629Y363450D01*
G01X1210387Y362300D02*
X1211400D01*
G01X1211629Y363450D02*
X1210387D01*
G01X1211093Y372772D02*
X1212027D01*
G01D02*
X1255171Y329631D01*
G01X1211093Y371622D02*
X1211550D01*
G01X1212027Y372772D02*
X1255171Y329631D01*
G01X1211550Y371622D02*
X1254195Y328979D01*
G01X1220457Y344077D02*
X1216494Y345471D01*
G01X1220969Y345116D02*
X1216876Y346556D01*
G01X1223453Y346975D02*
X1213973Y350900D01*
G01X1222801Y345999D02*
X1213744Y349750D01*
G01X1213973Y350900D02*
X1211585D01*
G01X1213744Y349750D02*
X1211108D01*
G01X1211585Y350900D02*
X1207730Y354755D01*
G01X1211108Y349750D02*
X1206916Y353941D01*
G01X1215130Y357270D02*
X1247495Y324905D01*
G01X1215944Y358084D02*
X1248471Y325557D01*
G01X1215979Y361649D02*
X1211629Y363450D01*
G01D02*
X1210387D01*
G01Y362300D02*
X1211400D01*
G01X1215979Y361649D02*
X1211629Y363450D01*
G01X1211400Y362300D02*
X1215327Y360673D01*
G01X1250823Y326805D02*
X1215979Y361649D01*
G01X1215327Y360673D02*
X1249847Y326153D01*
G01X1273858Y343227D02*
X1210070Y406987D01*
G01X1274833Y343880D02*
X1210722Y407963D01*
G01X1271792Y341590D02*
X1210322Y403060D01*
G01X1272766Y342244D02*
X1210800Y404210D01*
G01X1222347Y387288D02*
X1210357Y399278D01*
G01X1222824Y388438D02*
X1210834Y400428D01*
G01X1210357Y399278D02*
X1205825D01*
G01X1210834Y400428D02*
X1205825D01*
G01X1267514Y338584D02*
X1210514Y395585D01*
G01X1268490Y339236D02*
X1210991Y396735D01*
G01X1210514Y395585D02*
X1207140D01*
G01X1210991Y396735D02*
X1207140D01*
G01X1211118Y390880D02*
X1209318D01*
G01Y392030D02*
X1211596D01*
G01X1265753Y336245D02*
X1211118Y390880D01*
G01D02*
X1209318D01*
G01X1211596Y392030D02*
X1266729Y336897D01*
G01X1263586Y334787D02*
X1210048Y388325D01*
G01D02*
X1209572D01*
G01X1264562Y335439D02*
X1210526Y389475D01*
G01X1210048Y388325D02*
X1209572D01*
G01X1210524Y389476D02*
X1209572D01*
G01X1261392Y333381D02*
X1211473Y383300D01*
G01X1262368Y334033D02*
X1211951Y384450D01*
G01X1211473Y383300D02*
X1210187D01*
G01X1211951Y384450D02*
X1210187D01*
G01X1211212Y409475D02*
X1276023Y344692D01*
G01X1274833Y343880D02*
X1210722Y407963D01*
G01X1273858Y343227D02*
X1210070Y406987D01*
G01X1272766Y342244D02*
X1210800Y404210D01*
G01X1271792Y341590D02*
X1210322Y403060D01*
G01X1222824Y388438D02*
X1210834Y400428D01*
G01X1222347Y387288D02*
X1210357Y399278D01*
G01X1210834Y400428D02*
X1205825D01*
G01X1210357Y399278D02*
X1205825D01*
G01X1268490Y339236D02*
X1210991Y396735D01*
G01X1267514Y338584D02*
X1210514Y395585D01*
G01X1210991Y396735D02*
X1207140D01*
G01X1210514Y395585D02*
X1207140D01*
G01X1211596Y392030D02*
X1266729Y336897D01*
G01X1265753Y336245D02*
X1211118Y390880D01*
G01X1209318Y392030D02*
X1211596D01*
G01D02*
X1266729Y336897D01*
G01X1211118Y390880D02*
X1209318D01*
G01X1264562Y335439D02*
X1210526Y389475D01*
G01X1263586Y334787D02*
X1210048Y388325D01*
G01X1264562Y335439D02*
X1210526Y389475D01*
G01X1210524Y389476D02*
X1209572D01*
G01X1210048Y388325D02*
X1209572D01*
G01X1262368Y334033D02*
X1211951Y384450D01*
G01X1261392Y333381D02*
X1211473Y383300D01*
G01X1211951Y384450D02*
X1210187D01*
G01X1211473Y383300D02*
X1210187D01*
G01X1211212Y409475D02*
X1276023Y344692D01*
G01X1210070Y406987D02*
X1208823Y407504D01*
G01X1206374Y408518D02*
X1203278Y409800D01*
G01X1210722Y407963D02*
X1203507Y410950D01*
G01X1203278Y409800D02*
X1198887D01*
G01X1203507Y410950D02*
X1198887D01*
G01X1210322Y403060D02*
X1208583D01*
G01X1210800Y404210D02*
X1208583D01*
G01X1184341Y411442D02*
X1188484D01*
G01X1184341Y410292D02*
X1188716D01*
G01X1188484Y411442D02*
X1193813Y413650D01*
G01X1188716Y410292D02*
X1194042Y412500D01*
G01X1193813Y413650D02*
X1204134D01*
G01X1194042Y412500D02*
X1203905D01*
G01X1204134Y413650D02*
X1211864Y410451D01*
G01X1203905Y412500D02*
X1211212Y409475D01*
G01X1211864Y410451D02*
X1276995Y345347D01*
G01X1210722Y407963D02*
X1203507Y410950D01*
G01X1210070Y406987D02*
X1208823Y407504D01*
G01X1210722Y407963D02*
X1203507Y410950D01*
G01X1206374Y408518D02*
X1203278Y409800D01*
G01X1203507Y410950D02*
X1198887D01*
G01X1203278Y409800D02*
X1198887D01*
G01X1210800Y404210D02*
X1208583D01*
G01X1210322Y403060D02*
X1208583D01*
G01X1184341Y410292D02*
X1188716D01*
G01X1184341Y411442D02*
X1188484D01*
G01X1188716Y410292D02*
X1194042Y412500D01*
G01X1188484Y411442D02*
X1193813Y413650D01*
G01X1194042Y412500D02*
X1203905D01*
G01X1193813Y413650D02*
X1204134D01*
G01X1203905Y412500D02*
X1211212Y409475D01*
G01X1204134Y413650D02*
X1211864Y410451D01*
G01D02*
X1276995Y345347D01*
G01X1251980Y114180D02*
X1254300Y116500D01*
G01X1250770Y115680D02*
X1251853D01*
G01X1251980Y114180D02*
X1254300Y116500D01*
G01X1251853Y115680D02*
X1253150Y116977D01*
G01X1254300Y116500D02*
Y120099D01*
G01X1253150Y116977D02*
Y120576D01*
G01X1254300Y120099D02*
X1257900Y123699D01*
G01X1253150Y120576D02*
X1256750Y124176D01*
G01X1257900Y123699D02*
Y129928D01*
G01X1256750Y124176D02*
Y125376D01*
G01X1257900Y123699D02*
Y129928D01*
G01X1256750Y127776D02*
Y129451D01*
G01X1257900Y129928D02*
X1250578Y137250D01*
G01X1256750Y129451D02*
X1250101Y136100D01*
G01X1250578Y137250D02*
X1240681D01*
G01X1250101Y136100D02*
X1240204D01*
G01X1250770Y115680D02*
X1251853D01*
G01D02*
X1253150Y116977D01*
G01X1251980Y114180D02*
X1254300Y116500D01*
G01X1253150Y116977D02*
Y120576D01*
G01X1254300Y116500D02*
Y120099D01*
G01X1253150Y120576D02*
X1256750Y124176D01*
G01X1254300Y120099D02*
X1257900Y123699D01*
G01X1256750Y124176D02*
Y125376D01*
G01Y127776D02*
Y129451D01*
G01X1257900Y123699D02*
Y129928D01*
G01X1256750Y129451D02*
X1250101Y136100D01*
G01X1257900Y129928D02*
X1250578Y137250D01*
G01X1250101Y136100D02*
X1240204D01*
G01X1250578Y137250D02*
X1240681D01*
G01X1231240Y153933D02*
X1232195Y152978D01*
G01X1234068Y151105D02*
X1235023Y150150D01*
G01X1235500Y151300D02*
X1243627D01*
G01X1235023Y150150D02*
X1243150D01*
G01X1243627Y151300D02*
X1251777Y143150D01*
G01X1243150Y150150D02*
X1251300Y142000D01*
G01X1251777Y143150D02*
X1253549D01*
G01X1251300Y142000D02*
X1253072D01*
G01X1253549Y143150D02*
X1259749Y136950D01*
G01X1253072Y142000D02*
X1256444Y138628D01*
G01X1253549Y143150D02*
X1259749Y136950D01*
G01X1258317Y136755D02*
X1259272Y135800D01*
G01X1259749Y136950D02*
X1265650D01*
G01X1259272Y135800D02*
X1265173D01*
G01X1265650Y136950D02*
X1268600Y134000D01*
G01X1265173Y135800D02*
X1267450Y133523D01*
G01X1268600Y134000D02*
Y129235D01*
G01X1267450Y133523D02*
Y129712D01*
G01X1268600Y129235D02*
X1263950Y124585D01*
G01X1267450Y129712D02*
X1265346Y127608D01*
G01X1268600Y129235D02*
X1263950Y124585D01*
G01X1263648Y125910D02*
X1262800Y125062D01*
G01X1263950Y124585D02*
Y116523D01*
G01X1262800Y125062D02*
Y121800D01*
G01X1263950Y124585D02*
Y116523D01*
G01X1262800Y119400D02*
Y117000D01*
G01X1263950Y116523D02*
X1262139Y114712D01*
G01X1262800Y117000D02*
X1261662Y115862D01*
G01X1262139Y114712D02*
X1258712D01*
G01X1261662Y115862D02*
X1258838D01*
G01X1231240Y153933D02*
X1232195Y152978D01*
G01X1234068Y151105D02*
X1235023Y150150D01*
G01D02*
X1243150D01*
G01X1235500Y151300D02*
X1243627D01*
G01X1243150Y150150D02*
X1251300Y142000D01*
G01X1243627Y151300D02*
X1251777Y143150D01*
G01X1251300Y142000D02*
X1253072D01*
G01X1251777Y143150D02*
X1253549D01*
G01X1253072Y142000D02*
X1256444Y138628D01*
G01X1258317Y136755D02*
X1259272Y135800D01*
G01X1253549Y143150D02*
X1259749Y136950D01*
G01X1259272Y135800D02*
X1265173D01*
G01X1259749Y136950D02*
X1265650D01*
G01X1265173Y135800D02*
X1267450Y133523D01*
G01X1265650Y136950D02*
X1268600Y134000D01*
G01X1267450Y133523D02*
Y129712D01*
G01X1268600Y134000D02*
Y129235D01*
G01X1267450Y129712D02*
X1265346Y127608D01*
G01X1263648Y125910D02*
X1262800Y125062D01*
G01X1268600Y129235D02*
X1263950Y124585D01*
G01X1262800Y125062D02*
Y121800D01*
G01Y119400D02*
Y117000D01*
G01X1263950Y124585D02*
Y116523D01*
G01X1262800Y117000D02*
X1261662Y115862D01*
G01X1263950Y116523D02*
X1262139Y114712D01*
G01X1261662Y115862D02*
X1258838D01*
G01X1262139Y114712D02*
X1258712D01*
G01X1278422Y179529D02*
X1292175Y175173D01*
G01X1292908Y176148D02*
X1278546Y180697D01*
G01X1259753Y177738D02*
X1278422Y179529D01*
G01X1278546Y180697D02*
X1259807Y178899D01*
G01X1239005Y181709D02*
X1259753Y177738D01*
G01X1259807Y178899D02*
X1239504Y182785D01*
G01X1306873Y174582D02*
X1278941Y183426D01*
G01X1306370Y173534D02*
X1278821Y182257D01*
G01X1278941Y183426D02*
X1260086Y181482D01*
G01X1278821Y182257D02*
X1260035Y180320D01*
G01X1260086Y181482D02*
X1240431Y185258D01*
G01X1260035Y180320D02*
X1239932Y184182D01*
G01X1240431Y185258D02*
X1220325Y201487D01*
G01X1239932Y184182D02*
X1219464Y200704D01*
G01X1220325Y201487D02*
X1219312Y203019D01*
G01D02*
X1218681Y205234D01*
G01D02*
X1218631Y207704D01*
G01Y207719D02*
X1218798Y209252D01*
G01D02*
X1223330Y214080D01*
G01D02*
X1229379Y235350D01*
G01X1222299Y214664D02*
X1228213Y235457D01*
G01X1259807Y178899D02*
X1239504Y182785D01*
G01X1239005Y181709D02*
X1259753Y177738D01*
G01X1278546Y180697D02*
X1259807Y178899D01*
G01X1259753Y177738D02*
X1278422Y179529D01*
G01X1292908Y176148D02*
X1278546Y180697D01*
G01X1278422Y179529D02*
X1292175Y175173D01*
G01X1306370Y173534D02*
X1278821Y182257D01*
G01X1306873Y174582D02*
X1278941Y183426D01*
G01X1278821Y182257D02*
X1260035Y180320D01*
G01X1278941Y183426D02*
X1260086Y181482D01*
G01X1260035Y180320D02*
X1239932Y184182D01*
G01X1260086Y181482D02*
X1240431Y185258D01*
G01X1239932Y184182D02*
X1219464Y200704D01*
G01X1240431Y185258D02*
X1220325Y201487D01*
G01D02*
X1219312Y203019D01*
G01D02*
X1218681Y205234D01*
G01D02*
X1218631Y207704D01*
G01Y207719D02*
X1218798Y209252D01*
G01D02*
X1223330Y214080D01*
G01X1222299Y214664D02*
X1228213Y235457D01*
G01X1223330Y214080D02*
X1229379Y235350D01*
G01X1295697Y187505D02*
X1278753Y198472D01*
G01X1296192Y188555D02*
X1279571Y199313D01*
G01X1278753Y198472D02*
X1273703Y205822D01*
G01X1279571Y199313D02*
X1274456Y206757D01*
G01X1273703Y205822D02*
X1270176Y207259D01*
G01X1274456Y206757D02*
X1270929Y208195D01*
G01X1270176Y207259D02*
X1243928Y245420D01*
G01X1270929Y208195D02*
X1244945Y245972D01*
G01X1303277Y182462D02*
X1279510Y189983D01*
G01X1327616Y175966D02*
X1279630Y191152D01*
G01X1279510Y189983D02*
X1260154Y188001D01*
G01X1279630Y191152D02*
X1260205Y189163D01*
G01X1260154Y188001D02*
X1251247Y189706D01*
G01X1260205Y189163D02*
X1251745Y190783D01*
G01X1251247Y189706D02*
X1239330Y199327D01*
G01X1251745Y190783D02*
X1240267Y200049D01*
G01X1239330Y199327D02*
X1235426Y208033D01*
G01X1240267Y200049D02*
X1236621Y208180D01*
G01X1235426Y208033D02*
X1236191Y212320D01*
G01X1236621Y208180D02*
X1237362Y212332D01*
G01X1236191Y212320D02*
X1235420Y216193D01*
G01X1237362Y212332D02*
X1236599Y216163D01*
G01X1235420Y216193D02*
X1236247Y219472D01*
G01X1236599Y216163D02*
X1237434Y219473D01*
G01X1327650Y172094D02*
X1279235Y187418D01*
G01X1327713Y173281D02*
X1279355Y188587D01*
G01X1279235Y187418D02*
X1260071Y185452D01*
G01X1279355Y188587D02*
X1260121Y186614D01*
G01X1260071Y185452D02*
X1249575Y187460D01*
G01X1260121Y186614D02*
X1250074Y188536D01*
G01X1249575Y187460D02*
X1237531Y197179D01*
G01X1250074Y188536D02*
X1238468Y197901D01*
G01X1237531Y197179D02*
X1232816Y207697D01*
G01X1238468Y197901D02*
X1234011Y207844D01*
G01X1232816Y207697D02*
X1233635Y212294D01*
G01X1234011Y207844D02*
X1234806Y212305D01*
G01X1233635Y212294D02*
X1232837Y216315D01*
G01X1234806Y212305D02*
X1234016Y216286D01*
G01X1232837Y216315D02*
X1233635Y219493D01*
G01X1234016Y216286D02*
X1234821Y219493D01*
G01X1321509Y172595D02*
X1279055Y186036D01*
G01X1320894Y171583D02*
X1278935Y184867D01*
G01X1279055Y186036D02*
X1259981Y184079D01*
G01X1278935Y184867D02*
X1259931Y182917D01*
G01X1259981Y184079D02*
X1248133Y186341D01*
G01X1259931Y182917D02*
X1247635Y185265D01*
G01X1248133Y186341D02*
X1236713Y195561D01*
G01X1247635Y185265D02*
X1235776Y194839D01*
G01X1236713Y195561D02*
X1231388Y207439D01*
G01X1235776Y194839D02*
X1230193Y207292D01*
G01X1231388Y207439D02*
X1232253Y212281D01*
G01X1230193Y207292D02*
X1231082Y212270D01*
G01X1232253Y212281D02*
X1231436Y216387D01*
G01X1231082Y212270D02*
X1230257Y216416D01*
G01X1231436Y216387D02*
X1232178Y219351D01*
G01X1230257Y216416D02*
X1230992Y219350D01*
G01X1255518Y250714D02*
X1278426Y217410D01*
G01X1278428Y217409D02*
X1282210Y215866D01*
G01X1277528Y216318D02*
X1281262Y214794D01*
G01X1280509Y213859D02*
X1276777Y215381D01*
G01X1254186Y250252D02*
X1277528Y216318D01*
G01X1276775Y215383D02*
X1253169Y249700D01*
G01X1284333Y203861D02*
X1278853Y211833D01*
G01X1285151Y204703D02*
X1279606Y212768D01*
G01X1278853Y211833D02*
X1275126Y213353D01*
G01X1279606Y212768D02*
X1275876Y214290D01*
G01X1275123Y213355D02*
X1250867Y248618D01*
G01X1275876Y214290D02*
X1251884Y249170D01*
G01X1248600Y247486D02*
X1273473Y211324D01*
G01X1249619Y248035D02*
X1274226Y212260D01*
G01X1273473Y211324D02*
X1277132Y209834D01*
G01X1274226Y212260D02*
X1277885Y210769D01*
G01X1277132Y209834D02*
X1282469Y202070D01*
G01X1277885Y210769D02*
X1283287Y202911D01*
G01X1246245Y246479D02*
X1271821Y209296D01*
G01X1247262Y247031D02*
X1272574Y210232D01*
G01X1271824Y209294D02*
X1275413Y207833D01*
G01X1272574Y210232D02*
X1276166Y208769D01*
G01X1275413Y207833D02*
X1280616Y200265D01*
G01X1276166Y208769D02*
X1276500Y208283D01*
G01X1275413Y207833D02*
X1280616Y200265D01*
G01X1276500Y208283D02*
X1281434Y201106D01*
G01X1296192Y188555D02*
X1279571Y199313D01*
G01X1295697Y187505D02*
X1278753Y198472D01*
G01X1279571Y199313D02*
X1274456Y206757D01*
G01X1278753Y198472D02*
X1273703Y205822D01*
G01X1274456Y206757D02*
X1270929Y208195D01*
G01X1273703Y205822D02*
X1270176Y207259D01*
G01X1270929Y208195D02*
X1244945Y245972D01*
G01X1270176Y207259D02*
X1243928Y245420D01*
G01X1327616Y175966D02*
X1279630Y191152D01*
G01X1327616Y175966D02*
X1279630Y191152D01*
G01X1303277Y182462D02*
X1279510Y189983D01*
G01X1279630Y191152D02*
X1260205Y189163D01*
G01X1279510Y189983D02*
X1260154Y188001D01*
G01X1260205Y189163D02*
X1251745Y190783D01*
G01X1260154Y188001D02*
X1251247Y189706D01*
G01X1251745Y190783D02*
X1240267Y200049D01*
G01X1251247Y189706D02*
X1239330Y199327D01*
G01X1240267Y200049D02*
X1236621Y208180D01*
G01X1239330Y199327D02*
X1235426Y208033D01*
G01X1236621Y208180D02*
X1237362Y212332D01*
G01X1235426Y208033D02*
X1236191Y212320D01*
G01X1237362Y212332D02*
X1236599Y216163D01*
G01X1236191Y212320D02*
X1235420Y216193D01*
G01X1236599Y216163D02*
X1237434Y219473D01*
G01X1235420Y216193D02*
X1236247Y219472D01*
G01X1327713Y173281D02*
X1279355Y188587D01*
G01X1327650Y172094D02*
X1279235Y187418D01*
G01X1279355Y188587D02*
X1260121Y186614D01*
G01X1279235Y187418D02*
X1260071Y185452D01*
G01X1260121Y186614D02*
X1250074Y188536D01*
G01X1260071Y185452D02*
X1249575Y187460D01*
G01X1250074Y188536D02*
X1238468Y197901D01*
G01X1249575Y187460D02*
X1237531Y197179D01*
G01X1238468Y197901D02*
X1234011Y207844D01*
G01X1237531Y197179D02*
X1232816Y207697D01*
G01X1234011Y207844D02*
X1234806Y212305D01*
G01X1232816Y207697D02*
X1233635Y212294D01*
G01X1234806Y212305D02*
X1234016Y216286D01*
G01X1233635Y212294D02*
X1232837Y216315D01*
G01X1234016Y216286D02*
X1234821Y219493D01*
G01X1232837Y216315D02*
X1233635Y219493D01*
G01X1320894Y171583D02*
X1278935Y184867D01*
G01X1321509Y172595D02*
X1279055Y186036D01*
G01X1278935Y184867D02*
X1259931Y182917D01*
G01X1279055Y186036D02*
X1259981Y184079D01*
G01X1259931Y182917D02*
X1247635Y185265D01*
G01X1259981Y184079D02*
X1248133Y186341D01*
G01X1247635Y185265D02*
X1235776Y194839D01*
G01X1248133Y186341D02*
X1236713Y195561D01*
G01X1235776Y194839D02*
X1230193Y207292D01*
G01X1236713Y195561D02*
X1231388Y207439D01*
G01X1230193Y207292D02*
X1231082Y212270D01*
G01X1231388Y207439D02*
X1232253Y212281D01*
G01X1231082Y212270D02*
X1230257Y216416D01*
G01X1232253Y212281D02*
X1231436Y216387D01*
G01X1230257Y216416D02*
X1230992Y219350D01*
G01X1231436Y216387D02*
X1232178Y219351D01*
G01X1255518Y250714D02*
X1278426Y217410D01*
G01X1278428Y217409D02*
X1282210Y215866D01*
G01X1276775Y215383D02*
X1253169Y249700D01*
G01X1254186Y250252D02*
X1277528Y216318D01*
G01X1280509Y213859D02*
X1276777Y215381D01*
G01X1277528Y216318D02*
X1281262Y214794D01*
G01X1285151Y204703D02*
X1279606Y212768D01*
G01X1284333Y203861D02*
X1278853Y211833D01*
G01X1279606Y212768D02*
X1275876Y214290D01*
G01X1278853Y211833D02*
X1275126Y213353D01*
G01X1275876Y214290D02*
X1251884Y249170D01*
G01X1275123Y213355D02*
X1250867Y248618D01*
G01X1249619Y248035D02*
X1274226Y212260D01*
G01X1248600Y247486D02*
X1273473Y211324D01*
G01X1274226Y212260D02*
X1277885Y210769D01*
G01X1273473Y211324D02*
X1277132Y209834D01*
G01X1277885Y210769D02*
X1283287Y202911D01*
G01X1277132Y209834D02*
X1282469Y202070D01*
G01X1247262Y247031D02*
X1272574Y210232D01*
G01X1246245Y246479D02*
X1271821Y209296D01*
G01X1272574Y210232D02*
X1276166Y208769D01*
G01X1271824Y209294D02*
X1275413Y207833D01*
G01X1276166Y208769D02*
X1276500Y208283D01*
G01D02*
X1281434Y201106D01*
G01X1275413Y207833D02*
X1280616Y200265D01*
G01X1276748Y281301D02*
X1312179Y229791D01*
G01X1277765Y281853D02*
X1312945Y230707D01*
G01X1252016Y327556D02*
X1271929Y279475D01*
G01X1271930D02*
X1309347Y225081D01*
G01X1272947Y280027D02*
X1310168Y225917D01*
G01X1277765Y281853D02*
X1312945Y230707D01*
G01X1276748Y281301D02*
X1312179Y229791D01*
G01X1252016Y327556D02*
X1271929Y279475D01*
G01X1272947Y280027D02*
X1310168Y225917D01*
G01X1271930Y279475D02*
X1309347Y225081D01*
G01X1223373Y233268D02*
X1220383Y226762D01*
G01X1221389Y226197D02*
X1224475Y232910D01*
G01X1224719Y239991D02*
X1223373Y233268D01*
G01X1224475Y232910D02*
X1225908Y240068D01*
G01X1221257Y250192D02*
X1224719Y239991D01*
G01X1225908Y240068D02*
X1222259Y250819D01*
G01X1229379Y235350D02*
X1228500Y244725D01*
G01X1228213Y235457D02*
X1227371Y244441D01*
G01X1228500Y244725D02*
X1224721Y253667D01*
G01X1227371Y244441D02*
X1223803Y252883D01*
G01X1224721Y253667D02*
X1222530Y255033D01*
G01X1223803Y252883D02*
X1221636Y254234D01*
G01X1222530Y255033D02*
X1219922Y260492D01*
G01X1221636Y254234D02*
X1218726Y260327D01*
G01X1219922Y260492D02*
X1221801Y271340D01*
G01X1218726Y260327D02*
X1220610Y271208D01*
G01X1225908Y240068D02*
X1222259Y250819D01*
G01X1221257Y250192D02*
X1224719Y239991D01*
G01X1224475Y232910D02*
X1225908Y240068D01*
G01X1224719Y239991D02*
X1223373Y233268D01*
G01X1221389Y226197D02*
X1224475Y232910D01*
G01X1223373Y233268D02*
X1220383Y226762D01*
G01X1228213Y235457D02*
X1227371Y244441D01*
G01X1229379Y235350D02*
X1228500Y244725D01*
G01X1227371Y244441D02*
X1223803Y252883D01*
G01X1228500Y244725D02*
X1224721Y253667D01*
G01X1223803Y252883D02*
X1221636Y254234D01*
G01X1224721Y253667D02*
X1222530Y255033D01*
G01X1221636Y254234D02*
X1218726Y260327D01*
G01X1222530Y255033D02*
X1219922Y260492D01*
G01X1218726Y260327D02*
X1220610Y271208D01*
G01X1219922Y260492D02*
X1221801Y271340D01*
G01X1243927Y245422D02*
X1240864Y252819D01*
G01X1239845Y255270D02*
X1222298Y297636D01*
G01X1244945Y245972D02*
X1223296Y298234D01*
G01X1236247Y219472D02*
X1235625Y221938D01*
G01X1237434Y219473D02*
X1236798Y221991D01*
G01X1235625Y221938D02*
X1238077Y237847D01*
G01X1236798Y221991D02*
X1239236Y237813D01*
G01X1238077Y237847D02*
X1236248Y257363D01*
G01X1239236Y237813D02*
X1237377Y257643D01*
G01X1236248Y257363D02*
X1220441Y295524D01*
G01X1237377Y257643D02*
X1221439Y296122D01*
G01X1233635Y219493D02*
X1233035Y221880D01*
G01X1234821Y219493D02*
X1234206Y221939D01*
G01X1233035Y221880D02*
X1235486Y238689D01*
G01X1234206Y221939D02*
X1236608Y238411D01*
G01X1235486Y238689D02*
X1233884Y255778D01*
G01X1236654Y238552D02*
X1235013Y256059D01*
G01D02*
X1218912Y294937D01*
G01X1232178Y219351D02*
X1231507Y222010D01*
G01X1230992Y219350D02*
X1230337Y221944D01*
G01X1231507Y222010D02*
X1233883Y239466D01*
G01X1230337Y221944D02*
X1232725Y239490D01*
G01X1233883Y239466D02*
X1232336Y255984D01*
G01X1232725Y239490D02*
X1231207Y255704D01*
G01D02*
X1230938Y256353D01*
G01X1239552Y315702D02*
X1260283Y265669D01*
G01X1240549Y316303D02*
X1261300Y266221D01*
G01X1260283Y265669D02*
X1295081Y215080D01*
G01X1261300Y266221D02*
X1295902Y215918D01*
G01X1237344Y314322D02*
X1257885Y264741D01*
G01X1238342Y314921D02*
X1258906Y265287D01*
G01X1257885Y264741D02*
X1293519Y212936D01*
G01X1258906Y265287D02*
X1294337Y213777D01*
G01X1235318Y312610D02*
X1259966Y253108D01*
G01X1236316Y313208D02*
X1260983Y253660D01*
G01X1259966Y253108D02*
X1281731Y221464D01*
G01X1260983Y253660D02*
X1282484Y222399D01*
G01X1233306Y310881D02*
X1257711Y251958D01*
G01X1234304Y311479D02*
X1258740Y252490D01*
G01X1257723Y251938D02*
X1280077Y219438D01*
G01X1258740Y252490D02*
X1280830Y220373D01*
G01X1280077Y219438D02*
X1283902Y217877D01*
G01X1231400Y308924D02*
X1255513Y250724D01*
G01X1232398Y309522D02*
X1256535Y251266D01*
G01D02*
X1279179Y218345D01*
G01D02*
X1282963Y216801D01*
G01X1230545Y307327D02*
X1254186Y250252D01*
G01X1253165Y249709D02*
X1229547Y306729D01*
G01X1250865Y248624D02*
X1227770Y304370D01*
G01X1251884Y249170D02*
X1228768Y304968D01*
G01X1226037Y301965D02*
X1248600Y247486D01*
G01X1227035Y302563D02*
X1249619Y248035D01*
G01X1224332Y299387D02*
X1246243Y246485D01*
G01X1225330Y299985D02*
X1247262Y247031D01*
G01X1242919Y317366D02*
X1263731Y267123D01*
G01X1241921Y316768D02*
X1262714Y266571D01*
G01X1263731Y267123D02*
X1297510Y218010D01*
G01X1262714Y266571D02*
X1296689Y217172D01*
G01X1244945Y245972D02*
X1223296Y298234D01*
G01X1243927Y245422D02*
X1240864Y252819D01*
G01X1244945Y245972D02*
X1223296Y298234D01*
G01X1239845Y255270D02*
X1222298Y297636D01*
G01X1237434Y219473D02*
X1236798Y221991D01*
G01X1236247Y219472D02*
X1235625Y221938D01*
G01X1236798Y221991D02*
X1239236Y237813D01*
G01X1235625Y221938D02*
X1238077Y237847D01*
G01X1239236Y237813D02*
X1237377Y257643D01*
G01X1238077Y237847D02*
X1236248Y257363D01*
G01X1237377Y257643D02*
X1221439Y296122D01*
G01X1236248Y257363D02*
X1220441Y295524D01*
G01X1234821Y219493D02*
X1234206Y221939D01*
G01X1233635Y219493D02*
X1233035Y221880D01*
G01X1234206Y221939D02*
X1236608Y238411D01*
G01X1233035Y221880D02*
X1235486Y238689D01*
G01X1236654Y238552D02*
X1235013Y256059D01*
G01X1235486Y238689D02*
X1233884Y255778D01*
G01X1235013Y256059D02*
X1218912Y294937D01*
G01X1230992Y219350D02*
X1230337Y221944D01*
G01X1232178Y219351D02*
X1231507Y222010D01*
G01X1230337Y221944D02*
X1232725Y239490D01*
G01X1231507Y222010D02*
X1233883Y239466D01*
G01X1232725Y239490D02*
X1231207Y255704D01*
G01X1233883Y239466D02*
X1232336Y255984D01*
G01X1231207Y255704D02*
X1230938Y256353D01*
G01X1240549Y316303D02*
X1261300Y266221D01*
G01X1239552Y315702D02*
X1260283Y265669D01*
G01X1261300Y266221D02*
X1295902Y215918D01*
G01X1260283Y265669D02*
X1295081Y215080D01*
G01X1238342Y314921D02*
X1258906Y265287D01*
G01X1237344Y314322D02*
X1257885Y264741D01*
G01X1258906Y265287D02*
X1294337Y213777D01*
G01X1257885Y264741D02*
X1293519Y212936D01*
G01X1236316Y313208D02*
X1260983Y253660D01*
G01X1235318Y312610D02*
X1259966Y253108D01*
G01X1260983Y253660D02*
X1282484Y222399D01*
G01X1259966Y253108D02*
X1281731Y221464D01*
G01X1234304Y311479D02*
X1258740Y252490D01*
G01X1233306Y310881D02*
X1257711Y251958D01*
G01X1258740Y252490D02*
X1280830Y220373D01*
G01X1257723Y251938D02*
X1280077Y219438D01*
G01D02*
X1283902Y217877D01*
G01X1232398Y309522D02*
X1256535Y251266D01*
G01X1231400Y308924D02*
X1255513Y250724D01*
G01X1256535Y251266D02*
X1279179Y218345D01*
G01D02*
X1282963Y216801D01*
G01X1253165Y249709D02*
X1229547Y306729D01*
G01X1230545Y307327D02*
X1254186Y250252D01*
G01X1251884Y249170D02*
X1228768Y304968D01*
G01X1250865Y248624D02*
X1227770Y304370D01*
G01X1227035Y302563D02*
X1249619Y248035D01*
G01X1226037Y301965D02*
X1248600Y247486D01*
G01X1225330Y299985D02*
X1247262Y247031D01*
G01X1224332Y299387D02*
X1246243Y246485D01*
G01X1241921Y316768D02*
X1262714Y266571D01*
G01X1242919Y317366D02*
X1263731Y267123D01*
G01X1262714Y266571D02*
X1296689Y217172D01*
G01X1263731Y267123D02*
X1297510Y218010D01*
G01X1274294Y280454D02*
X1310964Y227144D01*
G01X1275311Y281006D02*
X1311785Y227980D01*
G01X1303343Y218048D02*
X1263503Y275959D01*
G01X1302522Y217212D02*
X1262486Y275407D01*
G01X1263503Y275959D02*
X1244156Y322672D01*
G01X1262486Y275407D02*
X1243180Y322020D01*
G01X1304111Y219315D02*
X1264714Y276582D01*
G01X1304932Y220151D02*
X1265731Y277134D01*
G01X1264714Y276582D02*
X1245268Y323532D01*
G01X1265731Y277134D02*
X1246244Y324184D01*
G01X1248471Y325557D02*
X1268018Y278362D01*
G01X1247495Y324905D02*
X1267001Y277810D01*
G01X1268018Y278362D02*
X1306809Y221972D01*
G01X1267001Y277810D02*
X1305988Y221136D01*
G01X1269613Y278429D02*
X1307765Y222967D01*
G01X1308586Y223803D02*
X1270632Y278977D01*
G01X1249847Y326153D02*
X1269613Y278429D01*
G01X1270632Y278977D02*
X1250823Y326805D01*
G01X1275311Y281006D02*
X1311785Y227980D01*
G01X1274294Y280454D02*
X1310964Y227144D01*
G01X1302522Y217212D02*
X1262486Y275407D01*
G01X1303343Y218048D02*
X1263503Y275959D01*
G01X1262486Y275407D02*
X1243180Y322020D01*
G01X1263503Y275959D02*
X1244156Y322672D01*
G01X1304932Y220151D02*
X1265731Y277134D01*
G01X1304111Y219315D02*
X1264714Y276582D01*
G01X1265731Y277134D02*
X1246244Y324184D01*
G01X1264714Y276582D02*
X1245268Y323532D01*
G01X1247495Y324905D02*
X1267001Y277810D01*
G01X1248471Y325557D02*
X1268018Y278362D01*
G01X1267001Y277810D02*
X1305988Y221136D01*
G01X1268018Y278362D02*
X1306809Y221972D01*
G01X1270632Y278977D02*
X1250823Y326805D01*
G01X1249847Y326153D02*
X1269613Y278429D01*
G01X1308586Y223803D02*
X1270632Y278977D01*
G01X1269613Y278429D02*
X1307765Y222967D01*
G01X1303124Y247370D02*
X1279153Y282220D01*
G01X1303942Y248211D02*
X1280170Y282772D01*
G01X1279153Y282220D02*
X1258643Y331730D01*
G01X1280170Y282772D02*
X1259619Y332382D01*
G01X1258643Y331730D02*
X1221789Y368582D01*
G01X1256419Y330382D02*
X1276748Y281301D01*
G01X1257397Y331030D02*
X1277765Y281853D01*
G01X1252992Y328208D02*
X1272947Y280027D01*
G01X1303942Y248211D02*
X1280170Y282772D01*
G01X1303124Y247370D02*
X1279153Y282220D01*
G01X1280170Y282772D02*
X1259619Y332382D01*
G01X1279153Y282220D02*
X1258643Y331730D01*
G01D02*
X1221789Y368582D01*
G01X1257397Y331030D02*
X1277765Y281853D01*
G01X1256419Y330382D02*
X1276748Y281301D01*
G01X1252992Y328208D02*
X1272947Y280027D01*
G01X1219120Y337699D02*
X1219300Y337434D01*
G01D02*
X1221951Y333533D01*
G01X1219950Y338524D02*
X1222827Y334291D01*
G01X1221953Y333531D02*
X1233546Y323022D01*
G01X1222827Y334291D02*
X1234382Y323818D01*
G01X1233546Y323022D02*
X1239553Y315703D01*
G01X1234382Y323818D02*
X1240549Y316303D01*
G01X1218723Y335928D02*
X1220603Y333043D01*
G01X1219704Y332314D02*
X1225194Y326824D01*
G01X1220603Y333043D02*
X1225988Y327658D01*
G01X1225194Y326824D02*
X1232604Y320111D01*
G01X1225988Y327658D02*
X1233440Y320906D01*
G01X1232604Y320111D02*
X1237344Y314322D01*
G01X1233440Y320906D02*
X1238342Y314921D01*
G01X1219300Y330642D02*
X1219417Y330460D01*
G01D02*
X1222970Y326907D01*
G01X1222176Y326073D02*
X1230374Y318645D01*
G01X1222970Y326907D02*
X1231210Y319441D01*
G01X1230374Y318645D02*
X1235318Y312610D01*
G01X1231210Y319441D02*
X1236316Y313208D01*
G01X1228108Y317214D02*
X1233306Y310881D01*
G01X1228950Y318005D02*
X1234304Y311479D01*
G01X1227347Y313864D02*
X1231400Y308924D01*
G01X1228176Y314667D02*
X1232398Y309522D01*
G01X1226771Y311928D02*
X1230545Y307327D01*
G01X1229547Y306729D02*
X1225932Y311136D01*
G01X1227770Y304370D02*
X1223415Y309679D01*
G01X1228768Y304968D02*
X1224251Y310476D01*
G01X1220672Y308503D02*
X1226037Y301965D01*
G01X1221510Y309298D02*
X1227035Y302563D01*
G01X1219300Y340655D02*
X1221520Y339198D01*
G01X1222366Y340020D02*
X1224906Y335894D01*
G01X1221520Y339198D02*
X1224012Y335150D01*
G01X1224906Y335894D02*
X1235747Y326106D01*
G01X1224012Y335150D02*
X1234912Y325309D01*
G01X1235747Y326106D02*
X1242919Y317366D01*
G01X1234912Y325309D02*
X1241922Y316768D01*
G01X1219950Y338524D02*
X1222827Y334291D01*
G01X1219120Y337699D02*
X1219300Y337434D01*
G01X1219950Y338524D02*
X1222827Y334291D01*
G01X1219300Y337434D02*
X1221951Y333533D01*
G01X1222827Y334291D02*
X1234382Y323818D01*
G01X1221953Y333531D02*
X1233546Y323022D01*
G01X1234382Y323818D02*
X1240549Y316303D01*
G01X1233546Y323022D02*
X1239553Y315703D01*
G01X1218723Y335928D02*
X1220603Y333043D01*
G01D02*
X1225988Y327658D01*
G01X1219704Y332314D02*
X1225194Y326824D01*
G01X1225988Y327658D02*
X1233440Y320906D01*
G01X1225194Y326824D02*
X1232604Y320111D01*
G01X1233440Y320906D02*
X1238342Y314921D01*
G01X1232604Y320111D02*
X1237344Y314322D01*
G01X1219300Y330642D02*
X1219417Y330460D01*
G01D02*
X1222970Y326907D01*
G01D02*
X1231210Y319441D01*
G01X1222176Y326073D02*
X1230374Y318645D01*
G01X1231210Y319441D02*
X1236316Y313208D01*
G01X1230374Y318645D02*
X1235318Y312610D01*
G01X1228950Y318005D02*
X1234304Y311479D01*
G01X1228108Y317214D02*
X1233306Y310881D01*
G01X1228176Y314667D02*
X1232398Y309522D01*
G01X1227347Y313864D02*
X1231400Y308924D01*
G01X1229547Y306729D02*
X1225932Y311136D01*
G01X1226771Y311928D02*
X1230545Y307327D01*
G01X1228768Y304968D02*
X1224251Y310476D01*
G01X1227770Y304370D02*
X1223415Y309679D01*
G01X1221510Y309298D02*
X1227035Y302563D01*
G01X1220672Y308503D02*
X1226037Y301965D01*
G01X1219300Y340655D02*
X1221520Y339198D01*
G01D02*
X1224012Y335150D01*
G01X1222366Y340020D02*
X1224906Y335894D01*
G01X1224012Y335150D02*
X1234912Y325309D01*
G01X1224906Y335894D02*
X1235747Y326106D01*
G01X1234912Y325309D02*
X1241922Y316768D01*
G01X1235747Y326106D02*
X1242919Y317366D01*
G01X1254195Y328979D02*
X1274294Y280454D01*
G01X1255171Y329631D02*
X1275311Y281006D01*
G01X1244156Y322672D02*
X1223095Y343733D01*
G01X1243180Y322020D02*
X1222366Y342834D01*
G01X1245268Y323532D02*
X1222801Y345999D01*
G01X1246244Y324184D02*
X1223453Y346975D01*
G01X1255171Y329631D02*
X1275311Y281006D01*
G01X1254195Y328979D02*
X1274294Y280454D01*
G01X1243180Y322020D02*
X1222366Y342834D01*
G01X1244156Y322672D02*
X1223095Y343733D01*
G01X1246244Y324184D02*
X1223453Y346975D01*
G01X1245268Y323532D02*
X1222801Y345999D01*
G01X1291560Y300497D02*
X1273858Y343227D01*
G01X1292577Y301050D02*
X1274833Y343880D01*
G01X1289247Y299445D02*
X1271792Y341590D01*
G01X1290265Y299996D02*
X1272766Y342244D01*
G01X1286849Y298516D02*
X1269687Y339949D01*
G01X1287867Y299067D02*
X1270667Y340596D01*
G01X1269687Y339949D02*
X1222348Y387288D01*
G01X1270667Y340596D02*
X1222825Y388438D01*
G01X1284568Y297416D02*
X1267514Y338584D01*
G01X1285585Y297968D02*
X1268490Y339236D01*
G01X1282303Y296293D02*
X1265753Y336245D01*
G01X1266729Y336897D02*
X1283320Y296845D01*
G01X1284184Y285060D02*
X1263586Y334787D01*
G01X1285201Y285612D02*
X1264562Y335439D01*
G01X1281963Y283718D02*
X1261392Y333381D01*
G01X1282981Y284269D02*
X1262368Y334033D01*
G01X1276995Y345347D02*
X1295973Y300548D01*
G01X1276023Y344692D02*
X1294914Y300099D01*
G01X1292577Y301050D02*
X1274833Y343880D01*
G01X1291560Y300497D02*
X1273858Y343227D01*
G01X1290265Y299996D02*
X1272766Y342244D01*
G01X1289247Y299445D02*
X1271792Y341590D01*
G01X1287867Y299067D02*
X1270667Y340596D01*
G01X1286849Y298516D02*
X1269687Y339949D01*
G01X1270667Y340596D02*
X1222825Y388438D01*
G01X1269687Y339949D02*
X1222348Y387288D01*
G01X1285585Y297968D02*
X1268490Y339236D01*
G01X1284568Y297416D02*
X1267514Y338584D01*
G01X1266729Y336897D02*
X1283320Y296845D01*
G01X1282303Y296293D02*
X1265753Y336245D01*
G01X1285201Y285612D02*
X1264562Y335439D01*
G01X1284184Y285060D02*
X1263586Y334787D01*
G01X1282981Y284269D02*
X1262368Y334033D01*
G01X1281963Y283718D02*
X1261392Y333381D01*
G01X1276023Y344692D02*
X1294914Y300099D01*
G01X1276995Y345347D02*
X1295973Y300548D01*
G01X1223095Y343733D02*
X1220969Y345116D01*
G01X1222366Y342834D02*
X1220457Y344077D01*
G01X1222366Y342834D02*
X1220457Y344077D01*
G01X1223095Y343733D02*
X1220969Y345116D01*
G01X1280785Y654412D02*
X1279107Y644878D01*
G01X1281836Y653742D02*
X1280157Y644208D01*
G01X1279107Y644878D02*
X1278584Y644513D01*
G01D02*
X1277549Y644695D01*
G01X1280157Y644208D02*
X1278853Y643298D01*
G01X1278584Y644513D02*
X1277549Y644695D01*
G01X1278853Y643298D02*
X1276879Y643644D01*
G01X1277549Y644695D02*
X1277185Y645216D01*
G01X1276879Y643644D02*
X1275969Y644947D01*
G01X1277185Y645216D02*
X1278677Y653669D01*
G01X1275969Y644947D02*
X1277461Y653401D01*
G01X1274490Y654408D02*
X1272806Y644858D01*
G01X1275541Y653739D02*
X1273856Y644189D01*
G01X1272806Y644858D02*
X1272287Y644495D01*
G01D02*
X1271253Y644678D01*
G01X1273856Y644189D02*
X1272556Y643279D01*
G01X1272287Y644495D02*
X1271253Y644678D01*
G01X1272556Y643279D02*
X1270583Y643628D01*
G01X1271253Y644678D02*
X1270886Y645202D01*
G01X1270583Y643628D02*
X1269670Y644932D01*
G01X1270886Y645202D02*
X1272370Y653608D01*
G01X1269670Y644932D02*
X1271154Y653339D01*
G01X1268654Y650807D02*
X1267673Y649499D01*
G01X1266973Y650484D02*
X1263869Y649497D01*
G01X1267673Y649499D02*
X1264002Y648332D01*
G01X1263869Y649497D02*
X1259594Y649839D01*
G01X1264002Y648332D02*
X1259547Y648689D01*
G01D02*
X1257806D01*
G01X1281836Y653742D02*
X1280157Y644208D01*
G01X1280785Y654412D02*
X1279107Y644878D01*
G01X1280157Y644208D02*
X1278853Y643298D01*
G01X1279107Y644878D02*
X1278584Y644513D01*
G01X1280157Y644208D02*
X1278853Y643298D01*
G01D02*
X1276879Y643644D01*
G01X1278584Y644513D02*
X1277549Y644695D01*
G01X1276879Y643644D02*
X1275969Y644947D01*
G01X1277549Y644695D02*
X1277185Y645216D01*
G01X1275969Y644947D02*
X1277461Y653401D01*
G01X1277185Y645216D02*
X1278677Y653669D01*
G01X1275541Y653739D02*
X1273856Y644189D01*
G01X1274490Y654408D02*
X1272806Y644858D01*
G01X1273856Y644189D02*
X1272556Y643279D01*
G01X1272806Y644858D02*
X1272287Y644495D01*
G01X1273856Y644189D02*
X1272556Y643279D01*
G01D02*
X1270583Y643628D01*
G01X1272287Y644495D02*
X1271253Y644678D01*
G01X1270583Y643628D02*
X1269670Y644932D01*
G01X1271253Y644678D02*
X1270886Y645202D01*
G01X1269670Y644932D02*
X1271154Y653339D01*
G01X1270886Y645202D02*
X1272370Y653608D01*
G01X1268654Y650807D02*
X1267673Y649499D01*
G01D02*
X1264002Y648332D01*
G01X1266973Y650484D02*
X1263869Y649497D01*
G01X1264002Y648332D02*
X1259547Y648689D01*
G01X1263869Y649497D02*
X1259594Y649839D01*
G01X1259547Y648689D02*
X1257806D01*
G01X1278677Y653669D02*
X1277768Y654974D01*
G01X1277461Y653401D02*
X1277097Y653924D01*
G01X1277768Y654974D02*
X1275794Y655322D01*
G01D02*
X1274490Y654408D01*
G01X1277097Y653924D02*
X1276064Y654106D01*
G01X1275794Y655322D02*
X1274490Y654408D01*
G01X1276064Y654106D02*
X1275541Y653739D01*
G01X1272370Y653608D02*
X1271459Y654912D01*
G01X1271154Y653339D02*
X1270789Y653861D01*
G01X1271459Y654912D02*
X1269485Y655259D01*
G01D02*
X1268183Y654347D01*
G01X1270789Y653861D02*
X1269755Y654043D01*
G01X1269485Y655259D02*
X1268183Y654347D01*
G01X1269755Y654043D02*
X1269234Y653678D01*
G01X1268183Y654347D02*
X1267772Y652010D01*
G01X1269234Y653678D02*
X1268898Y651768D01*
G01X1267772Y652010D02*
X1267595Y651314D01*
G01X1268898Y651768D02*
X1268654Y650807D01*
G01X1267595Y651314D02*
X1266973Y650484D01*
G01X1259594Y649839D02*
X1257806D01*
G01X1277461Y653401D02*
X1277097Y653924D01*
G01X1278677Y653669D02*
X1277768Y654974D01*
G01X1277097Y653924D02*
X1276064Y654106D01*
G01X1277768Y654974D02*
X1275794Y655322D01*
G01X1277097Y653924D02*
X1276064Y654106D01*
G01D02*
X1275541Y653739D01*
G01X1275794Y655322D02*
X1274490Y654408D01*
G01X1271154Y653339D02*
X1270789Y653861D01*
G01X1272370Y653608D02*
X1271459Y654912D01*
G01X1270789Y653861D02*
X1269755Y654043D01*
G01X1271459Y654912D02*
X1269485Y655259D01*
G01X1270789Y653861D02*
X1269755Y654043D01*
G01D02*
X1269234Y653678D01*
G01X1269485Y655259D02*
X1268183Y654347D01*
G01X1269234Y653678D02*
X1268898Y651768D01*
G01X1268183Y654347D02*
X1267772Y652010D01*
G01X1268898Y651768D02*
X1268654Y650807D01*
G01X1267772Y652010D02*
X1267595Y651314D01*
G01D02*
X1266973Y650484D01*
G01X1259594Y649839D02*
X1257806D01*
G01X1336960Y142918D02*
X1343543Y136335D01*
G01X1344020Y137485D02*
X1338110Y143395D01*
G01X1336960Y150679D02*
Y142918D01*
G01X1338110Y143395D02*
Y151156D01*
G01X1335595Y152044D02*
X1336960Y150679D01*
G01X1338110Y151156D02*
X1336072Y153194D01*
G01X1322261Y152044D02*
X1335595D01*
G01X1336072Y153194D02*
X1322608D01*
G01X1311402Y159239D02*
X1322261Y152044D01*
G01X1322608Y153194D02*
X1311849Y160323D01*
G01X1345278Y138942D02*
X1341952Y142268D01*
G01D02*
Y155770D01*
G01D02*
X1340628Y157094D01*
G01X1322608Y153194D02*
X1311849Y160323D01*
G01X1311402Y159239D02*
X1322261Y152044D01*
G01X1336072Y153194D02*
X1322608D01*
G01X1322261Y152044D02*
X1335595D01*
G01X1338110Y151156D02*
X1336072Y153194D01*
G01X1335595Y152044D02*
X1336960Y150679D01*
G01X1338110Y143395D02*
Y151156D01*
G01X1336960Y150679D02*
Y142918D01*
G01X1344020Y137485D02*
X1338110Y143395D01*
G01X1336960Y142918D02*
X1343543Y136335D01*
G01X1345278Y138942D02*
X1341952Y142268D01*
G01D02*
Y155770D01*
G01D02*
X1340628Y157094D01*
G01X1304602Y160598D02*
X1311402Y159239D01*
G01X1311849Y160323D02*
X1305051Y161682D01*
G01X1299725Y163849D02*
X1304602Y160598D01*
G01X1305051Y161682D02*
X1300555Y164679D01*
G01X1292175Y175173D02*
X1299725Y163849D01*
G01X1300555Y164679D02*
X1292908Y176148D01*
G01X1343102Y156247D02*
X1341105Y158244D01*
G01D02*
X1320448D01*
G01X1340628Y157094D02*
X1320101D01*
G01X1320448Y158244D02*
X1313200Y163047D01*
G01X1320101Y157094D02*
X1312050Y162429D01*
G01X1313200Y163047D02*
Y166410D01*
G01X1312050Y162429D02*
Y166295D01*
G01X1313200Y166410D02*
X1312499Y169909D01*
G01X1312050Y166295D02*
X1311416Y169460D01*
G01X1312499Y169909D02*
X1311393Y171569D01*
G01X1311416Y169460D02*
X1310563Y170739D01*
G01X1311393Y171569D02*
X1306873Y174582D01*
G01X1310563Y170739D02*
X1306370Y173534D01*
G01X1300555Y164679D02*
X1292908Y176148D01*
G01X1292175Y175173D02*
X1299725Y163849D01*
G01X1305051Y161682D02*
X1300555Y164679D01*
G01X1299725Y163849D02*
X1304602Y160598D01*
G01X1311849Y160323D02*
X1305051Y161682D01*
G01X1304602Y160598D02*
X1311402Y159239D01*
G01X1343102Y156247D02*
X1341105Y158244D01*
G01X1340628Y157094D02*
X1320101D01*
G01X1341105Y158244D02*
X1320448D01*
G01X1320101Y157094D02*
X1312050Y162429D01*
G01X1320448Y158244D02*
X1313200Y163047D01*
G01X1312050Y162429D02*
Y166295D01*
G01X1313200Y163047D02*
Y166410D01*
G01X1312050Y166295D02*
X1311416Y169460D01*
G01X1313200Y166410D02*
X1312499Y169909D01*
G01X1311416Y169460D02*
X1310563Y170739D01*
G01X1312499Y169909D02*
X1311393Y171569D01*
G01X1310563Y170739D02*
X1306370Y173534D01*
G01X1311393Y171569D02*
X1306873Y174582D01*
G01X1344201Y177324D02*
X1335668Y179060D01*
G01X1344201Y178498D02*
X1335668Y180234D01*
G01Y179060D02*
X1327596Y177415D01*
G01X1335668Y180234D02*
X1327659Y178602D01*
G01X1327596Y177415D02*
X1295697Y187505D01*
G01X1327659Y178602D02*
X1296192Y188555D01*
G01X1344447Y174570D02*
X1335476Y176394D01*
G01X1344447Y175744D02*
X1335476Y177568D01*
G01Y176394D02*
X1327553Y174779D01*
G01X1335476Y177568D02*
X1327616Y175966D01*
G01X1327553Y174779D02*
X1303277Y182460D01*
G01X1343300Y167000D02*
X1342000Y168300D01*
G01Y172089D02*
X1341657Y172432D01*
G01D02*
X1335477Y173689D01*
G01X1342309Y173473D02*
X1335477Y174863D01*
G01Y173689D02*
X1327650Y172094D01*
G01X1335477Y174863D02*
X1327713Y173281D01*
G01X1346963Y162850D02*
X1324051D01*
G01X1346486Y161700D02*
X1323574D01*
G01X1324051Y162850D02*
X1323046Y163855D01*
G01X1323574Y161700D02*
X1321896Y163378D01*
G01X1323046Y163855D02*
Y171058D01*
G01X1321896Y163378D02*
Y170581D01*
G01X1323046Y171058D02*
X1321509Y172595D01*
G01X1321896Y170581D02*
X1320894Y171583D01*
G01X1295081Y215080D02*
X1304980Y208570D01*
G01X1295902Y215918D02*
X1305478Y209619D01*
G01X1304980Y208570D02*
X1328775Y201081D01*
G01X1305478Y209620D02*
X1328837Y202268D01*
G01X1328775Y201081D02*
X1337912Y202941D01*
G01X1328837Y202268D02*
X1337912Y204115D01*
G01Y202941D02*
X1346770Y201139D01*
G01X1337912Y204115D02*
X1346770Y202313D01*
G01X1293519Y212936D02*
X1303939Y206185D01*
G01X1294337Y213777D02*
X1304434Y207236D01*
G01X1303939Y206185D02*
X1328646Y198403D01*
G01X1304434Y207236D02*
X1328708Y199590D01*
G01X1328646Y198403D02*
X1337783Y200265D01*
G01X1328708Y199590D02*
X1337783Y201439D01*
G01Y200265D02*
X1346453Y198500D01*
G01X1337783Y201439D02*
X1346453Y199674D01*
G01X1285601Y219885D02*
X1291574Y211198D01*
G01X1286354Y220820D02*
X1292392Y212039D01*
G01X1291574Y211198D02*
X1302884Y203872D01*
G01X1292392Y212039D02*
X1303377Y204924D01*
G01X1302884Y203872D02*
X1328534Y195788D01*
G01X1303377Y204924D02*
X1328596Y196975D01*
G01X1328534Y195788D02*
X1337508Y197615D01*
G01X1328596Y196975D02*
X1337508Y198789D01*
G01Y197615D02*
X1346233Y195840D01*
G01X1337508Y198789D02*
X1346233Y197014D01*
G01X1283902Y217877D02*
X1289761Y209359D01*
G01X1284655Y218812D02*
X1290579Y210200D01*
G01X1289761Y209359D02*
X1301777Y201575D01*
G01X1290579Y210200D02*
X1302272Y202626D01*
G01X1301777Y201575D02*
X1328479Y193161D01*
G01X1302272Y202626D02*
X1328541Y194348D01*
G01X1328479Y193161D02*
X1337291Y194955D01*
G01X1328541Y194348D02*
X1337291Y196129D01*
G01Y194955D02*
X1345931Y193198D01*
G01X1337291Y196129D02*
X1345931Y194372D01*
G01X1282210Y215866D02*
X1287944Y207526D01*
G01X1282963Y216801D02*
X1288762Y208367D01*
G01X1287944Y207526D02*
X1301067Y199027D01*
G01X1288762Y208367D02*
X1301561Y200078D01*
G01X1301067Y199027D02*
X1328163Y190480D01*
G01X1301561Y200078D02*
X1328225Y191667D01*
G01X1328163Y190480D02*
X1337071Y192296D01*
G01X1328225Y191667D02*
X1337071Y193470D01*
G01Y192296D02*
X1345658Y190549D01*
G01X1337071Y193470D02*
X1345658Y191723D01*
G01X1336746Y190832D02*
X1345348Y189082D01*
G01Y187908D02*
X1336746Y189658D01*
G01X1328003Y189053D02*
X1336746Y190832D01*
G01Y189658D02*
X1327941Y187866D01*
G01X1300581Y197716D02*
X1328003Y189053D01*
G01X1327941Y187866D02*
X1300086Y196666D01*
G01X1286925Y206560D02*
X1300581Y197716D01*
G01X1300086Y196666D02*
X1286107Y205719D01*
G01X1281262Y214794D02*
X1286925Y206560D01*
G01X1286107Y205719D02*
X1280509Y213859D01*
G01X1345004Y185273D02*
X1336420Y187020D01*
G01X1345004Y186447D02*
X1336420Y188194D01*
G01Y187020D02*
X1327833Y185271D01*
G01X1336420Y188194D02*
X1327896Y186458D01*
G01X1327833Y185271D02*
X1298974Y194391D01*
G01X1327896Y186458D02*
X1299469Y195442D01*
G01X1298974Y194391D02*
X1284333Y203861D01*
G01X1299469Y195442D02*
X1285151Y204703D01*
G01X1282469Y202070D02*
X1297871Y192091D01*
G01X1283287Y202911D02*
X1298371Y193139D01*
G01X1297871Y192091D02*
X1327711Y182653D01*
G01X1298371Y193139D02*
X1327774Y183840D01*
G01X1327711Y182653D02*
X1336150Y184371D01*
G01X1327774Y183840D02*
X1336150Y185545D01*
G01Y184371D02*
X1344689Y182633D01*
G01X1336150Y185545D02*
X1344689Y183807D01*
G01X1280616Y200265D02*
X1296757Y189809D01*
G01X1281434Y201106D02*
X1297255Y190858D01*
G01X1296757Y189809D02*
X1327564Y180063D01*
G01X1297255Y190858D02*
X1327626Y181250D01*
G01X1327564Y180063D02*
X1335787Y181741D01*
G01X1327626Y181250D02*
X1335787Y182915D01*
G01Y181741D02*
X1344459Y179976D01*
G01X1335787Y182915D02*
X1344459Y181150D01*
G01X1297510Y218010D02*
X1306548Y212059D01*
G01X1296689Y217172D02*
X1306050Y211010D01*
G01X1306548Y212059D02*
X1329186Y204939D01*
G01X1306050Y211010D02*
X1329124Y203752D01*
G01X1329186Y204939D02*
X1338170Y206768D01*
G01X1329124Y203752D02*
X1338170Y205594D01*
G01Y206768D02*
X1347089Y204953D01*
G01X1338170Y205594D02*
X1347089Y203779D01*
G01X1344201Y178498D02*
X1335668Y180234D01*
G01X1344201Y177324D02*
X1335668Y179060D01*
G01Y180234D02*
X1327659Y178602D01*
G01X1335668Y179060D02*
X1327596Y177415D01*
G01X1327659Y178602D02*
X1296192Y188555D01*
G01X1327596Y177415D02*
X1295697Y187505D01*
G01X1344447Y175744D02*
X1335476Y177568D01*
G01X1344447Y174570D02*
X1335476Y176394D01*
G01Y177568D02*
X1327616Y175966D01*
G01X1335476Y176394D02*
X1327553Y174779D01*
G01D02*
X1303277Y182460D01*
G01X1343300Y167000D02*
X1342000Y168300D01*
G01Y172089D02*
X1341657Y172432D01*
G01X1342309Y173473D02*
X1335477Y174863D01*
G01X1341657Y172432D02*
X1335477Y173689D01*
G01Y174863D02*
X1327713Y173281D01*
G01X1335477Y173689D02*
X1327650Y172094D01*
G01X1346486Y161700D02*
X1323574D01*
G01X1346963Y162850D02*
X1324051D01*
G01X1323574Y161700D02*
X1321896Y163378D01*
G01X1324051Y162850D02*
X1323046Y163855D01*
G01X1321896Y163378D02*
Y170581D01*
G01X1323046Y163855D02*
Y171058D01*
G01X1321896Y170581D02*
X1320894Y171583D01*
G01X1323046Y171058D02*
X1321509Y172595D01*
G01X1295902Y215918D02*
X1305478Y209619D01*
G01X1295081Y215080D02*
X1304980Y208570D01*
G01X1305478Y209620D02*
X1328837Y202268D01*
G01X1304980Y208570D02*
X1328775Y201081D01*
G01X1328837Y202268D02*
X1337912Y204115D01*
G01X1328775Y201081D02*
X1337912Y202941D01*
G01Y204115D02*
X1346770Y202313D01*
G01X1337912Y202941D02*
X1346770Y201139D01*
G01X1294337Y213777D02*
X1304434Y207236D01*
G01X1293519Y212936D02*
X1303939Y206185D01*
G01X1304434Y207236D02*
X1328708Y199590D01*
G01X1303939Y206185D02*
X1328646Y198403D01*
G01X1328708Y199590D02*
X1337783Y201439D01*
G01X1328646Y198403D02*
X1337783Y200265D01*
G01Y201439D02*
X1346453Y199674D01*
G01X1337783Y200265D02*
X1346453Y198500D01*
G01X1286354Y220820D02*
X1292392Y212039D01*
G01X1285601Y219885D02*
X1291574Y211198D01*
G01X1292392Y212039D02*
X1303377Y204924D01*
G01X1291574Y211198D02*
X1302884Y203872D01*
G01X1303377Y204924D02*
X1328596Y196975D01*
G01X1302884Y203872D02*
X1328534Y195788D01*
G01X1328596Y196975D02*
X1337508Y198789D01*
G01X1328534Y195788D02*
X1337508Y197615D01*
G01Y198789D02*
X1346233Y197014D01*
G01X1337508Y197615D02*
X1346233Y195840D01*
G01X1284655Y218812D02*
X1290579Y210200D01*
G01X1283902Y217877D02*
X1289761Y209359D01*
G01X1290579Y210200D02*
X1302272Y202626D01*
G01X1289761Y209359D02*
X1301777Y201575D01*
G01X1302272Y202626D02*
X1328541Y194348D01*
G01X1301777Y201575D02*
X1328479Y193161D01*
G01X1328541Y194348D02*
X1337291Y196129D01*
G01X1328479Y193161D02*
X1337291Y194955D01*
G01Y196129D02*
X1345931Y194372D01*
G01X1337291Y194955D02*
X1345931Y193198D01*
G01X1282963Y216801D02*
X1288762Y208367D01*
G01X1282210Y215866D02*
X1287944Y207526D01*
G01X1288762Y208367D02*
X1301561Y200078D01*
G01X1287944Y207526D02*
X1301067Y199027D01*
G01X1301561Y200078D02*
X1328225Y191667D01*
G01X1301067Y199027D02*
X1328163Y190480D01*
G01X1328225Y191667D02*
X1337071Y193470D01*
G01X1328163Y190480D02*
X1337071Y192296D01*
G01Y193470D02*
X1345658Y191723D01*
G01X1337071Y192296D02*
X1345658Y190549D01*
G01X1286107Y205719D02*
X1280509Y213859D01*
G01X1281262Y214794D02*
X1286925Y206560D01*
G01X1300086Y196666D02*
X1286107Y205719D01*
G01X1286925Y206560D02*
X1300581Y197716D01*
G01X1327941Y187866D02*
X1300086Y196666D01*
G01X1300581Y197716D02*
X1328003Y189053D01*
G01X1336746Y189658D02*
X1327941Y187866D01*
G01X1328003Y189053D02*
X1336746Y190832D01*
G01X1345348Y187908D02*
X1336746Y189658D01*
G01Y190832D02*
X1345348Y189082D01*
G01X1345004Y186447D02*
X1336420Y188194D01*
G01X1345004Y185273D02*
X1336420Y187020D01*
G01Y188194D02*
X1327896Y186458D01*
G01X1336420Y187020D02*
X1327833Y185271D01*
G01X1327896Y186458D02*
X1299469Y195442D01*
G01X1327833Y185271D02*
X1298974Y194391D01*
G01X1299469Y195442D02*
X1285151Y204703D01*
G01X1298974Y194391D02*
X1284333Y203861D01*
G01X1283287Y202911D02*
X1298371Y193139D01*
G01X1282469Y202070D02*
X1297871Y192091D01*
G01X1298371Y193139D02*
X1327774Y183840D01*
G01X1297871Y192091D02*
X1327711Y182653D01*
G01X1327774Y183840D02*
X1336150Y185545D01*
G01X1327711Y182653D02*
X1336150Y184371D01*
G01Y185545D02*
X1344689Y183807D01*
G01X1336150Y184371D02*
X1344689Y182633D01*
G01X1281434Y201106D02*
X1297255Y190858D01*
G01X1280616Y200265D02*
X1296757Y189809D01*
G01X1297255Y190858D02*
X1327626Y181250D01*
G01X1296757Y189809D02*
X1327564Y180063D01*
G01X1327626Y181250D02*
X1335787Y182915D01*
G01X1327564Y180063D02*
X1335787Y181741D01*
G01Y182915D02*
X1344459Y181150D01*
G01X1335787Y181741D02*
X1344459Y179976D01*
G01X1296689Y217172D02*
X1306050Y211010D01*
G01X1297510Y218010D02*
X1306548Y212059D01*
G01X1306050Y211010D02*
X1329124Y203752D01*
G01X1306548Y212059D02*
X1329186Y204939D01*
G01X1329124Y203752D02*
X1338170Y205594D01*
G01X1329186Y204939D02*
X1338170Y206768D01*
G01Y205594D02*
X1347089Y203779D01*
G01X1338170Y206768D02*
X1347089Y204953D01*
G01X1367736Y213629D02*
X1341326D01*
G01X1367368Y212479D02*
X1341803D01*
G01X1341326Y213629D02*
X1339831Y212134D01*
G01X1341803Y212479D02*
X1340308Y210984D01*
G01X1339831Y212134D02*
X1316681D01*
G01X1340308Y210984D02*
X1316501D01*
G01X1316681Y212134D02*
X1308170Y214853D01*
G01X1316501Y210984D02*
X1307668Y213806D01*
G01X1308170Y214853D02*
X1303343Y218048D01*
G01X1307668Y213806D02*
X1302522Y217212D01*
G01X1368226Y214979D02*
X1340136D01*
G01X1368594Y216129D02*
X1339659D01*
G01X1340136Y214979D02*
X1338641Y213484D01*
G01X1339659Y216129D02*
X1338164Y214634D01*
G01X1338641Y213484D02*
X1316932D01*
G01X1338164Y214634D02*
X1317112D01*
G01X1316932Y213484D02*
X1309161Y215972D01*
G01X1317112Y214634D02*
X1309664Y217019D01*
G01X1309161Y215972D02*
X1304111Y219315D01*
G01X1309664Y217019D02*
X1304932Y220151D01*
G01X1367368Y212479D02*
X1341803D01*
G01X1367736Y213629D02*
X1341326D01*
G01X1341803Y212479D02*
X1340308Y210984D01*
G01X1341326Y213629D02*
X1339831Y212134D01*
G01X1340308Y210984D02*
X1316501D01*
G01X1339831Y212134D02*
X1316681D01*
G01X1316501Y210984D02*
X1307668Y213806D01*
G01X1316681Y212134D02*
X1308170Y214853D01*
G01X1307668Y213806D02*
X1302522Y217212D01*
G01X1308170Y214853D02*
X1303343Y218048D01*
G01X1368594Y216129D02*
X1339659D01*
G01X1368226Y214979D02*
X1340136D01*
G01X1339659Y216129D02*
X1338164Y214634D01*
G01X1340136Y214979D02*
X1338641Y213484D01*
G01X1338164Y214634D02*
X1317112D01*
G01X1338641Y213484D02*
X1316932D01*
G01X1317112Y214634D02*
X1309664Y217019D01*
G01X1316932Y213484D02*
X1309161Y215972D01*
G01X1309664Y217019D02*
X1304932Y220151D01*
G01X1309161Y215972D02*
X1304111Y219315D01*
G01X1350849Y239948D02*
X1329651Y244071D01*
G01X1350827Y241124D02*
X1329630Y245247D01*
G01X1329651Y244071D02*
X1316818Y241091D01*
G01X1329630Y245247D02*
X1316795Y242267D01*
G01X1316818Y241091D02*
X1311153Y242171D01*
G01X1316795Y242267D02*
X1311589Y243259D01*
G01X1311153Y242171D02*
X1303124Y247370D01*
G01X1311589Y243259D02*
X1303942Y248211D01*
G01X1312179Y229791D02*
X1314116Y228914D01*
G01X1312945Y230707D02*
X1314365Y230064D01*
G01X1314116Y228914D02*
X1372948D01*
G01X1314365Y230064D02*
X1373136D01*
G01X1309347Y225081D02*
X1311300Y223789D01*
G01X1310168Y225917D02*
X1311646Y224939D01*
G01X1311300Y223789D02*
X1372163D01*
G01X1311646Y224939D02*
X1372351D01*
G01X1350827Y241124D02*
X1329630Y245247D01*
G01X1350849Y239948D02*
X1329651Y244071D01*
G01X1329630Y245247D02*
X1316795Y242267D01*
G01X1329651Y244071D02*
X1316818Y241091D01*
G01X1316795Y242267D02*
X1311589Y243259D01*
G01X1316818Y241091D02*
X1311153Y242171D01*
G01X1311589Y243259D02*
X1303942Y248211D01*
G01X1311153Y242171D02*
X1303124Y247370D01*
G01X1312945Y230707D02*
X1314365Y230064D01*
G01X1312179Y229791D02*
X1314116Y228914D01*
G01X1314365Y230064D02*
X1373136D01*
G01X1314116Y228914D02*
X1372948D01*
G01X1310168Y225917D02*
X1311646Y224939D01*
G01X1309347Y225081D02*
X1311300Y223789D01*
G01X1311646Y224939D02*
X1372351D01*
G01X1311300Y223789D02*
X1372163D01*
G01X1281731Y221464D02*
X1285601Y219885D01*
G01X1282484Y222399D02*
X1286354Y220820D01*
G01X1280830Y220373D02*
X1284655Y218812D01*
G01X1282484Y222399D02*
X1286354Y220820D01*
G01X1281731Y221464D02*
X1285601Y219885D01*
G01X1280830Y220373D02*
X1284655Y218812D01*
G01X1310964Y227144D02*
X1312253Y226293D01*
G01X1311785Y227980D02*
X1312599Y227443D01*
G01X1312253Y226293D02*
X1372561D01*
G01X1312599Y227443D02*
X1372749D01*
G01X1306809Y221973D02*
X1309963Y219886D01*
G01X1305988Y221136D02*
X1309617Y218736D01*
G01X1309963Y219886D02*
X1367923D01*
G01X1309617Y218736D02*
X1367555D01*
G01X1310306Y221286D02*
X1368714D01*
G01X1369080Y222436D02*
X1310653D01*
G01X1307765Y222967D02*
X1310306Y221286D01*
G01X1310653Y222436D02*
X1308586Y223804D01*
G01X1311785Y227980D02*
X1312599Y227443D01*
G01X1310964Y227144D02*
X1312253Y226293D01*
G01X1312599Y227443D02*
X1372749D01*
G01X1312253Y226293D02*
X1372561D01*
G01X1305988Y221136D02*
X1309617Y218736D01*
G01X1306809Y221973D02*
X1309963Y219886D01*
G01X1309617Y218736D02*
X1367555D01*
G01X1309963Y219886D02*
X1367923D01*
G01X1310653Y222436D02*
X1308586Y223804D01*
G01X1307765Y222967D02*
X1310306Y221286D01*
G01X1369080Y222436D02*
X1310653D01*
G01X1310306Y221286D02*
X1368714D01*
G01X1351084Y259000D02*
X1331531Y262808D01*
G01X1351062Y260176D02*
X1331974Y263894D01*
G01X1331531Y262808D02*
X1305863Y279706D01*
G01X1331974Y263894D02*
X1306684Y280544D01*
G01X1351330Y256393D02*
X1330527Y260445D01*
G01X1351308Y257569D02*
X1330970Y261531D01*
G01X1330527Y260445D02*
X1304118Y277827D01*
G01X1330963Y261536D02*
X1304939Y278665D01*
G01X1304118Y277827D02*
X1289247Y299445D01*
G01X1304939Y278665D02*
X1290265Y299996D01*
G01X1351545Y253792D02*
X1329292Y258126D01*
G01X1351523Y254968D02*
X1329735Y259212D01*
G01X1329292Y258126D02*
X1302507Y275754D01*
G01X1329735Y259212D02*
X1303328Y276592D01*
G01X1302507Y275754D02*
X1286849Y298516D01*
G01X1303328Y276592D02*
X1287867Y299067D01*
G01X1351685Y251206D02*
X1328220Y255775D01*
G01X1351664Y252382D02*
X1328663Y256861D01*
G01X1328220Y255775D02*
X1300799Y273821D01*
G01X1328663Y256861D02*
X1301620Y274659D01*
G01X1300799Y273821D02*
X1284568Y297416D01*
G01X1301620Y274659D02*
X1285585Y297968D01*
G01X1299160Y271789D02*
X1282303Y296293D01*
G01X1283320Y296845D02*
X1299981Y272627D01*
G01X1327027Y253450D02*
X1299160Y271789D01*
G01X1299981Y272627D02*
X1327470Y254536D01*
G01X1351783Y248628D02*
X1327027Y253450D01*
G01X1327470Y254536D02*
X1351762Y249804D01*
G01X1351958Y246035D02*
X1329553Y250391D01*
G01X1351936Y247211D02*
X1329532Y251567D01*
G01X1329553Y250391D02*
X1315915Y247231D01*
G01X1329532Y251567D02*
X1315894Y248407D01*
G01X1315915Y247231D02*
X1313313Y247737D01*
G01X1315894Y248407D02*
X1313756Y248823D01*
G01X1313313Y247737D02*
X1307001Y251891D01*
G01X1313756Y248823D02*
X1307823Y252728D01*
G01X1307001Y251891D02*
X1284184Y285060D01*
G01X1307823Y252728D02*
X1285201Y285612D01*
G01X1351985Y243471D02*
X1330375Y247671D01*
G01X1351963Y244647D02*
X1330351Y248848D01*
G01X1330375Y247671D02*
X1316420Y244439D01*
G01X1330351Y248848D02*
X1316399Y245615D01*
G01X1316420Y244439D02*
X1312351Y245231D01*
G01X1316399Y245615D02*
X1312789Y246318D01*
G01X1312351Y245231D02*
X1305297Y249795D01*
G01X1312789Y246318D02*
X1306115Y250637D01*
G01X1305297Y249795D02*
X1281963Y283718D01*
G01X1306115Y250637D02*
X1282981Y284269D01*
G01X1308485Y282355D02*
X1332937Y266261D01*
G01X1307664Y281517D02*
X1332494Y265175D01*
G01X1332937Y266261D02*
X1350921Y262762D01*
G01X1332494Y265175D02*
X1350943Y261586D01*
G01X1351062Y260176D02*
X1331974Y263894D01*
G01X1351084Y259000D02*
X1331531Y262808D01*
G01X1331974Y263894D02*
X1306684Y280544D01*
G01X1331531Y262808D02*
X1305863Y279706D01*
G01X1351308Y257569D02*
X1330970Y261531D01*
G01X1351330Y256393D02*
X1330527Y260445D01*
G01X1330963Y261536D02*
X1304939Y278665D01*
G01X1330527Y260445D02*
X1304118Y277827D01*
G01X1304939Y278665D02*
X1290265Y299996D01*
G01X1304118Y277827D02*
X1289247Y299445D01*
G01X1351523Y254968D02*
X1329735Y259212D01*
G01X1351545Y253792D02*
X1329292Y258126D01*
G01X1329735Y259212D02*
X1303328Y276592D01*
G01X1329292Y258126D02*
X1302507Y275754D01*
G01X1303328Y276592D02*
X1287867Y299067D01*
G01X1302507Y275754D02*
X1286849Y298516D01*
G01X1351664Y252382D02*
X1328663Y256861D01*
G01X1351685Y251206D02*
X1328220Y255775D01*
G01X1328663Y256861D02*
X1301620Y274659D01*
G01X1328220Y255775D02*
X1300799Y273821D01*
G01X1301620Y274659D02*
X1285585Y297968D01*
G01X1300799Y273821D02*
X1284568Y297416D01*
G01X1327470Y254536D02*
X1351762Y249804D01*
G01X1351783Y248628D02*
X1327027Y253450D01*
G01X1299981Y272627D02*
X1327470Y254536D01*
G01X1327027Y253450D02*
X1299160Y271789D01*
G01X1283320Y296845D02*
X1299981Y272627D01*
G01X1299160Y271789D02*
X1282303Y296293D01*
G01X1351936Y247211D02*
X1329532Y251567D01*
G01X1351958Y246035D02*
X1329553Y250391D01*
G01X1329532Y251567D02*
X1315894Y248407D01*
G01X1329553Y250391D02*
X1315915Y247231D01*
G01X1315894Y248407D02*
X1313756Y248823D01*
G01X1315915Y247231D02*
X1313313Y247737D01*
G01X1313756Y248823D02*
X1307823Y252728D01*
G01X1313313Y247737D02*
X1307001Y251891D01*
G01X1307823Y252728D02*
X1285201Y285612D01*
G01X1307001Y251891D02*
X1284184Y285060D01*
G01X1351963Y244647D02*
X1330351Y248848D01*
G01X1351985Y243471D02*
X1330375Y247671D01*
G01X1330351Y248848D02*
X1316399Y245615D01*
G01X1330375Y247671D02*
X1316420Y244439D01*
G01X1316399Y245615D02*
X1312789Y246318D01*
G01X1316420Y244439D02*
X1312351Y245231D01*
G01X1312789Y246318D02*
X1306115Y250637D01*
G01X1312351Y245231D02*
X1305297Y249795D01*
G01X1306115Y250637D02*
X1282981Y284269D01*
G01X1305297Y249795D02*
X1281963Y283718D01*
G01X1307664Y281517D02*
X1332494Y265175D01*
G01X1308485Y282355D02*
X1332937Y266261D01*
G01X1332494Y265175D02*
X1350943Y261586D01*
G01X1332937Y266261D02*
X1350921Y262762D01*
G01X1305863Y279706D02*
X1291560Y300497D01*
G01X1306684Y280544D02*
X1292577Y301050D01*
G01X1295975Y300545D02*
X1308485Y282355D01*
G01X1295027Y299893D02*
X1307664Y281517D01*
G01X1306684Y280544D02*
X1292577Y301050D01*
G01X1305863Y279706D02*
X1291560Y300497D01*
G01X1295027Y299893D02*
X1307664Y281517D01*
G01X1295975Y300545D02*
X1308485Y282355D01*
G01X1343877Y317750D02*
X1341825D01*
G01X1343400Y316600D02*
X1341825D01*
G01X1343400D02*
X1341825D01*
G01X1343877Y317750D02*
X1341825D01*
G01X1342068Y644894D02*
X1341547Y644530D01*
G01D02*
X1340515Y644712D01*
G01X1343118Y644224D02*
X1341816Y643314D01*
G01X1341547Y644530D02*
X1340515Y644712D01*
G01X1341816Y643314D02*
X1339845Y643661D01*
G01X1340515Y644712D02*
X1340150Y645234D01*
G01X1339845Y643661D02*
X1338934Y644965D01*
G01X1340150Y645234D02*
X1341577Y653318D01*
G01X1338934Y644965D02*
X1340361Y653049D01*
G01X1337389Y654059D02*
X1335776Y644895D01*
G01X1338439Y653389D02*
X1336827Y644224D01*
G01X1335776Y644895D02*
X1335252Y644530D01*
G01D02*
X1334220Y644710D01*
G01X1336827Y644224D02*
X1335521Y643315D01*
G01X1335252Y644530D02*
X1334220Y644710D01*
G01X1335521Y643315D02*
X1333550Y643659D01*
G01X1334220Y644710D02*
X1333855Y645234D01*
G01X1333550Y643659D02*
X1332639Y644966D01*
G01X1333855Y645234D02*
X1335287Y653351D01*
G01X1332639Y644966D02*
X1334071Y653082D01*
G01X1331099Y654092D02*
X1329484Y644926D01*
G01X1332149Y653422D02*
X1330534Y644257D01*
G01X1329484Y644926D02*
X1328924Y644534D01*
G01D02*
X1327956Y644704D01*
G01X1330534Y644257D02*
X1329194Y643318D01*
G01X1328924Y644534D02*
X1327956Y644704D01*
G01X1329194Y643318D02*
X1327286Y643653D01*
G01X1327956Y644704D02*
X1327565Y645264D01*
G01X1327286Y643653D02*
X1326349Y644995D01*
G01X1327565Y645264D02*
X1328991Y653351D01*
G01X1326349Y644995D02*
X1327775Y653082D01*
G01X1324805Y654091D02*
X1323167Y644831D01*
G01X1325855Y653421D02*
X1324217Y644161D01*
G01X1323167Y644831D02*
X1322645Y644466D01*
G01D02*
X1321611Y644648D01*
G01X1324217Y644161D02*
X1322914Y643251D01*
G01X1322645Y644466D02*
X1321611Y644648D01*
G01X1322914Y643251D02*
X1320941Y643598D01*
G01X1321611Y644648D02*
X1321247Y645170D01*
G01X1320941Y643598D02*
X1320031Y644901D01*
G01X1321247Y645170D02*
X1322724Y653548D01*
G01X1320031Y644901D02*
X1321508Y653279D01*
G01X1318539Y654286D02*
X1316873Y644830D01*
G01X1319589Y653617D02*
X1317923Y644160D01*
G01X1316873Y644830D02*
X1316351Y644466D01*
G01D02*
X1315316Y644648D01*
G01X1317923Y644160D02*
X1316620Y643251D01*
G01X1316351Y644466D02*
X1315316Y644648D01*
G01X1316620Y643251D02*
X1314646Y643597D01*
G01X1315316Y644648D02*
X1314951Y645170D01*
G01X1314646Y643597D02*
X1313735Y644901D01*
G01X1314951Y645170D02*
X1316437Y653594D01*
G01X1313735Y644901D02*
X1315221Y653326D01*
G01X1312249Y654336D02*
X1310583Y644863D01*
G01X1313300Y653665D02*
X1311633Y644193D01*
G01X1310583Y644863D02*
X1310061Y644499D01*
G01D02*
X1309026Y644681D01*
G01X1311633Y644193D02*
X1310330Y643284D01*
G01X1310061Y644499D02*
X1309026Y644681D01*
G01X1310330Y643284D02*
X1308356Y643630D01*
G01X1309026Y644681D02*
X1308661Y645203D01*
G01X1308356Y643630D02*
X1307445Y644934D01*
G01X1308661Y645203D02*
X1310139Y653578D01*
G01X1307445Y644934D02*
X1308923Y653309D01*
G01X1305955Y654319D02*
X1304286Y644863D01*
G01X1307005Y653649D02*
X1305336Y644193D01*
G01X1304286Y644863D02*
X1303764Y644499D01*
G01D02*
X1302730Y644680D01*
G01X1305336Y644193D02*
X1304033Y643284D01*
G01X1303764Y644499D02*
X1302730Y644680D01*
G01X1304033Y643284D02*
X1302060Y643629D01*
G01X1302730Y644680D02*
X1302366Y645201D01*
G01X1302060Y643629D02*
X1301150Y644932D01*
G01X1302366Y645201D02*
X1303843Y653577D01*
G01X1301150Y644932D02*
X1302627Y653309D01*
G01X1299656Y654314D02*
X1297988Y644845D01*
G01X1300707Y653645D02*
X1299038Y644175D01*
G01X1297988Y644845D02*
X1297466Y644480D01*
G01D02*
X1296432Y644663D01*
G01X1299038Y644175D02*
X1297735Y643265D01*
G01X1297466Y644480D02*
X1296432Y644663D01*
G01X1297735Y643265D02*
X1295762Y643613D01*
G01X1296432Y644663D02*
X1296069Y645185D01*
G01X1295762Y643613D02*
X1294853Y644914D01*
G01X1296069Y645185D02*
X1297569Y653692D01*
G01X1294853Y644914D02*
X1296353Y653422D01*
G01X1293380Y654426D02*
X1291690Y644845D01*
G01X1294431Y653758D02*
X1292740Y644176D01*
G01X1291690Y644845D02*
X1291170Y644481D01*
G01D02*
X1290136Y644663D01*
G01X1292740Y644176D02*
X1291440Y643265D01*
G01X1291170Y644481D02*
X1290136Y644663D01*
G01X1291440Y643265D02*
X1289466Y643612D01*
G01X1290136Y644663D02*
X1289772Y645184D01*
G01X1289466Y643612D02*
X1288556Y644915D01*
G01X1289772Y645184D02*
X1291272Y653695D01*
G01X1288556Y644915D02*
X1290056Y653424D01*
G01X1287085Y654431D02*
X1285402Y644879D01*
G01X1288135Y653761D02*
X1286453Y644209D01*
G01X1285402Y644879D02*
X1284879Y644514D01*
G01D02*
X1283845Y644696D01*
G01X1286453Y644209D02*
X1285149Y643299D01*
G01X1284879Y644514D02*
X1283845Y644696D01*
G01X1285149Y643299D02*
X1283175Y643645D01*
G01X1283845Y644696D02*
X1283481Y645217D01*
G01X1283175Y643645D02*
X1282265Y644948D01*
G01X1283481Y645217D02*
X1284972Y653673D01*
G01X1282265Y644948D02*
X1283756Y653404D01*
G01X1343118Y644224D02*
X1341816Y643314D01*
G01X1342068Y644894D02*
X1341547Y644530D01*
G01X1343118Y644224D02*
X1341816Y643314D01*
G01D02*
X1339845Y643661D01*
G01X1341547Y644530D02*
X1340515Y644712D01*
G01X1339845Y643661D02*
X1338934Y644965D01*
G01X1340515Y644712D02*
X1340150Y645234D01*
G01X1338934Y644965D02*
X1340361Y653049D01*
G01X1340150Y645234D02*
X1341577Y653318D01*
G01X1338439Y653389D02*
X1336827Y644224D01*
G01X1337389Y654059D02*
X1335776Y644895D01*
G01X1336827Y644224D02*
X1335521Y643315D01*
G01X1335776Y644895D02*
X1335252Y644530D01*
G01X1336827Y644224D02*
X1335521Y643315D01*
G01D02*
X1333550Y643659D01*
G01X1335252Y644530D02*
X1334220Y644710D01*
G01X1333550Y643659D02*
X1332639Y644966D01*
G01X1334220Y644710D02*
X1333855Y645234D01*
G01X1332639Y644966D02*
X1334071Y653082D01*
G01X1333855Y645234D02*
X1335287Y653351D01*
G01X1332149Y653422D02*
X1330534Y644257D01*
G01X1331099Y654092D02*
X1329484Y644926D01*
G01X1330534Y644257D02*
X1329194Y643318D01*
G01X1329484Y644926D02*
X1328924Y644534D01*
G01X1330534Y644257D02*
X1329194Y643318D01*
G01D02*
X1327286Y643653D01*
G01X1328924Y644534D02*
X1327956Y644704D01*
G01X1327286Y643653D02*
X1326349Y644995D01*
G01X1327956Y644704D02*
X1327565Y645264D01*
G01X1326349Y644995D02*
X1327775Y653082D01*
G01X1327565Y645264D02*
X1328991Y653351D01*
G01X1325855Y653421D02*
X1324217Y644161D01*
G01X1324805Y654091D02*
X1323167Y644831D01*
G01X1324217Y644161D02*
X1322914Y643251D01*
G01X1323167Y644831D02*
X1322645Y644466D01*
G01X1324217Y644161D02*
X1322914Y643251D01*
G01D02*
X1320941Y643598D01*
G01X1322645Y644466D02*
X1321611Y644648D01*
G01X1320941Y643598D02*
X1320031Y644901D01*
G01X1321611Y644648D02*
X1321247Y645170D01*
G01X1320031Y644901D02*
X1321508Y653279D01*
G01X1321247Y645170D02*
X1322724Y653548D01*
G01X1319589Y653617D02*
X1317923Y644160D01*
G01X1318539Y654286D02*
X1316873Y644830D01*
G01X1317923Y644160D02*
X1316620Y643251D01*
G01X1316873Y644830D02*
X1316351Y644466D01*
G01X1317923Y644160D02*
X1316620Y643251D01*
G01D02*
X1314646Y643597D01*
G01X1316351Y644466D02*
X1315316Y644648D01*
G01X1314646Y643597D02*
X1313735Y644901D01*
G01X1315316Y644648D02*
X1314951Y645170D01*
G01X1313735Y644901D02*
X1315221Y653326D01*
G01X1314951Y645170D02*
X1316437Y653594D01*
G01X1313300Y653665D02*
X1311633Y644193D01*
G01X1312249Y654336D02*
X1310583Y644863D01*
G01X1311633Y644193D02*
X1310330Y643284D01*
G01X1310583Y644863D02*
X1310061Y644499D01*
G01X1311633Y644193D02*
X1310330Y643284D01*
G01D02*
X1308356Y643630D01*
G01X1310061Y644499D02*
X1309026Y644681D01*
G01X1308356Y643630D02*
X1307445Y644934D01*
G01X1309026Y644681D02*
X1308661Y645203D01*
G01X1307445Y644934D02*
X1308923Y653309D01*
G01X1308661Y645203D02*
X1310139Y653578D01*
G01X1307005Y653649D02*
X1305336Y644193D01*
G01X1305955Y654319D02*
X1304286Y644863D01*
G01X1305336Y644193D02*
X1304033Y643284D01*
G01X1304286Y644863D02*
X1303764Y644499D01*
G01X1305336Y644193D02*
X1304033Y643284D01*
G01D02*
X1302060Y643629D01*
G01X1303764Y644499D02*
X1302730Y644680D01*
G01X1302060Y643629D02*
X1301150Y644932D01*
G01X1302730Y644680D02*
X1302366Y645201D01*
G01X1301150Y644932D02*
X1302627Y653309D01*
G01X1302366Y645201D02*
X1303843Y653577D01*
G01X1300707Y653645D02*
X1299038Y644175D01*
G01X1299656Y654314D02*
X1297988Y644845D01*
G01X1299038Y644175D02*
X1297735Y643265D01*
G01X1297988Y644845D02*
X1297466Y644480D01*
G01X1299038Y644175D02*
X1297735Y643265D01*
G01D02*
X1295762Y643613D01*
G01X1297466Y644480D02*
X1296432Y644663D01*
G01X1295762Y643613D02*
X1294853Y644914D01*
G01X1296432Y644663D02*
X1296069Y645185D01*
G01X1294853Y644914D02*
X1296353Y653422D01*
G01X1296069Y645185D02*
X1297569Y653692D01*
G01X1294431Y653758D02*
X1292740Y644176D01*
G01X1293380Y654426D02*
X1291690Y644845D01*
G01X1292740Y644176D02*
X1291440Y643265D01*
G01X1291690Y644845D02*
X1291170Y644481D01*
G01X1292740Y644176D02*
X1291440Y643265D01*
G01D02*
X1289466Y643612D01*
G01X1291170Y644481D02*
X1290136Y644663D01*
G01X1289466Y643612D02*
X1288556Y644915D01*
G01X1290136Y644663D02*
X1289772Y645184D01*
G01X1288556Y644915D02*
X1290056Y653424D01*
G01X1289772Y645184D02*
X1291272Y653695D01*
G01X1288135Y653761D02*
X1286453Y644209D01*
G01X1287085Y654431D02*
X1285402Y644879D01*
G01X1286453Y644209D02*
X1285149Y643299D01*
G01X1285402Y644879D02*
X1284879Y644514D01*
G01X1286453Y644209D02*
X1285149Y643299D01*
G01D02*
X1283175Y643645D01*
G01X1284879Y644514D02*
X1283845Y644696D01*
G01X1283175Y643645D02*
X1282265Y644948D01*
G01X1283845Y644696D02*
X1283481Y645217D01*
G01X1282265Y644948D02*
X1283756Y653404D01*
G01X1283481Y645217D02*
X1284972Y653673D01*
G01X1341577Y653318D02*
X1340666Y654622D01*
G01X1340361Y653049D02*
X1339996Y653571D01*
G01X1340666Y654622D02*
X1338692Y654968D01*
G01D02*
X1337389Y654059D01*
G01X1339996Y653571D02*
X1338961Y653753D01*
G01X1338692Y654968D02*
X1337389Y654059D01*
G01X1338961Y653753D02*
X1338439Y653389D01*
G01X1335287Y653351D02*
X1334376Y654655D01*
G01X1334071Y653082D02*
X1333706Y653604D01*
G01X1334376Y654655D02*
X1332402Y655001D01*
G01D02*
X1331099Y654092D01*
G01X1333706Y653604D02*
X1332671Y653786D01*
G01X1332402Y655001D02*
X1331099Y654092D01*
G01X1332671Y653786D02*
X1332149Y653422D01*
G01X1328991Y653351D02*
X1328081Y654654D01*
G01X1327775Y653082D02*
X1327411Y653604D01*
G01X1328081Y654654D02*
X1326108Y655001D01*
G01D02*
X1324805Y654091D01*
G01X1327411Y653604D02*
X1326377Y653786D01*
G01X1326108Y655001D02*
X1324805Y654091D01*
G01X1326377Y653786D02*
X1325855Y653421D01*
G01X1322724Y653548D02*
X1321787Y654890D01*
G01X1321508Y653279D02*
X1321117Y653839D01*
G01X1321787Y654890D02*
X1319879Y655225D01*
G01D02*
X1318539Y654286D01*
G01X1321117Y653839D02*
X1320149Y654009D01*
G01X1319879Y655225D02*
X1318539Y654286D01*
G01X1320149Y654009D02*
X1319589Y653617D01*
G01X1316437Y653594D02*
X1315526Y654901D01*
G01X1315221Y653326D02*
X1314856Y653850D01*
G01X1315526Y654901D02*
X1313555Y655245D01*
G01D02*
X1312249Y654336D01*
G01X1314856Y653850D02*
X1313824Y654030D01*
G01X1313555Y655245D02*
X1312249Y654336D01*
G01X1313824Y654030D02*
X1313300Y653665D01*
G01X1310139Y653578D02*
X1309228Y654882D01*
G01X1308923Y653309D02*
X1308558Y653831D01*
G01X1309228Y654882D02*
X1307257Y655229D01*
G01D02*
X1305955Y654319D01*
G01X1308558Y653831D02*
X1307526Y654013D01*
G01X1307257Y655229D02*
X1305955Y654319D01*
G01X1307526Y654013D02*
X1307005Y653649D01*
G01X1303843Y653577D02*
X1302933Y654882D01*
G01X1302627Y653309D02*
X1302263Y653831D01*
G01X1302933Y654882D02*
X1300959Y655228D01*
G01D02*
X1299656Y654314D01*
G01X1302263Y653831D02*
X1301230Y654012D01*
G01X1300959Y655228D02*
X1299656Y654314D01*
G01X1301230Y654012D02*
X1300707Y653645D01*
G01X1297569Y653692D02*
X1296657Y654993D01*
G01X1296353Y653422D02*
X1295988Y653943D01*
G01X1296657Y654993D02*
X1294683Y655342D01*
G01D02*
X1293380Y654426D01*
G01X1295988Y653943D02*
X1294954Y654126D01*
G01X1294683Y655342D02*
X1293380Y654426D01*
G01X1294954Y654126D02*
X1294431Y653758D01*
G01X1291272Y653695D02*
X1290357Y654995D01*
G01X1290056Y653424D02*
X1289690Y653944D01*
G01X1290357Y654995D02*
X1288388Y655340D01*
G01D02*
X1287085Y654431D01*
G01X1289690Y653944D02*
X1288657Y654125D01*
G01X1288388Y655340D02*
X1287085Y654431D01*
G01X1288657Y654125D02*
X1288135Y653761D01*
G01X1284972Y653673D02*
X1284060Y654977D01*
G01X1283756Y653404D02*
X1283391Y653926D01*
G01X1284060Y654977D02*
X1282088Y655322D01*
G01D02*
X1280785Y654412D01*
G01X1283391Y653926D02*
X1282358Y654107D01*
G01X1282088Y655322D02*
X1280785Y654412D01*
G01X1282358Y654107D02*
X1281836Y653742D01*
G01X1340361Y653049D02*
X1339996Y653571D01*
G01X1341577Y653318D02*
X1340666Y654622D01*
G01X1339996Y653571D02*
X1338961Y653753D01*
G01X1340666Y654622D02*
X1338692Y654968D01*
G01X1339996Y653571D02*
X1338961Y653753D01*
G01D02*
X1338439Y653389D01*
G01X1338692Y654968D02*
X1337389Y654059D01*
G01X1334071Y653082D02*
X1333706Y653604D01*
G01X1335287Y653351D02*
X1334376Y654655D01*
G01X1333706Y653604D02*
X1332671Y653786D01*
G01X1334376Y654655D02*
X1332402Y655001D01*
G01X1333706Y653604D02*
X1332671Y653786D01*
G01D02*
X1332149Y653422D01*
G01X1332402Y655001D02*
X1331099Y654092D01*
G01X1327775Y653082D02*
X1327411Y653604D01*
G01X1328991Y653351D02*
X1328081Y654654D01*
G01X1327411Y653604D02*
X1326377Y653786D01*
G01X1328081Y654654D02*
X1326108Y655001D01*
G01X1327411Y653604D02*
X1326377Y653786D01*
G01D02*
X1325855Y653421D01*
G01X1326108Y655001D02*
X1324805Y654091D01*
G01X1321508Y653279D02*
X1321117Y653839D01*
G01X1322724Y653548D02*
X1321787Y654890D01*
G01X1321117Y653839D02*
X1320149Y654009D01*
G01X1321787Y654890D02*
X1319879Y655225D01*
G01X1321117Y653839D02*
X1320149Y654009D01*
G01D02*
X1319589Y653617D01*
G01X1319879Y655225D02*
X1318539Y654286D01*
G01X1315221Y653326D02*
X1314856Y653850D01*
G01X1316437Y653594D02*
X1315526Y654901D01*
G01X1314856Y653850D02*
X1313824Y654030D01*
G01X1315526Y654901D02*
X1313555Y655245D01*
G01X1314856Y653850D02*
X1313824Y654030D01*
G01D02*
X1313300Y653665D01*
G01X1313555Y655245D02*
X1312249Y654336D01*
G01X1308923Y653309D02*
X1308558Y653831D01*
G01X1310139Y653578D02*
X1309228Y654882D01*
G01X1308558Y653831D02*
X1307526Y654013D01*
G01X1309228Y654882D02*
X1307257Y655229D01*
G01X1308558Y653831D02*
X1307526Y654013D01*
G01D02*
X1307005Y653649D01*
G01X1307257Y655229D02*
X1305955Y654319D01*
G01X1302627Y653309D02*
X1302263Y653831D01*
G01X1303843Y653577D02*
X1302933Y654882D01*
G01X1302263Y653831D02*
X1301230Y654012D01*
G01X1302933Y654882D02*
X1300959Y655228D01*
G01X1302263Y653831D02*
X1301230Y654012D01*
G01D02*
X1300707Y653645D01*
G01X1300959Y655228D02*
X1299656Y654314D01*
G01X1296353Y653422D02*
X1295988Y653943D01*
G01X1297569Y653692D02*
X1296657Y654993D01*
G01X1295988Y653943D02*
X1294954Y654126D01*
G01X1296657Y654993D02*
X1294683Y655342D01*
G01X1295988Y653943D02*
X1294954Y654126D01*
G01D02*
X1294431Y653758D01*
G01X1294683Y655342D02*
X1293380Y654426D01*
G01X1290056Y653424D02*
X1289690Y653944D01*
G01X1291272Y653695D02*
X1290357Y654995D01*
G01X1289690Y653944D02*
X1288657Y654125D01*
G01X1290357Y654995D02*
X1288388Y655340D01*
G01X1289690Y653944D02*
X1288657Y654125D01*
G01D02*
X1288135Y653761D01*
G01X1288388Y655340D02*
X1287085Y654431D01*
G01X1283756Y653404D02*
X1283391Y653926D01*
G01X1284972Y653673D02*
X1284060Y654977D01*
G01X1283391Y653926D02*
X1282358Y654107D01*
G01X1284060Y654977D02*
X1282088Y655322D01*
G01X1283391Y653926D02*
X1282358Y654107D01*
G01D02*
X1281836Y653742D01*
G01X1282088Y655322D02*
X1280785Y654412D01*
G01X1401961Y128159D02*
X1418641Y103140D01*
G01X1419720Y103595D02*
X1402791Y128989D01*
G01X1395886Y132210D02*
X1401961Y128159D01*
G01X1402791Y128989D02*
X1396326Y133299D01*
G01X1365452Y137777D02*
X1395886Y132210D01*
G01X1396326Y133299D02*
X1365436Y138950D01*
G01X1358649Y136335D02*
X1365452Y137777D01*
G01X1365436Y138950D02*
X1358527Y137485D01*
G01X1343543Y136335D02*
X1358649D01*
G01X1358527Y137485D02*
X1344020D01*
G01X1404625Y130834D02*
X1397316Y135707D01*
G01X1403795Y130004D02*
X1396874Y134618D01*
G01X1397316Y135707D02*
X1365207Y141638D01*
G01X1396874Y134618D02*
X1365222Y140465D01*
G01X1365207Y141638D02*
X1357885Y140092D01*
G01X1365222Y140465D02*
X1358005Y138942D01*
G01X1357885Y140092D02*
X1345755D01*
G01X1358005Y138942D02*
X1345278D01*
G01X1345755Y140092D02*
X1343102Y142745D01*
G01D02*
Y156247D01*
G01X1358527Y137485D02*
X1344020D01*
G01X1343543Y136335D02*
X1358649D01*
G01X1365436Y138950D02*
X1358527Y137485D01*
G01X1358649Y136335D02*
X1365452Y137777D01*
G01X1396326Y133299D02*
X1365436Y138950D01*
G01X1365452Y137777D02*
X1395886Y132210D01*
G01X1402791Y128989D02*
X1396326Y133299D01*
G01X1395886Y132210D02*
X1401961Y128159D01*
G01X1419720Y103595D02*
X1402791Y128989D01*
G01X1401961Y128159D02*
X1418641Y103140D01*
G01X1403795Y130004D02*
X1396874Y134618D01*
G01X1404625Y130834D02*
X1397316Y135707D01*
G01X1396874Y134618D02*
X1365222Y140465D01*
G01X1397316Y135707D02*
X1365207Y141638D01*
G01X1365222Y140465D02*
X1358005Y138942D01*
G01X1365207Y141638D02*
X1357885Y140092D01*
G01X1358005Y138942D02*
X1345278D01*
G01X1357885Y140092D02*
X1345755D01*
G01D02*
X1343102Y142745D01*
G01D02*
Y156247D01*
G01X1411062Y137556D02*
X1398605Y145871D01*
G01X1411892Y138386D02*
X1399393Y146728D01*
G01X1398605Y145871D02*
X1393771Y151945D01*
G01X1399393Y146728D02*
X1394845Y152444D01*
G01X1393771Y151945D02*
X1392072Y160445D01*
G01X1394845Y152444D02*
X1393200Y160670D01*
G01X1393771Y151945D02*
X1392072Y160445D01*
G01X1409371Y135544D02*
X1395712Y144649D01*
G01X1410201Y136374D02*
X1396500Y145506D01*
G01X1395712Y144649D02*
X1386245Y156540D01*
G01X1396500Y145506D02*
X1386971Y157476D01*
G01X1407479Y133781D02*
X1392726Y143616D01*
G01X1408309Y134611D02*
X1393516Y144473D01*
G01X1392726Y143616D02*
X1386355Y151660D01*
G01X1393516Y144473D02*
X1387072Y152609D01*
G01X1386355Y151660D02*
X1385716Y151925D01*
G01X1387072Y152609D02*
X1385945Y153075D01*
G01X1385716Y151925D02*
X1353652D01*
G01X1385945Y153075D02*
X1354129D01*
G01X1353652Y151925D02*
X1352237Y153340D01*
G01X1354129Y153075D02*
X1353387Y153817D01*
G01X1352237Y153340D02*
Y165963D01*
G01X1353387Y153817D02*
Y166440D01*
G01X1406488Y132690D02*
X1390170Y143570D01*
G01X1405658Y131860D02*
X1392704Y140497D01*
G01X1406488Y132690D02*
X1390170Y143570D01*
G01X1392704Y140497D02*
X1391803Y140317D01*
G01X1406488Y132690D02*
X1390170Y143570D01*
G01X1390499Y141967D02*
X1389376Y142716D01*
G01X1390170Y143570D02*
X1387359Y147188D01*
G01X1389376Y142716D02*
X1386637Y146241D01*
G01X1387359Y147188D02*
X1385212Y148075D01*
G01X1386637Y146241D02*
X1384983Y146925D01*
G01X1385212Y148075D02*
X1348536D01*
G01X1384983Y146925D02*
X1348059D01*
G01X1348536Y148075D02*
X1348086Y148525D01*
G01X1348059Y146925D02*
X1346936Y148048D01*
G01X1348086Y148525D02*
Y161727D01*
G01X1346936Y148048D02*
Y161250D01*
G01X1411892Y138386D02*
X1399393Y146728D01*
G01X1411062Y137556D02*
X1398605Y145871D01*
G01X1399393Y146728D02*
X1394845Y152444D01*
G01X1398605Y145871D02*
X1393771Y151945D01*
G01X1394845Y152444D02*
X1393200Y160670D01*
G01X1393771Y151945D02*
X1392072Y160445D01*
G01X1410201Y136374D02*
X1396500Y145506D01*
G01X1409371Y135544D02*
X1395712Y144649D01*
G01X1396500Y145506D02*
X1386971Y157476D01*
G01X1395712Y144649D02*
X1386245Y156540D01*
G01X1408309Y134611D02*
X1393516Y144473D01*
G01X1407479Y133781D02*
X1392726Y143616D01*
G01X1393516Y144473D02*
X1387072Y152609D01*
G01X1392726Y143616D02*
X1386355Y151660D01*
G01X1387072Y152609D02*
X1385945Y153075D01*
G01X1386355Y151660D02*
X1385716Y151925D01*
G01X1385945Y153075D02*
X1354129D01*
G01X1385716Y151925D02*
X1353652D01*
G01X1354129Y153075D02*
X1353387Y153817D01*
G01X1353652Y151925D02*
X1352237Y153340D01*
G01X1353387Y153817D02*
Y166440D01*
G01X1352237Y153340D02*
Y165963D01*
G01X1405658Y131860D02*
X1392704Y140497D01*
G01D02*
X1391803Y140317D01*
G01X1390499Y141967D02*
X1389376Y142716D01*
G01X1406488Y132690D02*
X1390170Y143570D01*
G01X1389376Y142716D02*
X1386637Y146241D01*
G01X1390170Y143570D02*
X1387359Y147188D01*
G01X1386637Y146241D02*
X1384983Y146925D01*
G01X1387359Y147188D02*
X1385212Y148075D01*
G01X1384983Y146925D02*
X1348059D01*
G01X1385212Y148075D02*
X1348536D01*
G01X1348059Y146925D02*
X1346936Y148048D01*
G01X1348536Y148075D02*
X1348086Y148525D01*
G01X1346936Y148048D02*
Y161250D01*
G01X1348086Y148525D02*
Y161727D01*
G01X1380480Y220997D02*
X1393204Y211997D01*
G01X1381007Y222034D02*
X1393669Y213077D01*
G01X1380480Y220997D02*
X1393204Y211997D01*
G01D02*
X1394778Y211683D01*
G01D02*
X1403354Y213626D01*
G01X1393669Y213077D02*
X1394763Y212859D01*
G01X1394778Y211683D02*
X1403354Y213626D01*
G01X1394763Y212859D02*
X1403414Y214819D01*
G01X1403354Y213626D02*
X1410453Y211243D01*
G01X1403414Y214819D02*
X1410981Y212279D01*
G01X1381007Y222034D02*
X1393669Y213077D01*
G01D02*
X1394763Y212859D01*
G01X1380480Y220997D02*
X1393204Y211997D01*
G01X1393669Y213077D02*
X1394763Y212859D01*
G01X1393204Y211997D02*
X1394778Y211683D01*
G01X1393669Y213077D02*
X1394763Y212859D01*
G01D02*
X1403414Y214819D01*
G01X1394778Y211683D02*
X1403354Y213626D01*
G01X1403414Y214819D02*
X1410981Y212279D01*
G01X1403354Y213626D02*
X1410453Y211243D01*
G01X1393201Y160670D02*
X1393156Y160895D01*
G01X1392072Y160445D02*
X1391786Y160874D01*
G01X1393156Y160895D02*
X1392744Y161511D01*
G01X1392072Y160445D02*
X1391786Y160874D01*
G01X1392744Y161512D02*
X1392607Y161716D01*
G01X1391786Y160874D02*
X1390478Y161700D01*
G01X1392607Y161716D02*
X1390811Y162850D01*
G01X1390478Y161700D02*
X1363954D01*
G01X1390811Y162850D02*
X1364431D01*
G01X1363954Y161700D02*
X1362146Y163508D01*
G01X1364431Y162850D02*
X1363296Y163985D01*
G01X1362146Y163508D02*
Y170594D01*
G01X1363296Y163985D02*
Y170710D01*
G01X1362146Y170594D02*
X1361366Y174425D01*
G01X1363296Y170710D02*
X1362449Y174874D01*
G01X1361366Y174425D02*
X1359385Y177418D01*
G01X1362449Y174874D02*
X1360104Y178416D01*
G01X1359385Y177418D02*
X1353033Y179121D01*
G01X1360104Y178416D02*
X1353069Y180302D01*
G01X1353033Y179121D02*
X1344201Y177324D01*
G01X1353069Y180302D02*
X1344201Y178498D01*
G01X1386245Y156540D02*
X1385387Y156925D01*
G01X1386971Y157476D02*
X1385634Y158075D01*
G01X1385387Y156925D02*
X1358849D01*
G01X1385634Y158075D02*
X1359326D01*
G01X1358849Y156925D02*
X1357134Y158640D01*
G01X1359326Y158075D02*
X1358284Y159117D01*
G01X1357134Y158640D02*
Y170800D01*
G01X1358284Y159117D02*
Y170916D01*
G01X1357134Y170800D02*
X1356494Y173941D01*
G01X1358284Y170916D02*
X1357577Y174390D01*
G01X1356494Y173941D02*
X1355471Y175486D01*
G01X1357577Y174390D02*
X1356190Y176485D01*
G01X1355471Y175486D02*
X1352659Y176240D01*
G01X1356190Y176485D02*
X1352695Y177421D01*
G01X1352659Y176240D02*
X1344447Y174570D01*
G01X1352695Y177421D02*
X1344447Y175744D01*
G01X1352237Y165963D02*
X1351200Y167000D01*
G01X1353387Y166440D02*
X1351677Y168150D01*
G01X1351200Y167000D02*
X1343300D01*
G01X1351677Y168150D02*
X1343777D01*
G01D02*
X1343150Y168777D01*
G01X1342000Y168300D02*
Y172089D01*
G01X1343150Y168777D02*
Y172566D01*
G01D02*
X1342309Y173407D01*
G01X1348086Y161727D02*
X1346963Y162850D01*
G01X1346936Y161250D02*
X1346486Y161700D01*
G01X1346770Y201139D02*
X1354297Y202671D01*
G01X1346770Y202313D02*
X1354333Y203852D01*
G01X1354297Y202671D02*
X1412982Y186936D01*
G01X1354333Y203852D02*
X1413461Y187999D01*
G01X1346453Y198500D02*
X1354187Y200073D01*
G01X1346453Y199674D02*
X1354223Y201254D01*
G01X1354187Y200073D02*
X1411654Y184667D01*
G01X1354223Y201254D02*
X1354484Y201185D01*
G01X1354187Y200073D02*
X1411654Y184667D01*
G01X1354484Y201184D02*
X1412133Y185730D01*
G01X1346233Y195840D02*
X1354199Y197462D01*
G01X1346233Y197014D02*
X1354235Y198643D01*
G01X1354199Y197462D02*
X1410233Y182444D01*
G01X1354235Y198643D02*
X1410712Y183507D01*
G01X1345931Y193198D02*
X1354079Y194856D01*
G01X1345931Y194372D02*
X1354115Y196037D01*
G01X1354079Y194856D02*
X1409271Y180062D01*
G01X1354115Y196037D02*
X1409300Y181245D01*
G01X1354079Y194856D02*
X1409271Y180062D01*
G01X1345658Y190549D02*
X1354075Y192263D01*
G01X1345658Y191723D02*
X1354111Y193444D01*
G01X1354075Y192263D02*
X1407748Y177877D01*
G01X1354111Y193444D02*
X1408227Y178940D01*
G01X1354013Y190845D02*
X1407033Y176633D01*
G01X1406554Y175570D02*
X1353977Y189664D01*
G01X1345348Y189082D02*
X1354013Y190845D01*
G01X1353977Y189664D02*
X1345348Y187908D01*
G01X1405216Y173289D02*
X1353816Y187065D01*
G01X1405695Y174352D02*
X1353852Y188246D01*
G01X1353816Y187065D02*
X1345004Y185273D01*
G01X1353852Y188246D02*
X1345004Y186447D01*
G01X1344689Y182633D02*
X1353622Y184450D01*
G01X1344689Y183807D02*
X1353658Y185631D01*
G01X1353622Y184450D02*
X1404088Y170923D01*
G01X1353658Y185631D02*
X1404567Y171986D01*
G01X1344459Y179976D02*
X1353341Y181782D01*
G01X1344459Y181150D02*
X1353377Y182963D01*
G01X1353341Y181782D02*
X1403324Y168384D01*
G01X1353377Y182963D02*
X1403803Y169447D01*
G01X1403324Y168384D02*
X1406760Y166109D01*
G01X1347089Y204953D02*
X1355060Y206575D01*
G01X1347089Y203779D02*
X1355021Y205393D01*
G01X1355060Y206575D02*
X1414511Y190354D01*
G01X1355021Y205393D02*
X1414030Y189293D01*
G01X1393201Y160670D02*
X1393156Y160895D01*
G01D02*
X1392744Y161511D01*
G01Y161512D02*
X1392607Y161716D01*
G01X1392072Y160445D02*
X1391786Y160874D01*
G01X1392607Y161716D02*
X1390811Y162850D01*
G01X1391786Y160874D02*
X1390478Y161700D01*
G01X1390811Y162850D02*
X1364431D01*
G01X1390478Y161700D02*
X1363954D01*
G01X1364431Y162850D02*
X1363296Y163985D01*
G01X1363954Y161700D02*
X1362146Y163508D01*
G01X1363296Y163985D02*
Y170710D01*
G01X1362146Y163508D02*
Y170594D01*
G01X1363296Y170710D02*
X1362449Y174874D01*
G01X1362146Y170594D02*
X1361366Y174425D01*
G01X1362449Y174874D02*
X1360104Y178416D01*
G01X1361366Y174425D02*
X1359385Y177418D01*
G01X1360104Y178416D02*
X1353069Y180302D01*
G01X1359385Y177418D02*
X1353033Y179121D01*
G01X1353069Y180302D02*
X1344201Y178498D01*
G01X1353033Y179121D02*
X1344201Y177324D01*
G01X1386971Y157476D02*
X1385634Y158075D01*
G01X1386245Y156540D02*
X1385387Y156925D01*
G01X1385634Y158075D02*
X1359326D01*
G01X1385387Y156925D02*
X1358849D01*
G01X1359326Y158075D02*
X1358284Y159117D01*
G01X1358849Y156925D02*
X1357134Y158640D01*
G01X1358284Y159117D02*
Y170916D01*
G01X1357134Y158640D02*
Y170800D01*
G01X1358284Y170916D02*
X1357577Y174390D01*
G01X1357134Y170800D02*
X1356494Y173941D01*
G01X1357577Y174390D02*
X1356190Y176485D01*
G01X1356494Y173941D02*
X1355471Y175486D01*
G01X1356190Y176485D02*
X1352695Y177421D01*
G01X1355471Y175486D02*
X1352659Y176240D01*
G01X1352695Y177421D02*
X1344447Y175744D01*
G01X1352659Y176240D02*
X1344447Y174570D01*
G01X1353387Y166440D02*
X1351677Y168150D01*
G01X1352237Y165963D02*
X1351200Y167000D01*
G01X1351677Y168150D02*
X1343777D01*
G01X1351200Y167000D02*
X1343300D01*
G01X1343777Y168150D02*
X1343150Y168777D01*
G01D02*
Y172566D01*
G01X1342000Y168300D02*
Y172089D01*
G01X1343150Y172566D02*
X1342309Y173407D01*
G01X1346936Y161250D02*
X1346486Y161700D01*
G01X1348086Y161727D02*
X1346963Y162850D01*
G01X1346770Y202313D02*
X1354333Y203852D01*
G01X1346770Y201139D02*
X1354297Y202671D01*
G01X1354333Y203852D02*
X1413461Y187999D01*
G01X1354297Y202671D02*
X1412982Y186936D01*
G01X1346453Y199674D02*
X1354223Y201254D01*
G01X1346453Y198500D02*
X1354187Y200073D01*
G01X1354223Y201254D02*
X1354484Y201185D01*
G01Y201184D02*
X1412133Y185730D01*
G01X1354187Y200073D02*
X1411654Y184667D01*
G01X1346233Y197014D02*
X1354235Y198643D01*
G01X1346233Y195840D02*
X1354199Y197462D01*
G01X1354235Y198643D02*
X1410712Y183507D01*
G01X1354199Y197462D02*
X1410233Y182444D01*
G01X1345931Y194372D02*
X1354115Y196037D01*
G01X1345931Y193198D02*
X1354079Y194856D01*
G01X1354115Y196037D02*
X1409300Y181245D01*
G01X1354079Y194856D02*
X1409271Y180062D01*
G01X1345658Y191723D02*
X1354111Y193444D01*
G01X1345658Y190549D02*
X1354075Y192263D01*
G01X1354111Y193444D02*
X1408227Y178940D01*
G01X1354075Y192263D02*
X1407748Y177877D01*
G01X1353977Y189664D02*
X1345348Y187908D01*
G01Y189082D02*
X1354013Y190845D01*
G01X1406554Y175570D02*
X1353977Y189664D01*
G01X1354013Y190845D02*
X1407033Y176633D01*
G01X1405695Y174352D02*
X1353852Y188246D01*
G01X1405216Y173289D02*
X1353816Y187065D01*
G01X1353852Y188246D02*
X1345004Y186447D01*
G01X1353816Y187065D02*
X1345004Y185273D01*
G01X1344689Y183807D02*
X1353658Y185631D01*
G01X1344689Y182633D02*
X1353622Y184450D01*
G01X1353658Y185631D02*
X1404567Y171986D01*
G01X1353622Y184450D02*
X1404088Y170923D01*
G01X1344459Y181150D02*
X1353377Y182963D01*
G01X1344459Y179976D02*
X1353341Y181782D01*
G01X1353377Y182963D02*
X1403803Y169447D01*
G01X1353341Y181782D02*
X1403324Y168384D01*
G01D02*
X1406760Y166109D01*
G01X1347089Y203779D02*
X1355021Y205393D01*
G01X1347089Y204953D02*
X1355060Y206575D01*
G01X1355021Y205393D02*
X1414030Y189293D01*
G01X1355060Y206575D02*
X1414511Y190354D01*
G01X1372561Y226293D02*
X1401266Y216660D01*
G01X1372749Y227443D02*
X1401454Y217810D01*
G01X1401266Y216660D02*
X1403343D01*
G01X1401454Y217810D02*
X1403531D01*
G01X1403343Y216660D02*
X1411177Y214031D01*
G01X1403531Y217810D02*
X1411705Y215067D01*
G01X1416210Y193115D02*
X1384134Y201959D01*
G01X1415730Y192054D02*
X1383633Y200904D01*
G01X1384134Y201959D02*
X1367736Y213629D01*
G01X1383633Y200904D02*
X1367368Y212479D01*
G01X1417569Y194161D02*
X1384207Y203600D01*
G01X1418051Y195220D02*
X1384712Y204653D01*
G01X1384207Y203600D02*
X1368226Y214979D01*
G01X1384712Y204653D02*
X1368594Y216129D01*
G01X1367923Y219886D02*
X1385391Y207449D01*
G01X1367555Y218736D02*
X1384881Y206400D01*
G01X1385391Y207449D02*
X1429331Y194518D01*
G01X1384881Y206400D02*
X1429165Y193368D01*
G01X1403658Y210508D02*
X1408528Y208874D01*
G01X1395311Y208843D02*
X1403658Y210508D01*
G01X1403733Y211696D02*
X1395311Y210016D01*
G01X1382754Y211354D02*
X1395311Y208843D01*
G01Y210016D02*
X1383219Y212434D01*
G01X1368714Y221286D02*
X1382754Y211354D01*
G01X1383219Y212434D02*
X1369080Y222436D01*
G01X1372749Y227443D02*
X1401454Y217810D01*
G01X1372561Y226293D02*
X1401266Y216660D01*
G01X1401454Y217810D02*
X1403531D01*
G01X1401266Y216660D02*
X1403343D01*
G01X1403531Y217810D02*
X1411705Y215067D01*
G01X1403343Y216660D02*
X1411177Y214031D01*
G01X1415730Y192054D02*
X1383633Y200904D01*
G01X1416210Y193115D02*
X1384134Y201959D01*
G01X1383633Y200904D02*
X1367368Y212479D01*
G01X1384134Y201959D02*
X1367736Y213629D01*
G01X1418051Y195220D02*
X1384712Y204653D01*
G01X1417569Y194161D02*
X1384207Y203600D01*
G01X1384712Y204653D02*
X1368594Y216129D01*
G01X1384207Y203600D02*
X1368226Y214979D01*
G01X1367555Y218736D02*
X1384881Y206400D01*
G01X1367923Y219886D02*
X1385391Y207449D01*
G01X1384881Y206400D02*
X1429165Y193368D01*
G01X1385391Y207449D02*
X1429331Y194518D01*
G01X1383219Y212434D02*
X1369080Y222436D01*
G01X1368714Y221286D02*
X1382754Y211354D01*
G01X1395311Y210016D02*
X1383219Y212434D01*
G01X1382754Y211354D02*
X1395311Y208843D01*
G01X1403733Y211696D02*
X1395311Y210016D01*
G01Y208843D02*
X1403658Y210508D01*
G01D02*
X1408528Y208874D01*
G01X1403933Y236619D02*
X1398464Y240266D01*
G01D02*
X1397276Y240503D01*
G01X1404763Y237449D02*
X1398913Y241350D01*
G01X1398464Y240266D02*
X1397276Y240503D01*
G01X1398913Y241350D02*
X1397276Y241676D01*
G01X1398464Y240266D02*
X1397276Y240503D01*
G01D02*
X1394548Y239958D01*
G01X1397276Y241676D02*
X1394548Y241131D01*
G01Y239958D02*
X1388888Y241091D01*
G01X1394548Y241131D02*
X1388870Y242268D01*
G01X1388888Y241091D02*
X1383823Y239910D01*
G01X1388870Y242268D02*
X1383801Y241086D01*
G01X1383823Y239910D02*
X1377774Y241091D01*
G01X1383801Y241086D02*
X1377752Y242268D01*
G01X1377774Y241091D02*
X1372785Y239925D01*
G01X1377752Y242268D02*
X1372763Y241101D01*
G01X1372785Y239925D02*
X1367163Y241018D01*
G01X1372763Y241101D02*
X1367142Y242194D01*
G01X1367163Y241018D02*
X1362258Y239877D01*
G01X1367142Y242194D02*
X1362237Y241053D01*
G01X1362258Y239877D02*
X1355864Y241121D01*
G01X1362237Y241053D02*
X1355842Y242297D01*
G01X1355864Y241121D02*
X1350849Y239948D01*
G01X1355842Y242297D02*
X1350827Y241124D01*
G01X1372948Y228914D02*
X1402013Y219160D01*
G01X1373136Y230064D02*
X1402201Y220310D01*
G01X1402013Y219160D02*
X1403788D01*
G01X1402201Y220310D02*
X1403976D01*
G01X1372163Y223789D02*
X1380480Y220997D01*
G01X1372351Y224939D02*
X1381007Y222034D01*
G01X1404763Y237449D02*
X1398913Y241350D01*
G01X1403933Y236619D02*
X1398464Y240266D01*
G01X1404763Y237449D02*
X1398913Y241350D01*
G01D02*
X1397276Y241676D01*
G01D02*
X1394548Y241131D01*
G01X1398464Y240266D02*
X1397276Y240503D01*
G01Y241676D02*
X1394548Y241131D01*
G01X1397276Y240503D02*
X1394548Y239958D01*
G01Y241131D02*
X1388870Y242268D01*
G01X1394548Y239958D02*
X1388888Y241091D01*
G01X1388870Y242268D02*
X1383801Y241086D01*
G01X1388888Y241091D02*
X1383823Y239910D01*
G01X1383801Y241086D02*
X1377752Y242268D01*
G01X1383823Y239910D02*
X1377774Y241091D01*
G01X1377752Y242268D02*
X1372763Y241101D01*
G01X1377774Y241091D02*
X1372785Y239925D01*
G01X1372763Y241101D02*
X1367142Y242194D01*
G01X1372785Y239925D02*
X1367163Y241018D01*
G01X1367142Y242194D02*
X1362237Y241053D01*
G01X1367163Y241018D02*
X1362258Y239877D01*
G01X1362237Y241053D02*
X1355842Y242297D01*
G01X1362258Y239877D02*
X1355864Y241121D01*
G01X1355842Y242297D02*
X1350827Y241124D01*
G01X1355864Y241121D02*
X1350849Y239948D01*
G01X1373136Y230064D02*
X1402201Y220310D01*
G01X1372948Y228914D02*
X1402013Y219160D01*
G01X1402201Y220310D02*
X1403976D01*
G01X1402013Y219160D02*
X1403788D01*
G01X1372351Y224939D02*
X1381007Y222034D01*
G01X1372163Y223789D02*
X1380480Y220997D01*
G01X1405214Y261532D02*
X1399495Y262675D01*
G01X1405780Y262592D02*
X1399495Y263848D01*
G01Y262675D02*
X1381001Y258976D01*
G01X1399495Y263848D02*
X1380998Y260149D01*
G01X1381001Y258976D02*
X1377536Y259652D01*
G01X1380998Y260149D02*
X1377514Y260828D01*
G01X1377536Y259652D02*
X1372540Y258486D01*
G01X1377514Y260828D02*
X1372518Y259662D01*
G01X1372540Y258486D02*
X1366550Y259650D01*
G01X1372518Y259662D02*
X1366529Y260826D01*
G01X1366550Y259650D02*
X1361684Y258518D01*
G01X1366529Y260826D02*
X1361663Y259694D01*
G01X1361684Y258518D02*
X1354775Y259862D01*
G01X1361663Y259694D02*
X1354753Y261038D01*
G01X1354775Y259862D02*
X1351084Y259000D01*
G01X1354753Y261038D02*
X1351062Y260176D01*
G01X1404104Y259013D02*
X1399304Y259970D01*
G01X1404670Y260073D02*
X1399304Y261143D01*
G01Y259970D02*
X1381279Y256363D01*
G01X1399304Y261143D02*
X1381276Y257536D01*
G01X1381279Y256363D02*
X1377561Y257088D01*
G01X1381276Y257536D02*
X1377539Y258264D01*
G01X1377561Y257088D02*
X1372571Y255921D01*
G01X1377539Y258264D02*
X1372549Y257097D01*
G01X1372571Y255921D02*
X1366581Y257085D01*
G01X1372549Y257097D02*
X1366560Y258261D01*
G01X1366581Y257085D02*
X1361715Y255953D01*
G01X1366560Y258261D02*
X1361694Y257129D01*
G01X1361715Y255953D02*
X1355020Y257255D01*
G01X1361694Y257129D02*
X1354998Y258431D01*
G01X1355020Y257255D02*
X1351330Y256393D01*
G01X1354998Y258431D02*
X1351308Y257569D01*
G01X1405745Y253841D02*
X1403002Y256563D01*
G01X1406219Y254991D02*
X1403567Y257623D01*
G01X1403002Y256563D02*
X1399368Y257290D01*
G01X1403567Y257623D02*
X1399368Y258463D01*
G01Y257290D02*
X1381612Y253738D01*
G01X1399368Y258463D02*
X1381609Y254911D01*
G01X1381612Y253738D02*
X1377592Y254523D01*
G01X1381609Y254911D02*
X1377570Y255699D01*
G01X1377592Y254523D02*
X1372602Y253356D01*
G01X1377570Y255699D02*
X1372580Y254532D01*
G01X1372602Y253356D02*
X1366602Y254522D01*
G01X1372580Y254532D02*
X1366580Y255698D01*
G01X1366602Y254522D02*
X1361732Y253389D01*
G01X1366580Y255698D02*
X1361711Y254565D01*
G01X1361732Y253389D02*
X1355236Y254654D01*
G01X1361711Y254565D02*
X1355214Y255830D01*
G01X1355236Y254654D02*
X1351545Y253792D01*
G01X1355214Y255830D02*
X1351523Y254968D01*
G01X1404668Y251217D02*
X1401673Y254184D01*
G01X1405142Y252367D02*
X1402238Y255245D01*
G01X1401673Y254184D02*
X1399153Y254688D01*
G01X1402238Y255245D02*
X1399153Y255861D01*
G01Y254688D02*
X1381605Y251181D01*
G01X1399153Y255861D02*
X1381602Y252354D01*
G01X1381605Y251181D02*
X1377623Y251958D01*
G01X1381602Y252354D02*
X1377601Y253134D01*
G01X1377623Y251958D02*
X1372633Y250791D01*
G01X1377601Y253134D02*
X1372611Y251967D01*
G01X1372633Y250791D02*
X1366732Y251938D01*
G01X1372611Y251967D02*
X1366710Y253114D01*
G01X1366732Y251938D02*
X1361862Y250805D01*
G01X1366710Y253114D02*
X1361841Y251981D01*
G01X1361862Y250805D02*
X1355381Y252067D01*
G01X1361841Y251981D02*
X1355359Y253243D01*
G01X1355381Y252067D02*
X1351685Y251206D01*
G01X1355359Y253243D02*
X1351664Y252382D01*
G01X1355486Y249487D02*
X1351783Y248628D01*
G01X1351762Y249804D02*
X1355465Y250663D01*
G01X1361888Y248241D02*
X1355486Y249487D01*
G01X1355465Y250663D02*
X1361867Y249417D01*
G01X1366758Y249374D02*
X1361888Y248241D01*
G01X1361867Y249417D02*
X1366736Y250550D01*
G01X1372664Y248226D02*
X1366758Y249374D01*
G01X1366736Y250550D02*
X1372642Y249402D01*
G01X1377654Y249393D02*
X1372664Y248226D01*
G01X1372642Y249402D02*
X1377632Y250569D01*
G01X1383706Y248212D02*
X1377654Y249393D01*
G01X1377632Y250569D02*
X1383685Y249388D01*
G01X1393681Y250539D02*
X1383706Y248212D01*
G01X1383685Y249388D02*
X1393662Y251716D01*
G01X1408623Y247551D02*
X1393681Y250539D01*
G01X1393662Y251716D02*
X1409190Y248611D01*
G01X1418170Y234445D02*
X1399532Y246783D01*
G01X1418902Y235341D02*
X1399979Y247867D01*
G01X1399532Y246783D02*
X1393655Y247958D01*
G01X1399979Y247867D02*
X1393636Y249135D01*
G01X1393655Y247958D02*
X1383737Y245647D01*
G01X1393636Y249135D02*
X1383716Y246823D01*
G01X1383737Y245647D02*
X1377685Y246828D01*
G01X1383716Y246823D02*
X1377663Y248004D01*
G01X1377685Y246828D02*
X1372695Y245661D01*
G01X1377663Y248004D02*
X1372673Y246837D01*
G01X1372695Y245661D02*
X1366853Y246796D01*
G01X1372673Y246837D02*
X1366831Y247972D01*
G01X1366853Y246796D02*
X1361983Y245663D01*
G01X1366831Y247972D02*
X1361962Y246839D01*
G01X1361983Y245663D02*
X1355647Y246897D01*
G01X1361962Y246839D02*
X1355625Y248073D01*
G01X1355647Y246897D02*
X1351958Y246035D01*
G01X1355625Y248073D02*
X1351936Y247211D01*
G01X1413312Y234617D02*
X1398028Y244250D01*
G01X1414035Y235522D02*
X1398462Y245336D01*
G01X1398028Y244250D02*
X1393051Y245245D01*
G01X1398462Y245336D02*
X1393032Y246422D01*
G01X1393051Y245245D02*
X1383768Y243082D01*
G01X1393032Y246422D02*
X1383747Y244258D01*
G01X1383768Y243082D02*
X1377716Y244263D01*
G01X1383747Y244258D02*
X1377694Y245439D01*
G01X1377716Y244263D02*
X1372726Y243096D01*
G01X1377694Y245439D02*
X1372704Y244272D01*
G01X1372726Y243096D02*
X1366881Y244232D01*
G01X1372704Y244272D02*
X1366859Y245408D01*
G01X1366881Y244232D02*
X1362011Y243099D01*
G01X1366859Y245408D02*
X1361990Y244275D01*
G01X1362011Y243099D02*
X1355673Y244333D01*
G01X1361990Y244275D02*
X1355651Y245509D01*
G01X1355673Y244333D02*
X1351985Y243471D01*
G01X1355651Y245509D02*
X1351963Y244647D01*
G01X1350921Y262762D02*
X1354617Y263623D01*
G01X1350943Y261586D02*
X1354639Y262447D01*
G01X1354617Y263623D02*
X1361604Y262263D01*
G01X1354639Y262447D02*
X1361625Y261087D01*
G01X1361604Y262263D02*
X1366472Y263396D01*
G01X1361625Y261087D02*
X1366494Y262220D01*
G01X1366472Y263396D02*
X1372487Y262227D01*
G01X1366494Y262220D02*
X1372509Y261051D01*
G01X1372487Y262227D02*
X1377477Y263395D01*
G01X1372509Y261051D02*
X1377499Y262218D01*
G01X1377477Y263395D02*
X1380948Y262717D01*
G01X1377499Y262218D02*
X1380951Y261544D01*
G01X1380948Y262717D02*
X1399585Y266443D01*
G01X1380951Y261544D02*
X1399585Y265270D01*
G01Y266443D02*
X1407030Y264954D01*
G01X1399585Y265270D02*
X1406463Y263894D01*
G01X1405780Y262592D02*
X1399495Y263848D01*
G01X1405214Y261532D02*
X1399495Y262675D01*
G01Y263848D02*
X1380998Y260149D01*
G01X1399495Y262675D02*
X1381001Y258976D01*
G01X1380998Y260149D02*
X1377514Y260828D01*
G01X1381001Y258976D02*
X1377536Y259652D01*
G01X1377514Y260828D02*
X1372518Y259662D01*
G01X1377536Y259652D02*
X1372540Y258486D01*
G01X1372518Y259662D02*
X1366529Y260826D01*
G01X1372540Y258486D02*
X1366550Y259650D01*
G01X1366529Y260826D02*
X1361663Y259694D01*
G01X1366550Y259650D02*
X1361684Y258518D01*
G01X1361663Y259694D02*
X1354753Y261038D01*
G01X1361684Y258518D02*
X1354775Y259862D01*
G01X1354753Y261038D02*
X1351062Y260176D01*
G01X1354775Y259862D02*
X1351084Y259000D01*
G01X1404670Y260073D02*
X1399304Y261143D01*
G01X1404104Y259013D02*
X1399304Y259970D01*
G01Y261143D02*
X1381276Y257536D01*
G01X1399304Y259970D02*
X1381279Y256363D01*
G01X1381276Y257536D02*
X1377539Y258264D01*
G01X1381279Y256363D02*
X1377561Y257088D01*
G01X1377539Y258264D02*
X1372549Y257097D01*
G01X1377561Y257088D02*
X1372571Y255921D01*
G01X1372549Y257097D02*
X1366560Y258261D01*
G01X1372571Y255921D02*
X1366581Y257085D01*
G01X1366560Y258261D02*
X1361694Y257129D01*
G01X1366581Y257085D02*
X1361715Y255953D01*
G01X1361694Y257129D02*
X1354998Y258431D01*
G01X1361715Y255953D02*
X1355020Y257255D01*
G01X1354998Y258431D02*
X1351308Y257569D01*
G01X1355020Y257255D02*
X1351330Y256393D01*
G01X1406219Y254991D02*
X1403567Y257623D01*
G01X1405745Y253841D02*
X1403002Y256563D01*
G01X1403567Y257623D02*
X1399368Y258463D01*
G01X1403002Y256563D02*
X1399368Y257290D01*
G01Y258463D02*
X1381609Y254911D01*
G01X1399368Y257290D02*
X1381612Y253738D01*
G01X1381609Y254911D02*
X1377570Y255699D01*
G01X1381612Y253738D02*
X1377592Y254523D01*
G01X1377570Y255699D02*
X1372580Y254532D01*
G01X1377592Y254523D02*
X1372602Y253356D01*
G01X1372580Y254532D02*
X1366580Y255698D01*
G01X1372602Y253356D02*
X1366602Y254522D01*
G01X1366580Y255698D02*
X1361711Y254565D01*
G01X1366602Y254522D02*
X1361732Y253389D01*
G01X1361711Y254565D02*
X1355214Y255830D01*
G01X1361732Y253389D02*
X1355236Y254654D01*
G01X1355214Y255830D02*
X1351523Y254968D01*
G01X1355236Y254654D02*
X1351545Y253792D01*
G01X1405142Y252367D02*
X1402238Y255245D01*
G01X1404668Y251217D02*
X1401673Y254184D01*
G01X1402238Y255245D02*
X1399153Y255861D01*
G01X1401673Y254184D02*
X1399153Y254688D01*
G01Y255861D02*
X1381602Y252354D01*
G01X1399153Y254688D02*
X1381605Y251181D01*
G01X1381602Y252354D02*
X1377601Y253134D01*
G01X1381605Y251181D02*
X1377623Y251958D01*
G01X1377601Y253134D02*
X1372611Y251967D01*
G01X1377623Y251958D02*
X1372633Y250791D01*
G01X1372611Y251967D02*
X1366710Y253114D01*
G01X1372633Y250791D02*
X1366732Y251938D01*
G01X1366710Y253114D02*
X1361841Y251981D01*
G01X1366732Y251938D02*
X1361862Y250805D01*
G01X1361841Y251981D02*
X1355359Y253243D01*
G01X1361862Y250805D02*
X1355381Y252067D01*
G01X1355359Y253243D02*
X1351664Y252382D01*
G01X1355381Y252067D02*
X1351685Y251206D01*
G01X1393662Y251716D02*
X1409190Y248611D01*
G01X1408623Y247551D02*
X1393681Y250539D01*
G01X1383685Y249388D02*
X1393662Y251716D01*
G01X1393681Y250539D02*
X1383706Y248212D01*
G01X1377632Y250569D02*
X1383685Y249388D01*
G01X1383706Y248212D02*
X1377654Y249393D01*
G01X1372642Y249402D02*
X1377632Y250569D01*
G01X1377654Y249393D02*
X1372664Y248226D01*
G01X1366736Y250550D02*
X1372642Y249402D01*
G01X1372664Y248226D02*
X1366758Y249374D01*
G01X1361867Y249417D02*
X1366736Y250550D01*
G01X1366758Y249374D02*
X1361888Y248241D01*
G01X1355465Y250663D02*
X1361867Y249417D01*
G01X1361888Y248241D02*
X1355486Y249487D01*
G01X1351762Y249804D02*
X1355465Y250663D01*
G01X1355486Y249487D02*
X1351783Y248628D01*
G01X1418902Y235341D02*
X1399979Y247867D01*
G01X1418170Y234445D02*
X1399532Y246783D01*
G01X1399979Y247867D02*
X1393636Y249135D01*
G01X1399532Y246783D02*
X1393655Y247958D01*
G01X1393636Y249135D02*
X1383716Y246823D01*
G01X1393655Y247958D02*
X1383737Y245647D01*
G01X1383716Y246823D02*
X1377663Y248004D01*
G01X1383737Y245647D02*
X1377685Y246828D01*
G01X1377663Y248004D02*
X1372673Y246837D01*
G01X1377685Y246828D02*
X1372695Y245661D01*
G01X1372673Y246837D02*
X1366831Y247972D01*
G01X1372695Y245661D02*
X1366853Y246796D01*
G01X1366831Y247972D02*
X1361962Y246839D01*
G01X1366853Y246796D02*
X1361983Y245663D01*
G01X1361962Y246839D02*
X1355625Y248073D01*
G01X1361983Y245663D02*
X1355647Y246897D01*
G01X1355625Y248073D02*
X1351936Y247211D01*
G01X1355647Y246897D02*
X1351958Y246035D01*
G01X1414035Y235522D02*
X1398462Y245336D01*
G01X1413312Y234617D02*
X1398028Y244250D01*
G01X1398462Y245336D02*
X1393032Y246422D01*
G01X1398028Y244250D02*
X1393051Y245245D01*
G01X1393032Y246422D02*
X1383747Y244258D01*
G01X1393051Y245245D02*
X1383768Y243082D01*
G01X1383747Y244258D02*
X1377694Y245439D01*
G01X1383768Y243082D02*
X1377716Y244263D01*
G01X1377694Y245439D02*
X1372704Y244272D01*
G01X1377716Y244263D02*
X1372726Y243096D01*
G01X1372704Y244272D02*
X1366859Y245408D01*
G01X1372726Y243096D02*
X1366881Y244232D01*
G01X1366859Y245408D02*
X1361990Y244275D01*
G01X1366881Y244232D02*
X1362011Y243099D01*
G01X1361990Y244275D02*
X1355651Y245509D01*
G01X1362011Y243099D02*
X1355673Y244333D01*
G01X1355651Y245509D02*
X1351963Y244647D01*
G01X1355673Y244333D02*
X1351985Y243471D01*
G01X1350943Y261586D02*
X1354639Y262447D01*
G01X1350921Y262762D02*
X1354617Y263623D01*
G01X1354639Y262447D02*
X1361625Y261087D01*
G01X1354617Y263623D02*
X1361604Y262263D01*
G01X1361625Y261087D02*
X1366494Y262220D01*
G01X1361604Y262263D02*
X1366472Y263396D01*
G01X1366494Y262220D02*
X1372509Y261051D01*
G01X1366472Y263396D02*
X1372487Y262227D01*
G01X1372509Y261051D02*
X1377499Y262218D01*
G01X1372487Y262227D02*
X1377477Y263395D01*
G01X1377499Y262218D02*
X1380951Y261544D01*
G01X1377477Y263395D02*
X1380948Y262717D01*
G01X1380951Y261544D02*
X1399585Y265270D01*
G01X1380948Y262717D02*
X1399585Y266443D01*
G01Y265270D02*
X1406463Y263894D01*
G01X1399585Y266443D02*
X1407030Y264954D01*
G01X1404762Y289340D02*
X1402902Y288973D01*
G01X1404762Y289340D02*
X1402902Y288973D01*
G01X1404761Y288167D02*
X1402902Y287800D01*
G01Y288973D02*
X1400940Y289359D01*
G01X1402902Y287800D02*
X1400939Y288186D01*
G01X1400940Y289359D02*
X1398878Y288952D01*
G01X1400939Y288186D02*
X1398878Y287779D01*
G01Y288952D02*
X1396916Y289339D01*
G01X1398878Y287779D02*
X1396916Y288166D01*
G01Y289339D02*
X1394865Y288933D01*
G01X1396916Y288166D02*
X1394865Y287760D01*
G01Y288933D02*
X1392964Y289309D01*
G01X1394865Y287760D02*
X1392964Y288136D01*
G01Y289309D02*
X1391088Y288939D01*
G01X1392964Y288136D02*
X1391088Y287766D01*
G01Y288939D02*
X1389068Y289338D01*
G01X1391088Y287766D02*
X1389068Y288165D01*
G01Y289338D02*
X1381221Y287790D01*
G01X1389068Y288165D02*
X1381161Y286605D01*
G01X1381221Y287790D02*
X1355686Y295593D01*
G01X1381161Y286605D02*
X1355239Y294527D01*
G01X1355686Y295593D02*
X1351723Y297746D01*
G01X1355239Y294527D02*
X1351430Y296596D01*
G01X1351723Y297746D02*
X1346530D01*
G01X1351430Y296596D02*
X1346053D01*
G01X1346530Y297746D02*
X1345500Y298776D01*
G01X1346053Y296596D02*
X1344350Y298299D01*
G01X1345500Y298776D02*
Y316127D01*
G01X1344350Y298299D02*
Y315650D01*
G01X1345500Y316127D02*
X1343877Y317750D01*
G01X1344350Y315650D02*
X1343400Y316600D01*
G01X1404761Y288167D02*
X1402902Y287800D01*
G01X1404762Y289340D02*
X1402902Y288973D01*
G01Y287800D02*
X1400939Y288186D01*
G01X1402902Y288973D02*
X1400940Y289359D01*
G01X1400939Y288186D02*
X1398878Y287779D01*
G01X1400940Y289359D02*
X1398878Y288952D01*
G01Y287779D02*
X1396916Y288166D01*
G01X1398878Y288952D02*
X1396916Y289339D01*
G01Y288166D02*
X1394865Y287760D01*
G01X1396916Y289339D02*
X1394865Y288933D01*
G01Y287760D02*
X1392964Y288136D01*
G01X1394865Y288933D02*
X1392964Y289309D01*
G01Y288136D02*
X1391088Y287766D01*
G01X1392964Y289309D02*
X1391088Y288939D01*
G01Y287766D02*
X1389068Y288165D01*
G01X1391088Y288939D02*
X1389068Y289338D01*
G01Y288165D02*
X1381161Y286605D01*
G01X1389068Y289338D02*
X1381221Y287790D01*
G01X1381161Y286605D02*
X1355239Y294527D01*
G01X1381221Y287790D02*
X1355686Y295593D01*
G01X1355239Y294527D02*
X1351430Y296596D01*
G01X1355686Y295593D02*
X1351723Y297746D01*
G01X1351430Y296596D02*
X1346053D01*
G01X1351723Y297746D02*
X1346530D01*
G01X1346053Y296596D02*
X1344350Y298299D01*
G01X1346530Y297746D02*
X1345500Y298776D01*
G01X1344350Y298299D02*
Y315650D01*
G01X1345500Y298776D02*
Y316127D01*
G01X1344350Y315650D02*
X1343400Y316600D01*
G01X1345500Y316127D02*
X1343877Y317750D01*
G01X1404764Y291939D02*
X1402902Y291571D01*
G01X1404764Y290766D02*
X1402902Y290398D01*
G01Y291571D02*
X1400940Y291959D01*
G01X1402902Y290398D02*
X1400940Y290786D01*
G01Y291959D02*
X1398878Y291551D01*
G01X1400940Y290786D02*
X1398878Y290378D01*
G01Y291551D02*
X1396916Y291939D01*
G01X1398878Y290378D02*
X1396916Y290766D01*
G01Y291939D02*
X1394865Y291533D01*
G01X1396916Y290766D02*
X1394865Y290360D01*
G01Y291533D02*
X1392966Y291909D01*
G01X1394865Y290360D02*
X1392965Y290736D01*
G01X1392966Y291909D02*
X1391088Y291539D01*
G01X1392965Y290736D02*
X1391088Y290366D01*
G01Y291539D02*
X1389068Y291938D01*
G01X1391088Y290366D02*
X1389068Y290765D01*
G01Y291938D02*
X1381355Y290416D01*
G01X1389068Y290765D02*
X1381295Y289231D01*
G01X1381355Y290416D02*
X1359173Y297195D01*
G01X1381295Y289231D02*
X1358562Y296178D01*
G01X1359173Y297195D02*
X1356647Y299721D01*
G01X1358562Y296178D02*
X1355497Y299244D01*
G01X1356647Y299721D02*
Y316852D01*
G01X1355497Y299244D02*
Y316375D01*
G01X1356647Y316852D02*
X1353633Y319866D01*
G01X1355497Y316375D02*
X1353156Y318716D01*
G01X1353633Y319866D02*
X1350413D01*
G01X1353156Y318716D02*
X1350414D01*
G01X1404764Y294538D02*
X1402902Y294170D01*
G01X1404764Y293365D02*
X1402902Y292997D01*
G01Y294170D02*
X1400940Y294558D01*
G01X1402902Y292997D02*
X1400940Y293385D01*
G01Y294558D02*
X1398878Y294150D01*
G01X1400940Y293385D02*
X1398878Y292977D01*
G01Y294150D02*
X1396916Y294538D01*
G01X1398878Y292977D02*
X1396916Y293365D01*
G01Y294538D02*
X1394865Y294132D01*
G01X1396916Y293365D02*
X1394865Y292959D01*
G01Y294132D02*
X1392902Y294520D01*
G01X1394865Y292959D02*
X1392902Y293347D01*
G01Y294520D02*
X1391030Y294150D01*
G01X1392902Y293347D02*
X1391030Y292977D01*
G01Y294150D02*
X1389068Y294538D01*
G01X1391030Y292977D02*
X1389068Y293365D01*
G01Y294538D02*
X1383598Y293458D01*
G01X1389068Y293365D02*
X1383538Y292273D01*
G01X1383598Y293458D02*
X1370125Y297576D01*
G01X1383538Y292273D02*
X1376526Y294416D01*
G01X1383598Y293458D02*
X1370125Y297576D01*
G01X1376526Y294417D02*
X1369514Y296559D01*
G01X1370125Y297576D02*
X1367388Y300313D01*
G01X1369514Y296559D02*
X1366238Y299836D01*
G01X1367388Y300313D02*
Y311813D01*
G01X1366238Y299836D02*
Y311336D01*
G01X1367388Y311813D02*
X1366600Y312601D01*
G01X1366238Y311336D02*
X1365450Y312124D01*
G01X1366600Y312601D02*
Y315928D01*
G01X1365450Y312124D02*
Y315451D01*
G01X1366600Y315928D02*
X1365028Y317500D01*
G01X1365450Y315451D02*
X1364551Y316350D01*
G01X1365028Y317500D02*
X1361619D01*
G01X1364551Y316350D02*
X1361619D01*
G01X1404764Y297138D02*
X1402902Y296770D01*
G01X1404764Y295965D02*
X1402902Y295597D01*
G01Y296770D02*
X1400940Y297158D01*
G01X1402902Y295597D02*
X1400940Y295985D01*
G01Y297158D02*
X1398878Y296750D01*
G01X1400940Y295985D02*
X1398878Y295577D01*
G01Y296750D02*
X1396916Y297138D01*
G01X1398878Y295577D02*
X1396916Y295965D01*
G01Y297138D02*
X1394865Y296732D01*
G01X1396916Y295965D02*
X1394865Y295559D01*
G01Y296732D02*
X1392902Y297120D01*
G01X1394865Y295559D02*
X1392902Y295947D01*
G01Y297120D02*
X1391030Y296750D01*
G01X1392902Y295947D02*
X1391030Y295577D01*
G01Y296750D02*
X1389068Y297138D01*
G01X1391030Y295577D02*
X1389068Y295965D01*
G01Y297138D02*
X1386867Y296703D01*
G01X1389068Y295965D02*
X1386867Y295530D01*
G01Y296703D02*
X1381029Y297857D01*
G01X1386867Y295530D02*
X1380664Y296756D01*
G01X1381029Y297857D02*
X1379811Y298439D01*
G01X1380664Y296756D02*
X1379134Y297487D01*
G01X1379811Y298439D02*
X1378254Y300015D01*
G01X1379134Y297487D02*
X1377104Y299542D01*
G01X1378254Y300015D02*
Y313684D01*
G01X1377104Y299542D02*
Y313207D01*
G01X1378254Y313684D02*
X1374068Y317870D01*
G01X1377104Y313207D02*
X1373591Y316720D01*
G01X1378254Y313684D02*
X1374068Y317870D01*
G01D02*
X1372415D01*
G01X1373591Y316720D02*
X1372415D01*
G01X1382251Y318400D02*
X1385105D01*
G01X1382207Y317250D02*
X1384628D01*
G01X1385105Y318400D02*
X1387473Y316032D01*
G01X1384628Y317250D02*
X1386323Y315555D01*
G01X1387473Y316032D02*
Y314058D01*
G01X1386323Y315555D02*
Y313581D01*
G01X1387473Y314058D02*
X1389737Y311794D01*
G01X1386323Y313581D02*
X1388587Y311317D01*
G01X1389737Y311794D02*
Y300464D01*
G01X1388587Y311317D02*
Y299987D01*
G01X1389737Y300464D02*
X1390378Y299823D01*
G01X1388587Y299987D02*
X1389771Y298803D01*
G01X1390378Y299823D02*
X1391596Y299462D01*
G01X1389771Y298803D02*
X1391541Y298278D01*
G01X1391596Y299462D02*
X1392992Y299738D01*
G01X1391541Y298278D02*
X1392992Y298565D01*
G01Y299738D02*
X1394954Y299350D01*
G01X1392992Y298565D02*
X1394954Y298177D01*
G01Y299350D02*
X1396916Y299738D01*
G01X1394954Y298177D02*
X1396916Y298565D01*
G01Y299738D02*
X1398878Y299350D01*
G01X1396916Y298565D02*
X1398878Y298177D01*
G01Y299350D02*
X1400840Y299738D01*
G01X1398878Y298177D02*
X1400840Y298565D01*
G01Y299738D02*
X1402802Y299350D01*
G01X1400840Y298565D02*
X1402802Y298177D01*
G01Y299350D02*
X1404764Y299738D01*
G01X1402802Y298177D02*
X1404764Y298565D01*
G01X1390968Y318200D02*
X1388900D01*
G01X1390834Y317050D02*
X1388423D01*
G01X1388900Y318200D02*
X1387679Y319421D01*
G01X1388423Y317050D02*
X1386529Y318944D01*
G01X1387679Y319421D02*
Y321179D01*
G01X1386529Y318944D02*
Y321656D01*
G01X1387679Y321179D02*
X1388500Y322000D01*
G01X1386529Y321656D02*
X1388023Y323150D01*
G01X1388500Y322000D02*
X1392779D01*
G01X1388023Y323150D02*
X1393256D01*
G01X1392779Y322000D02*
X1395087Y319692D01*
G01X1393256Y323150D02*
X1396237Y320169D01*
G01X1395087Y319692D02*
Y313637D01*
G01X1396237Y320169D02*
Y314114D01*
G01X1395087Y313637D02*
X1396124Y312600D01*
G01X1396237Y314114D02*
X1396601Y313750D01*
G01X1396124Y312600D02*
X1415294D01*
G01X1396601Y313750D02*
X1414817D01*
G01X1404380Y317680D02*
X1401881D01*
G01X1403903Y318830D02*
X1401885D01*
G01X1404764Y290766D02*
X1402902Y290398D01*
G01X1404764Y291939D02*
X1402902Y291571D01*
G01Y290398D02*
X1400940Y290786D01*
G01X1402902Y291571D02*
X1400940Y291959D01*
G01Y290786D02*
X1398878Y290378D01*
G01X1400940Y291959D02*
X1398878Y291551D01*
G01Y290378D02*
X1396916Y290766D01*
G01X1398878Y291551D02*
X1396916Y291939D01*
G01Y290766D02*
X1394865Y290360D01*
G01X1396916Y291939D02*
X1394865Y291533D01*
G01Y290360D02*
X1392965Y290736D01*
G01X1394865Y291533D02*
X1392966Y291909D01*
G01X1392965Y290736D02*
X1391088Y290366D01*
G01X1392966Y291909D02*
X1391088Y291539D01*
G01Y290366D02*
X1389068Y290765D01*
G01X1391088Y291539D02*
X1389068Y291938D01*
G01Y290765D02*
X1381295Y289231D01*
G01X1389068Y291938D02*
X1381355Y290416D01*
G01X1381295Y289231D02*
X1358562Y296178D01*
G01X1381355Y290416D02*
X1359173Y297195D01*
G01X1358562Y296178D02*
X1355497Y299244D01*
G01X1359173Y297195D02*
X1356647Y299721D01*
G01X1355497Y299244D02*
Y316375D01*
G01X1356647Y299721D02*
Y316852D01*
G01X1355497Y316375D02*
X1353156Y318716D01*
G01X1356647Y316852D02*
X1353633Y319866D01*
G01X1353156Y318716D02*
X1350414D01*
G01X1353633Y319866D02*
X1350413D01*
G01X1404764Y293365D02*
X1402902Y292997D01*
G01X1404764Y294538D02*
X1402902Y294170D01*
G01Y292997D02*
X1400940Y293385D01*
G01X1402902Y294170D02*
X1400940Y294558D01*
G01Y293385D02*
X1398878Y292977D01*
G01X1400940Y294558D02*
X1398878Y294150D01*
G01Y292977D02*
X1396916Y293365D01*
G01X1398878Y294150D02*
X1396916Y294538D01*
G01Y293365D02*
X1394865Y292959D01*
G01X1396916Y294538D02*
X1394865Y294132D01*
G01Y292959D02*
X1392902Y293347D01*
G01X1394865Y294132D02*
X1392902Y294520D01*
G01Y293347D02*
X1391030Y292977D01*
G01X1392902Y294520D02*
X1391030Y294150D01*
G01Y292977D02*
X1389068Y293365D01*
G01X1391030Y294150D02*
X1389068Y294538D01*
G01Y293365D02*
X1383538Y292273D01*
G01X1389068Y294538D02*
X1383598Y293458D01*
G01X1383538Y292273D02*
X1376526Y294416D01*
G01Y294417D02*
X1369514Y296559D01*
G01X1383598Y293458D02*
X1370125Y297576D01*
G01X1369514Y296559D02*
X1366238Y299836D01*
G01X1370125Y297576D02*
X1367388Y300313D01*
G01X1366238Y299836D02*
Y311336D01*
G01X1367388Y300313D02*
Y311813D01*
G01X1366238Y311336D02*
X1365450Y312124D01*
G01X1367388Y311813D02*
X1366600Y312601D01*
G01X1365450Y312124D02*
Y315451D01*
G01X1366600Y312601D02*
Y315928D01*
G01X1365450Y315451D02*
X1364551Y316350D01*
G01X1366600Y315928D02*
X1365028Y317500D01*
G01X1364551Y316350D02*
X1361619D01*
G01X1365028Y317500D02*
X1361619D01*
G01X1404764Y295965D02*
X1402902Y295597D01*
G01X1404764Y297138D02*
X1402902Y296770D01*
G01Y295597D02*
X1400940Y295985D01*
G01X1402902Y296770D02*
X1400940Y297158D01*
G01Y295985D02*
X1398878Y295577D01*
G01X1400940Y297158D02*
X1398878Y296750D01*
G01Y295577D02*
X1396916Y295965D01*
G01X1398878Y296750D02*
X1396916Y297138D01*
G01Y295965D02*
X1394865Y295559D01*
G01X1396916Y297138D02*
X1394865Y296732D01*
G01Y295559D02*
X1392902Y295947D01*
G01X1394865Y296732D02*
X1392902Y297120D01*
G01Y295947D02*
X1391030Y295577D01*
G01X1392902Y297120D02*
X1391030Y296750D01*
G01Y295577D02*
X1389068Y295965D01*
G01X1391030Y296750D02*
X1389068Y297138D01*
G01Y295965D02*
X1386867Y295530D01*
G01X1389068Y297138D02*
X1386867Y296703D01*
G01Y295530D02*
X1380664Y296756D01*
G01X1386867Y296703D02*
X1381029Y297857D01*
G01X1380664Y296756D02*
X1379134Y297487D01*
G01X1381029Y297857D02*
X1379811Y298439D01*
G01X1379134Y297487D02*
X1377104Y299542D01*
G01X1379811Y298439D02*
X1378254Y300015D01*
G01X1377104Y299542D02*
Y313207D01*
G01X1378254Y300015D02*
Y313684D01*
G01X1377104Y313207D02*
X1373591Y316720D01*
G01D02*
X1372415D01*
G01X1378254Y313684D02*
X1374068Y317870D01*
G01X1373591Y316720D02*
X1372415D01*
G01X1374068Y317870D02*
X1372415D01*
G01X1382207Y317250D02*
X1384628D01*
G01X1382251Y318400D02*
X1385105D01*
G01X1384628Y317250D02*
X1386323Y315555D01*
G01X1385105Y318400D02*
X1387473Y316032D01*
G01X1386323Y315555D02*
Y313581D01*
G01X1387473Y316032D02*
Y314058D01*
G01X1386323Y313581D02*
X1388587Y311317D01*
G01X1387473Y314058D02*
X1389737Y311794D01*
G01X1388587Y311317D02*
Y299987D01*
G01X1389737Y311794D02*
Y300464D01*
G01X1388587Y299987D02*
X1389771Y298803D01*
G01X1389737Y300464D02*
X1390378Y299823D01*
G01X1389771Y298803D02*
X1391541Y298278D01*
G01X1390378Y299823D02*
X1391596Y299462D01*
G01X1391541Y298278D02*
X1392992Y298565D01*
G01X1391596Y299462D02*
X1392992Y299738D01*
G01Y298565D02*
X1394954Y298177D01*
G01X1392992Y299738D02*
X1394954Y299350D01*
G01Y298177D02*
X1396916Y298565D01*
G01X1394954Y299350D02*
X1396916Y299738D01*
G01Y298565D02*
X1398878Y298177D01*
G01X1396916Y299738D02*
X1398878Y299350D01*
G01Y298177D02*
X1400840Y298565D01*
G01X1398878Y299350D02*
X1400840Y299738D01*
G01Y298565D02*
X1402802Y298177D01*
G01X1400840Y299738D02*
X1402802Y299350D01*
G01Y298177D02*
X1404764Y298565D01*
G01X1402802Y299350D02*
X1404764Y299738D01*
G01X1390834Y317050D02*
X1388423D01*
G01X1390968Y318200D02*
X1388900D01*
G01X1388423Y317050D02*
X1386529Y318944D01*
G01X1388900Y318200D02*
X1387679Y319421D01*
G01X1386529Y318944D02*
Y321656D01*
G01X1387679Y319421D02*
Y321179D01*
G01X1386529Y321656D02*
X1388023Y323150D01*
G01X1387679Y321179D02*
X1388500Y322000D01*
G01X1388023Y323150D02*
X1393256D01*
G01X1388500Y322000D02*
X1392779D01*
G01X1393256Y323150D02*
X1396237Y320169D01*
G01X1392779Y322000D02*
X1395087Y319692D01*
G01X1396237Y320169D02*
Y314114D01*
G01X1395087Y319692D02*
Y313637D01*
G01X1396237Y314114D02*
X1396601Y313750D01*
G01X1395087Y313637D02*
X1396124Y312600D01*
G01X1396601Y313750D02*
X1414817D01*
G01X1396124Y312600D02*
X1415294D01*
G01X1403903Y318830D02*
X1401885D01*
G01X1404380Y317680D02*
X1401881D01*
G01X1373946Y457675D02*
Y456519D01*
G01X1375096Y457675D02*
Y456042D01*
G01X1373946Y456519D02*
X1373196Y455769D01*
G01X1375096Y456042D02*
X1373673Y454619D01*
G01X1373196Y455769D02*
X1368274D01*
G01X1373673Y454619D02*
X1367797D01*
G01X1368274Y455769D02*
X1367405Y456638D01*
G01X1367797Y454619D02*
X1366255Y456161D01*
G01X1367405Y456638D02*
Y476523D01*
G01X1366255Y456161D02*
Y477000D01*
G01X1375096Y457675D02*
Y456042D01*
G01X1373946Y457675D02*
Y456519D01*
G01X1375096Y456042D02*
X1373673Y454619D01*
G01X1373946Y456519D02*
X1373196Y455769D01*
G01X1373673Y454619D02*
X1367797D01*
G01X1373196Y455769D02*
X1368274D01*
G01X1367797Y454619D02*
X1366255Y456161D01*
G01X1368274Y455769D02*
X1367405Y456638D01*
G01X1366255Y456161D02*
Y477000D01*
G01X1367405Y456638D02*
Y476523D01*
G01X1414077Y449350D02*
X1401849D01*
G01X1413600Y450500D02*
X1401372D01*
G01X1401849Y449350D02*
X1397400Y444901D01*
G01X1401372Y450500D02*
X1396250Y445378D01*
G01X1397400Y444901D02*
Y440627D01*
G01X1396250Y445378D02*
Y440150D01*
G01X1397400Y440627D02*
X1399977Y438050D01*
G01X1396250Y440150D02*
X1399500Y436900D01*
G01X1399977Y438050D02*
X1404977D01*
G01X1399500Y436900D02*
X1404500D01*
G01X1405199Y431700D02*
X1401848D01*
G01X1404722Y432850D02*
X1401848D01*
G01X1394924Y455050D02*
X1393519D01*
G01X1394925Y456200D02*
X1393996D01*
G01X1393519Y455050D02*
X1392184Y456385D01*
G01X1393996Y456200D02*
X1393334Y456862D01*
G01X1392184Y456385D02*
Y459323D01*
G01X1393334Y456862D02*
Y459037D01*
G01X1392184Y459323D02*
X1395007Y464659D01*
G01X1393334Y459037D02*
X1396097Y464259D01*
G01X1395007Y464659D02*
X1397026Y473846D01*
G01X1396097Y464259D02*
X1398205Y473853D01*
G01X1400750Y464462D02*
Y463112D01*
G01Y460462D02*
Y456749D01*
G01X1399600Y472587D02*
Y456272D01*
G01X1400750Y456749D02*
X1401363Y456136D01*
G01X1399600Y456272D02*
X1400886Y454986D01*
G01X1401363Y456136D02*
X1402325D01*
G01X1400886Y454986D02*
X1402325D01*
G01X1413600Y450500D02*
X1401372D01*
G01X1414077Y449350D02*
X1401849D01*
G01X1401372Y450500D02*
X1396250Y445378D01*
G01X1401849Y449350D02*
X1397400Y444901D01*
G01X1396250Y445378D02*
Y440150D01*
G01X1397400Y444901D02*
Y440627D01*
G01X1396250Y440150D02*
X1399500Y436900D01*
G01X1397400Y440627D02*
X1399977Y438050D01*
G01X1399500Y436900D02*
X1404500D01*
G01X1399977Y438050D02*
X1404977D01*
G01X1404722Y432850D02*
X1401848D01*
G01X1405199Y431700D02*
X1401848D01*
G01X1394925Y456200D02*
X1393996D01*
G01X1394924Y455050D02*
X1393519D01*
G01X1393996Y456200D02*
X1393334Y456862D01*
G01X1393519Y455050D02*
X1392184Y456385D01*
G01X1393334Y456862D02*
Y459037D01*
G01X1392184Y456385D02*
Y459323D01*
G01X1393334Y459037D02*
X1396097Y464259D01*
G01X1392184Y459323D02*
X1395007Y464659D01*
G01X1396097Y464259D02*
X1398205Y473853D01*
G01X1395007Y464659D02*
X1397026Y473846D01*
G01X1399600Y472587D02*
Y456272D01*
G01Y472587D02*
Y456272D01*
G01X1400750Y464462D02*
Y463112D01*
G01X1399600Y472587D02*
Y456272D01*
G01X1400750Y460462D02*
Y456749D01*
G01X1399600Y456272D02*
X1400886Y454986D01*
G01X1400750Y456749D02*
X1401363Y456136D01*
G01X1400886Y454986D02*
X1402325D01*
G01X1401363Y456136D02*
X1402325D01*
G01X1367405Y476523D02*
X1375103Y484221D01*
G01X1366255Y477000D02*
X1373953Y484698D01*
G01X1375103Y484221D02*
Y497164D01*
G01X1373953Y484698D02*
Y497641D01*
G01X1375103Y497164D02*
X1388012Y510073D01*
G01X1373953Y497641D02*
X1387535Y511223D01*
G01X1388012Y510073D02*
X1395177D01*
G01X1387535Y511223D02*
X1394700D01*
G01X1395177Y510073D02*
X1397360Y512256D01*
G01X1394700Y511223D02*
X1396883Y513406D01*
G01X1397360Y512256D02*
X1401850D01*
G01X1396883Y513406D02*
X1401373D01*
G01X1401850Y512256D02*
X1416994Y527400D01*
G01X1401373Y513406D02*
X1416517Y528550D01*
G01X1366255Y477000D02*
X1373953Y484698D01*
G01X1367405Y476523D02*
X1375103Y484221D01*
G01X1373953Y484698D02*
Y497641D01*
G01X1375103Y484221D02*
Y497164D01*
G01X1373953Y497641D02*
X1387535Y511223D01*
G01X1375103Y497164D02*
X1388012Y510073D01*
G01X1387535Y511223D02*
X1394700D01*
G01X1388012Y510073D02*
X1395177D01*
G01X1394700Y511223D02*
X1396883Y513406D01*
G01X1395177Y510073D02*
X1397360Y512256D01*
G01X1396883Y513406D02*
X1401373D01*
G01X1397360Y512256D02*
X1401850D01*
G01X1401373Y513406D02*
X1416517Y528550D01*
G01X1401850Y512256D02*
X1416994Y527400D01*
G01X1397026Y473846D02*
X1394540Y484584D01*
G01X1398205Y473853D02*
X1395739Y484506D01*
G01X1394540Y484584D02*
X1401735Y503885D01*
G01X1395739Y484506D02*
X1402678Y503119D01*
G01X1401735Y503885D02*
X1416920Y513473D01*
G01X1402678Y503119D02*
X1403915Y503900D01*
G01X1401735Y503885D02*
X1416920Y513473D01*
G01X1401735Y503885D02*
X1416920Y513473D01*
G01X1401735Y503885D02*
X1416920Y513473D01*
G01X1401735Y503885D02*
X1416920Y513473D01*
G01X1421376Y512496D02*
X1403384Y501136D01*
G01X1404327Y500370D02*
X1400906Y491192D01*
G01X1403384Y501136D02*
X1399707Y491270D01*
G01X1400906Y491192D02*
X1402938Y482418D01*
G01X1399707Y491270D02*
X1401758Y482411D01*
G01X1402938Y482418D02*
X1400750Y472462D01*
G01X1401758Y482411D02*
X1399600Y472587D01*
G01X1400750Y472462D02*
Y467112D01*
G01X1398205Y473853D02*
X1395739Y484506D01*
G01X1397026Y473846D02*
X1394540Y484584D01*
G01X1395739Y484506D02*
X1402678Y503119D01*
G01X1394540Y484584D02*
X1401735Y503885D01*
G01X1402678Y503119D02*
X1403915Y503900D01*
G01X1401735Y503885D02*
X1416920Y513473D01*
G01X1421376Y512496D02*
X1403384Y501136D01*
G01D02*
X1399707Y491270D01*
G01X1404327Y500370D02*
X1400906Y491192D01*
G01X1399707Y491270D02*
X1401758Y482411D01*
G01X1400906Y491192D02*
X1402938Y482418D01*
G01X1401758Y482411D02*
X1399600Y472587D01*
G01X1402938Y482418D02*
X1400750Y472462D01*
G01D02*
Y467112D01*
G01X1406716Y498863D02*
X1403550Y491009D01*
G01X1405787Y499638D02*
X1402347Y491103D01*
G01X1403550Y491009D02*
X1405544Y482399D01*
G01X1402347Y491103D02*
X1404365Y482392D01*
G01D02*
X1403270Y477406D01*
G01D02*
X1407348Y469539D01*
G01X1405787Y499638D02*
X1402347Y491103D01*
G01X1406716Y498863D02*
X1403550Y491009D01*
G01X1402347Y491103D02*
X1404365Y482392D01*
G01X1403550Y491009D02*
X1405544Y482399D01*
G01X1404365Y482392D02*
X1403270Y477406D01*
G01D02*
X1407348Y469539D01*
G01X1404491Y644453D02*
X1403457Y644636D01*
G01X1404491Y644453D02*
X1403457Y644636D01*
G01X1404762Y643237D02*
X1402788Y643586D01*
G01X1403457Y644636D02*
X1403092Y645157D01*
G01X1402788Y643586D02*
X1401876Y644887D01*
G01X1403092Y645157D02*
X1404524Y653277D01*
G01X1401876Y644887D02*
X1403308Y653006D01*
G01X1400339Y654016D02*
X1398721Y644837D01*
G01X1401389Y653346D02*
X1399772Y644168D01*
G01X1398721Y644837D02*
X1398198Y644470D01*
G01D02*
X1397165Y644651D01*
G01X1399772Y644168D02*
X1398469Y643254D01*
G01X1398198Y644470D02*
X1397165Y644651D01*
G01X1398469Y643254D02*
X1396495Y643600D01*
G01X1397165Y644651D02*
X1396801Y645173D01*
G01X1396495Y643600D02*
X1395585Y644905D01*
G01X1396801Y645173D02*
X1398227Y653259D01*
G01X1395585Y644905D02*
X1397011Y652990D01*
G01X1394041Y653998D02*
X1392423Y644833D01*
G01X1395091Y653328D02*
X1393473Y644163D01*
G01X1392423Y644833D02*
X1391902Y644469D01*
G01D02*
X1390870Y644651D01*
G01X1393473Y644163D02*
X1392171Y643253D01*
G01X1391902Y644469D02*
X1390870Y644651D01*
G01X1392171Y643253D02*
X1390200Y643600D01*
G01X1390870Y644651D02*
X1390505Y645173D01*
G01X1390200Y643600D02*
X1389289Y644904D01*
G01X1390505Y645173D02*
X1391932Y653257D01*
G01X1389289Y644904D02*
X1390716Y652988D01*
G01X1387744Y653998D02*
X1386131Y644834D01*
G01X1388794Y653328D02*
X1387182Y644163D01*
G01X1386131Y644834D02*
X1385607Y644469D01*
G01D02*
X1384575Y644649D01*
G01X1387182Y644163D02*
X1385876Y643254D01*
G01X1385607Y644469D02*
X1384575Y644649D01*
G01X1385876Y643254D02*
X1383905Y643598D01*
G01X1384575Y644649D02*
X1384210Y645173D01*
G01X1383905Y643598D02*
X1382994Y644905D01*
G01X1384210Y645173D02*
X1385642Y653290D01*
G01X1382994Y644905D02*
X1384426Y653021D01*
G01X1381454Y654031D02*
X1379839Y644865D01*
G01X1382504Y653361D02*
X1380889Y644196D01*
G01X1379839Y644865D02*
X1379318Y644500D01*
G01D02*
X1378284Y644682D01*
G01X1380889Y644196D02*
X1379588Y643284D01*
G01X1379318Y644500D02*
X1378284Y644682D01*
G01X1379588Y643284D02*
X1377614Y643631D01*
G01X1378284Y644682D02*
X1377919Y645204D01*
G01X1377614Y643631D02*
X1376703Y644935D01*
G01X1377919Y645204D02*
X1379352Y653320D01*
G01X1376703Y644935D02*
X1378136Y653050D01*
G01X1375166Y654063D02*
X1373550Y644901D01*
G01X1376216Y653394D02*
X1374600Y644232D01*
G01X1373550Y644901D02*
X1373026Y644534D01*
G01D02*
X1371994Y644715D01*
G01X1374600Y644232D02*
X1373296Y643318D01*
G01X1373026Y644534D02*
X1371994Y644715D01*
G01X1373296Y643318D02*
X1371322Y643666D01*
G01X1371994Y644715D02*
X1371629Y645238D01*
G01X1371322Y643666D02*
X1370413Y644970D01*
G01X1371629Y645238D02*
X1373053Y653305D01*
G01X1370413Y644970D02*
X1371837Y653036D01*
G01X1368865Y654044D02*
X1367254Y644898D01*
G01X1369915Y653374D02*
X1368305Y644228D01*
G01X1367254Y644898D02*
X1366732Y644533D01*
G01D02*
X1365699Y644714D01*
G01X1368305Y644228D02*
X1367002Y643318D01*
G01X1366732Y644533D02*
X1365699Y644714D01*
G01X1367002Y643318D02*
X1365030Y643663D01*
G01X1365699Y644714D02*
X1365334Y645236D01*
G01X1365030Y643663D02*
X1364118Y644967D01*
G01X1365334Y645236D02*
X1366757Y653304D01*
G01X1364118Y644967D02*
X1365541Y653035D01*
G01X1362569Y654043D02*
X1360955Y644879D01*
G01X1363620Y653373D02*
X1362005Y644209D01*
G01X1360955Y644879D02*
X1360433Y644515D01*
G01D02*
X1359400Y644696D01*
G01X1362005Y644209D02*
X1360702Y643300D01*
G01X1360433Y644515D02*
X1359400Y644696D01*
G01X1360702Y643300D02*
X1358733Y643645D01*
G01X1359400Y644696D02*
X1359034Y645216D01*
G01X1358733Y643645D02*
X1357818Y644945D01*
G01X1359034Y645216D02*
X1360466Y653337D01*
G01X1357818Y644945D02*
X1359250Y653068D01*
G01X1356282Y654076D02*
X1354645Y644802D01*
G01X1357332Y653407D02*
X1355696Y644134D01*
G01X1354645Y644802D02*
X1354122Y644434D01*
G01D02*
X1353088Y644617D01*
G01X1355696Y644134D02*
X1354393Y643218D01*
G01X1354122Y644434D02*
X1353088Y644617D01*
G01X1354393Y643218D02*
X1352419Y643567D01*
G01X1353088Y644617D02*
X1352723Y645138D01*
G01X1352419Y643567D02*
X1351507Y644868D01*
G01X1352723Y645138D02*
X1354169Y653338D01*
G01X1351507Y644868D02*
X1352953Y653067D01*
G01X1349984Y654077D02*
X1348366Y644898D01*
G01X1351034Y653407D02*
X1349417Y644229D01*
G01X1348366Y644898D02*
X1347843Y644531D01*
G01D02*
X1346810Y644712D01*
G01X1349417Y644229D02*
X1348114Y643315D01*
G01X1347843Y644531D02*
X1346810Y644712D01*
G01X1348114Y643315D02*
X1346140Y643661D01*
G01X1346810Y644712D02*
X1346446Y645234D01*
G01X1346140Y643661D02*
X1345230Y644966D01*
G01X1346446Y645234D02*
X1347872Y653320D01*
G01X1345230Y644966D02*
X1346656Y653051D01*
G01X1343686Y654059D02*
X1342068Y644894D01*
G01X1344736Y653389D02*
X1343118Y644224D01*
G01X1404762Y643237D02*
X1402788Y643586D01*
G01X1404491Y644453D02*
X1403457Y644636D01*
G01X1402788Y643586D02*
X1401876Y644887D01*
G01X1403457Y644636D02*
X1403092Y645157D01*
G01X1401876Y644887D02*
X1403308Y653006D01*
G01X1403092Y645157D02*
X1404524Y653277D01*
G01X1401389Y653346D02*
X1399772Y644168D01*
G01X1400339Y654016D02*
X1398721Y644837D01*
G01X1399772Y644168D02*
X1398469Y643254D01*
G01X1398721Y644837D02*
X1398198Y644470D01*
G01X1399772Y644168D02*
X1398469Y643254D01*
G01D02*
X1396495Y643600D01*
G01X1398198Y644470D02*
X1397165Y644651D01*
G01X1396495Y643600D02*
X1395585Y644905D01*
G01X1397165Y644651D02*
X1396801Y645173D01*
G01X1395585Y644905D02*
X1397011Y652990D01*
G01X1396801Y645173D02*
X1398227Y653259D01*
G01X1395091Y653328D02*
X1393473Y644163D01*
G01X1394041Y653998D02*
X1392423Y644833D01*
G01X1393473Y644163D02*
X1392171Y643253D01*
G01X1392423Y644833D02*
X1391902Y644469D01*
G01X1393473Y644163D02*
X1392171Y643253D01*
G01D02*
X1390200Y643600D01*
G01X1391902Y644469D02*
X1390870Y644651D01*
G01X1390200Y643600D02*
X1389289Y644904D01*
G01X1390870Y644651D02*
X1390505Y645173D01*
G01X1389289Y644904D02*
X1390716Y652988D01*
G01X1390505Y645173D02*
X1391932Y653257D01*
G01X1388794Y653328D02*
X1387182Y644163D01*
G01X1387744Y653998D02*
X1386131Y644834D01*
G01X1387182Y644163D02*
X1385876Y643254D01*
G01X1386131Y644834D02*
X1385607Y644469D01*
G01X1387182Y644163D02*
X1385876Y643254D01*
G01D02*
X1383905Y643598D01*
G01X1385607Y644469D02*
X1384575Y644649D01*
G01X1383905Y643598D02*
X1382994Y644905D01*
G01X1384575Y644649D02*
X1384210Y645173D01*
G01X1382994Y644905D02*
X1384426Y653021D01*
G01X1384210Y645173D02*
X1385642Y653290D01*
G01X1382504Y653361D02*
X1380889Y644196D01*
G01X1381454Y654031D02*
X1379839Y644865D01*
G01X1380889Y644196D02*
X1379588Y643284D01*
G01X1379839Y644865D02*
X1379318Y644500D01*
G01X1380889Y644196D02*
X1379588Y643284D01*
G01D02*
X1377614Y643631D01*
G01X1379318Y644500D02*
X1378284Y644682D01*
G01X1377614Y643631D02*
X1376703Y644935D01*
G01X1378284Y644682D02*
X1377919Y645204D01*
G01X1376703Y644935D02*
X1378136Y653050D01*
G01X1377919Y645204D02*
X1379352Y653320D01*
G01X1376216Y653394D02*
X1374600Y644232D01*
G01X1375166Y654063D02*
X1373550Y644901D01*
G01X1374600Y644232D02*
X1373296Y643318D01*
G01X1373550Y644901D02*
X1373026Y644534D01*
G01X1374600Y644232D02*
X1373296Y643318D01*
G01D02*
X1371322Y643666D01*
G01X1373026Y644534D02*
X1371994Y644715D01*
G01X1371322Y643666D02*
X1370413Y644970D01*
G01X1371994Y644715D02*
X1371629Y645238D01*
G01X1370413Y644970D02*
X1371837Y653036D01*
G01X1371629Y645238D02*
X1373053Y653305D01*
G01X1369915Y653374D02*
X1368305Y644228D01*
G01X1368865Y654044D02*
X1367254Y644898D01*
G01X1368305Y644228D02*
X1367002Y643318D01*
G01X1367254Y644898D02*
X1366732Y644533D01*
G01X1368305Y644228D02*
X1367002Y643318D01*
G01D02*
X1365030Y643663D01*
G01X1366732Y644533D02*
X1365699Y644714D01*
G01X1365030Y643663D02*
X1364118Y644967D01*
G01X1365699Y644714D02*
X1365334Y645236D01*
G01X1364118Y644967D02*
X1365541Y653035D01*
G01X1365334Y645236D02*
X1366757Y653304D01*
G01X1363620Y653373D02*
X1362005Y644209D01*
G01X1362569Y654043D02*
X1360955Y644879D01*
G01X1362005Y644209D02*
X1360702Y643300D01*
G01X1360955Y644879D02*
X1360433Y644515D01*
G01X1362005Y644209D02*
X1360702Y643300D01*
G01D02*
X1358733Y643645D01*
G01X1360433Y644515D02*
X1359400Y644696D01*
G01X1358733Y643645D02*
X1357818Y644945D01*
G01X1359400Y644696D02*
X1359034Y645216D01*
G01X1357818Y644945D02*
X1359250Y653068D01*
G01X1359034Y645216D02*
X1360466Y653337D01*
G01X1357332Y653407D02*
X1355696Y644134D01*
G01X1356282Y654076D02*
X1354645Y644802D01*
G01X1355696Y644134D02*
X1354393Y643218D01*
G01X1354645Y644802D02*
X1354122Y644434D01*
G01X1355696Y644134D02*
X1354393Y643218D01*
G01D02*
X1352419Y643567D01*
G01X1354122Y644434D02*
X1353088Y644617D01*
G01X1352419Y643567D02*
X1351507Y644868D01*
G01X1353088Y644617D02*
X1352723Y645138D01*
G01X1351507Y644868D02*
X1352953Y653067D01*
G01X1352723Y645138D02*
X1354169Y653338D01*
G01X1351034Y653407D02*
X1349417Y644229D01*
G01X1349984Y654077D02*
X1348366Y644898D01*
G01X1349417Y644229D02*
X1348114Y643315D01*
G01X1348366Y644898D02*
X1347843Y644531D01*
G01X1349417Y644229D02*
X1348114Y643315D01*
G01D02*
X1346140Y643661D01*
G01X1347843Y644531D02*
X1346810Y644712D01*
G01X1346140Y643661D02*
X1345230Y644966D01*
G01X1346810Y644712D02*
X1346446Y645234D01*
G01X1345230Y644966D02*
X1346656Y653051D01*
G01X1346446Y645234D02*
X1347872Y653320D01*
G01X1344736Y653389D02*
X1343118Y644224D01*
G01X1343686Y654059D02*
X1342068Y644894D01*
G01X1404524Y653277D02*
X1403615Y654578D01*
G01X1403308Y653006D02*
X1402945Y653528D01*
G01X1403615Y654578D02*
X1401642Y654926D01*
G01D02*
X1400339Y654016D01*
G01X1402945Y653528D02*
X1401911Y653711D01*
G01X1401642Y654926D02*
X1400339Y654016D01*
G01X1401911Y653711D02*
X1401389Y653346D01*
G01X1398227Y653259D02*
X1397317Y654562D01*
G01X1397011Y652990D02*
X1396647Y653511D01*
G01X1397317Y654562D02*
X1395344Y654907D01*
G01D02*
X1394041Y653998D01*
G01X1396647Y653511D02*
X1395613Y653692D01*
G01X1395344Y654907D02*
X1394041Y653998D01*
G01X1395613Y653692D02*
X1395091Y653328D01*
G01X1391932Y653257D02*
X1391021Y654561D01*
G01X1390716Y652988D02*
X1390351Y653510D01*
G01X1391021Y654561D02*
X1389047Y654907D01*
G01D02*
X1387744Y653998D01*
G01X1390351Y653510D02*
X1389316Y653692D01*
G01X1389047Y654907D02*
X1387744Y653998D01*
G01X1389316Y653692D02*
X1388794Y653328D01*
G01X1385642Y653290D02*
X1384731Y654594D01*
G01X1384426Y653021D02*
X1384061Y653543D01*
G01X1384731Y654594D02*
X1382757Y654940D01*
G01D02*
X1381454Y654031D01*
G01X1384061Y653543D02*
X1383026Y653725D01*
G01X1382757Y654940D02*
X1381454Y654031D01*
G01X1383026Y653725D02*
X1382504Y653361D01*
G01X1379352Y653320D02*
X1378439Y654624D01*
G01X1378136Y653050D02*
X1377769Y653574D01*
G01X1378439Y654624D02*
X1376466Y654973D01*
G01D02*
X1375166Y654063D01*
G01X1377769Y653574D02*
X1376735Y653757D01*
G01X1376466Y654973D02*
X1375166Y654063D01*
G01X1376735Y653757D02*
X1376216Y653394D01*
G01X1373053Y653305D02*
X1372143Y654608D01*
G01X1371837Y653036D02*
X1371473Y653557D01*
G01X1372143Y654608D02*
X1370169Y654954D01*
G01D02*
X1368865Y654044D01*
G01X1371473Y653557D02*
X1370438Y653739D01*
G01X1370169Y654954D02*
X1368865Y654044D01*
G01X1370438Y653739D02*
X1369915Y653374D01*
G01X1366757Y653304D02*
X1365847Y654607D01*
G01X1365541Y653035D02*
X1365177Y653556D01*
G01X1365847Y654607D02*
X1363873Y654953D01*
G01D02*
X1362569Y654043D01*
G01X1365177Y653556D02*
X1364143Y653738D01*
G01X1363873Y654953D02*
X1362569Y654043D01*
G01X1364143Y653738D02*
X1363620Y653373D01*
G01X1360466Y653337D02*
X1359556Y654640D01*
G01X1359250Y653068D02*
X1358886Y653589D01*
G01X1359556Y654640D02*
X1357582Y654987D01*
G01D02*
X1356282Y654076D01*
G01X1358886Y653589D02*
X1357852Y653771D01*
G01X1357582Y654987D02*
X1356282Y654076D01*
G01X1357852Y653771D02*
X1357332Y653407D01*
G01X1354169Y653338D02*
X1353260Y654639D01*
G01X1352953Y653067D02*
X1352590Y653589D01*
G01X1353260Y654639D02*
X1351287Y654987D01*
G01D02*
X1349984Y654077D01*
G01X1352590Y653589D02*
X1351556Y653772D01*
G01X1351287Y654987D02*
X1349984Y654077D01*
G01X1351556Y653772D02*
X1351034Y653407D01*
G01X1347872Y653320D02*
X1346962Y654623D01*
G01X1346656Y653051D02*
X1346292Y653572D01*
G01X1346962Y654623D02*
X1344989Y654968D01*
G01D02*
X1343686Y654059D01*
G01X1346292Y653572D02*
X1345258Y653753D01*
G01X1344989Y654968D02*
X1343686Y654059D01*
G01X1345258Y653753D02*
X1344736Y653389D01*
G01X1403308Y653006D02*
X1402945Y653528D01*
G01X1404524Y653277D02*
X1403615Y654578D01*
G01X1402945Y653528D02*
X1401911Y653711D01*
G01X1403615Y654578D02*
X1401642Y654926D01*
G01X1402945Y653528D02*
X1401911Y653711D01*
G01D02*
X1401389Y653346D01*
G01X1401642Y654926D02*
X1400339Y654016D01*
G01X1397011Y652990D02*
X1396647Y653511D01*
G01X1398227Y653259D02*
X1397317Y654562D01*
G01X1396647Y653511D02*
X1395613Y653692D01*
G01X1397317Y654562D02*
X1395344Y654907D01*
G01X1396647Y653511D02*
X1395613Y653692D01*
G01D02*
X1395091Y653328D01*
G01X1395344Y654907D02*
X1394041Y653998D01*
G01X1390716Y652988D02*
X1390351Y653510D01*
G01X1391932Y653257D02*
X1391021Y654561D01*
G01X1390351Y653510D02*
X1389316Y653692D01*
G01X1391021Y654561D02*
X1389047Y654907D01*
G01X1390351Y653510D02*
X1389316Y653692D01*
G01D02*
X1388794Y653328D01*
G01X1389047Y654907D02*
X1387744Y653998D01*
G01X1384426Y653021D02*
X1384061Y653543D01*
G01X1385642Y653290D02*
X1384731Y654594D01*
G01X1384061Y653543D02*
X1383026Y653725D01*
G01X1384731Y654594D02*
X1382757Y654940D01*
G01X1384061Y653543D02*
X1383026Y653725D01*
G01D02*
X1382504Y653361D01*
G01X1382757Y654940D02*
X1381454Y654031D01*
G01X1378136Y653050D02*
X1377769Y653574D01*
G01X1379352Y653320D02*
X1378439Y654624D01*
G01X1377769Y653574D02*
X1376735Y653757D01*
G01X1378439Y654624D02*
X1376466Y654973D01*
G01X1377769Y653574D02*
X1376735Y653757D01*
G01D02*
X1376216Y653394D01*
G01X1376466Y654973D02*
X1375166Y654063D01*
G01X1371837Y653036D02*
X1371473Y653557D01*
G01X1373053Y653305D02*
X1372143Y654608D01*
G01X1371473Y653557D02*
X1370438Y653739D01*
G01X1372143Y654608D02*
X1370169Y654954D01*
G01X1371473Y653557D02*
X1370438Y653739D01*
G01D02*
X1369915Y653374D01*
G01X1370169Y654954D02*
X1368865Y654044D01*
G01X1365541Y653035D02*
X1365177Y653556D01*
G01X1366757Y653304D02*
X1365847Y654607D01*
G01X1365177Y653556D02*
X1364143Y653738D01*
G01X1365847Y654607D02*
X1363873Y654953D01*
G01X1365177Y653556D02*
X1364143Y653738D01*
G01D02*
X1363620Y653373D01*
G01X1363873Y654953D02*
X1362569Y654043D01*
G01X1359250Y653068D02*
X1358886Y653589D01*
G01X1360466Y653337D02*
X1359556Y654640D01*
G01X1358886Y653589D02*
X1357852Y653771D01*
G01X1359556Y654640D02*
X1357582Y654987D01*
G01X1358886Y653589D02*
X1357852Y653771D01*
G01D02*
X1357332Y653407D01*
G01X1357582Y654987D02*
X1356282Y654076D01*
G01X1352953Y653067D02*
X1352590Y653589D01*
G01X1354169Y653338D02*
X1353260Y654639D01*
G01X1352590Y653589D02*
X1351556Y653772D01*
G01X1353260Y654639D02*
X1351287Y654987D01*
G01X1352590Y653589D02*
X1351556Y653772D01*
G01D02*
X1351034Y653407D01*
G01X1351287Y654987D02*
X1349984Y654077D01*
G01X1346656Y653051D02*
X1346292Y653572D01*
G01X1347872Y653320D02*
X1346962Y654623D01*
G01X1346292Y653572D02*
X1345258Y653753D01*
G01X1346962Y654623D02*
X1344989Y654968D01*
G01X1346292Y653572D02*
X1345258Y653753D01*
G01D02*
X1344736Y653389D01*
G01X1344989Y654968D02*
X1343686Y654059D01*
G01X1424367Y21615D02*
Y12013D01*
G01X1425517D02*
Y21489D01*
G01X1426379Y30746D02*
X1426094Y29458D01*
G01X1425518Y26840D02*
X1425228Y25521D01*
G01X1424657Y22933D02*
X1424367Y21615D01*
G01X1425517Y21489D02*
X1431488Y48592D01*
G01X1434100Y8206D02*
Y14473D01*
G01X1432950Y8206D02*
Y14950D01*
G01X1434100Y14473D02*
X1436325Y16698D01*
G01X1432950Y14950D02*
X1435175Y17175D01*
G01X1436325Y16698D02*
Y41303D01*
G01X1435175Y17175D02*
Y18525D01*
G01X1436325Y16698D02*
Y41303D01*
G01X1435175Y21175D02*
Y22525D01*
G01X1436325Y16698D02*
Y41303D01*
G01X1435175Y25175D02*
Y26525D01*
G01X1436325Y16698D02*
Y41303D01*
G01X1435175Y29175D02*
Y30525D01*
G01X1436325Y16698D02*
Y41303D01*
G01X1425517Y21489D02*
X1431488Y48592D01*
G01X1425517Y21489D02*
X1431488Y48592D01*
G01X1425517Y21489D02*
X1431488Y48592D01*
G01X1426379Y30746D02*
X1426094Y29458D01*
G01X1425517Y21489D02*
X1431488Y48592D01*
G01X1425518Y26840D02*
X1425228Y25521D01*
G01X1425517Y21489D02*
X1431488Y48592D01*
G01X1424657Y22933D02*
X1424367Y21615D01*
G01X1425517Y12013D02*
Y21489D01*
G01X1424367Y21615D02*
Y12013D01*
G01X1432950Y8206D02*
Y14950D01*
G01X1434100Y8206D02*
Y14473D01*
G01X1432950Y14950D02*
X1435175Y17175D01*
G01X1434100Y14473D02*
X1436325Y16698D01*
G01X1435175Y17175D02*
Y18525D01*
G01Y21175D02*
Y22525D01*
G01Y25175D02*
Y26525D01*
G01Y29175D02*
Y30525D01*
G01X1436325Y16698D02*
Y41303D01*
G01X1465656Y24060D02*
X1464701Y25014D01*
G01X1462827Y26888D02*
X1458167Y31548D01*
G01X1472463Y18880D02*
X1459152Y32191D01*
G01X1458167Y31548D02*
X1454131Y41908D01*
G01X1459152Y32191D02*
X1455088Y42622D01*
G01X1462162Y12013D02*
Y14193D01*
G01X1463312Y12013D02*
Y14412D01*
G01X1462162Y14193D02*
X1461667Y15449D01*
G01X1460694Y17914D02*
X1460199Y19170D01*
G01X1463312Y14412D02*
X1460297Y22056D01*
G01X1459206Y21695D02*
X1451816Y40418D01*
G01X1460277Y22116D02*
X1452767Y41144D01*
G01X1451916Y5999D02*
Y18971D01*
G01X1453066Y5988D02*
Y19125D01*
G01X1451916Y18971D02*
X1451561Y20273D01*
G01X1450864Y22830D02*
X1450509Y24133D01*
G01X1449812Y26689D02*
X1449457Y27992D01*
G01X1448759Y30548D02*
X1447178Y36348D01*
G01X1453066Y19125D02*
X1448187Y37023D01*
G01X1444415Y12013D02*
Y16829D01*
G01X1443265Y12013D02*
Y16384D01*
G01X1444222Y17022D02*
X1442905Y18998D01*
G01X1443265Y16384D02*
X1441822Y18549D01*
G01X1442905Y18998D02*
X1439766Y34692D01*
G01X1441822Y18549D02*
X1441557Y19873D01*
G01X1442905Y18998D02*
X1439766Y34692D01*
G01X1441037Y22471D02*
X1440773Y23795D01*
G01X1442905Y18998D02*
X1439766Y34692D01*
G01X1440253Y26394D02*
X1439988Y27717D01*
G01X1442905Y18998D02*
X1439766Y34692D01*
G01X1439468Y30316D02*
X1438593Y34692D01*
G01X1461484Y39818D02*
X1465147Y30366D01*
G01D02*
X1469746Y25767D01*
G01X1472463Y18880D02*
X1459152Y32191D01*
G01X1472463Y18880D02*
X1459152Y32191D01*
G01X1472463Y18880D02*
X1459152Y32191D01*
G01X1465656Y24060D02*
X1464701Y25014D01*
G01X1472463Y18880D02*
X1459152Y32191D01*
G01X1462827Y26888D02*
X1458167Y31548D01*
G01X1459152Y32191D02*
X1455088Y42622D01*
G01X1458167Y31548D02*
X1454131Y41908D01*
G01X1463312Y12013D02*
Y14412D01*
G01X1462162Y12013D02*
Y14193D01*
G01X1463312Y14412D02*
X1460297Y22056D01*
G01X1462162Y14193D02*
X1461667Y15449D01*
G01X1463312Y14412D02*
X1460297Y22056D01*
G01X1460694Y17914D02*
X1460199Y19170D01*
G01X1460277Y22116D02*
X1452767Y41144D01*
G01X1459206Y21695D02*
X1451816Y40418D01*
G01X1453066Y5988D02*
Y19125D01*
G01X1451916Y5999D02*
Y18971D01*
G01X1453066Y19125D02*
X1448187Y37023D01*
G01X1451916Y18971D02*
X1451561Y20273D01*
G01X1453066Y19125D02*
X1448187Y37023D01*
G01X1450864Y22830D02*
X1450509Y24133D01*
G01X1453066Y19125D02*
X1448187Y37023D01*
G01X1449812Y26689D02*
X1449457Y27992D01*
G01X1453066Y19125D02*
X1448187Y37023D01*
G01X1448759Y30548D02*
X1447178Y36348D01*
G01X1443265Y12013D02*
Y16384D01*
G01X1444415Y12013D02*
Y16829D01*
G01X1443265Y16384D02*
X1441822Y18549D01*
G01X1444222Y17022D02*
X1442905Y18998D01*
G01X1441822Y18549D02*
X1441557Y19873D01*
G01X1441037Y22471D02*
X1440773Y23795D01*
G01X1440253Y26394D02*
X1439988Y27717D01*
G01X1439468Y30316D02*
X1438593Y34692D01*
G01X1442905Y18998D02*
X1439766Y34692D01*
G01X1461484Y39818D02*
X1465147Y30366D01*
G01D02*
X1469746Y25767D01*
G01X1430311Y48596D02*
X1427815Y37270D01*
G01X1427239Y34652D02*
X1426949Y33334D01*
G01X1418641Y103140D02*
X1430311Y48596D01*
G01X1431488Y48592D02*
X1419720Y103595D01*
G01X1435175Y33175D02*
Y41181D01*
G01X1436325Y41303D02*
X1423094Y103128D01*
G01X1435175Y41181D02*
X1422015Y102673D01*
G01X1431488Y48592D02*
X1419720Y103595D01*
G01X1418641Y103140D02*
X1430311Y48596D01*
G01D02*
X1427815Y37270D01*
G01X1427239Y34652D02*
X1426949Y33334D01*
G01X1435175Y33175D02*
Y41181D01*
G01D02*
X1422015Y102673D01*
G01X1436325Y41303D02*
X1423094Y103128D01*
G01X1454131Y41908D02*
X1444660Y49262D01*
G01X1455088Y42622D02*
X1445697Y49913D01*
G01X1444660Y49262D02*
X1432720Y105069D01*
G01X1445697Y49913D02*
X1433799Y105524D01*
G01X1451815Y40421D02*
X1450740Y41238D01*
G01D02*
X1449829Y41113D01*
G01X1448630Y42841D02*
X1447555Y43658D01*
G01D02*
X1446644Y43533D01*
G01X1445445Y45261D02*
X1442314Y47639D01*
G01X1452766Y41144D02*
X1443350Y48297D01*
G01X1442314Y47639D02*
X1430190Y104314D01*
G01X1443350Y48297D02*
X1431269Y104769D01*
G01X1447178Y36348D02*
X1440960Y41154D01*
G01X1448187Y37023D02*
X1441997Y41807D01*
G01X1440960Y41154D02*
X1427602Y103596D01*
G01X1441997Y41807D02*
X1428681Y104051D01*
G01X1439766Y34692D02*
X1440232Y37021D01*
G01X1438593Y34692D02*
X1439057Y37014D01*
G01X1440232Y37021D02*
X1426184Y103148D01*
G01X1439057Y37014D02*
X1425104Y102693D01*
G01X1463400Y95126D02*
X1471462Y60537D01*
G01X1464402Y95897D02*
X1472522Y61061D01*
G01X1448259Y100390D02*
X1461086Y93367D01*
G01X1449279Y101144D02*
X1462090Y94130D01*
G01X1461086Y93367D02*
X1465747Y73374D01*
G01X1462090Y94130D02*
X1466868Y73635D01*
G01X1461254Y85347D02*
X1467553Y58325D01*
G01X1466494Y57802D02*
X1460300Y84372D01*
G01X1461254Y85347D02*
X1467553Y58325D01*
G01X1460300Y84372D02*
X1460237Y84642D01*
G01X1451025Y92166D02*
X1461254Y85347D01*
G01X1460237Y84642D02*
X1455216Y87989D01*
G01X1451025Y92166D02*
X1461254Y85347D01*
G01X1455216Y87990D02*
X1450195Y91336D01*
G01X1447142Y97984D02*
X1451025Y92166D01*
G01X1450195Y91336D02*
X1446059Y97535D01*
G01X1472559Y39731D02*
X1451714Y55934D01*
G01X1473397Y40537D02*
X1452753Y56584D01*
G01X1451714Y55934D02*
X1440970Y106796D01*
G01X1452753Y56584D02*
X1442050Y107250D01*
G01X1437938Y106593D02*
X1449638Y51905D01*
G01X1439017Y107048D02*
X1450672Y52570D01*
G01X1449638Y51905D02*
X1449985Y51647D01*
G01D02*
X1449986D01*
G01D02*
X1464711Y40710D01*
G01X1450672Y52570D02*
X1465659Y41440D01*
G01X1464711Y40710D02*
X1467636Y33385D01*
G01X1435127Y106210D02*
X1447021Y50610D01*
G01X1436206Y106665D02*
X1448056Y51274D01*
G01X1447021Y50610D02*
X1460000Y40925D01*
G01D02*
X1460300Y40701D01*
G01D02*
X1461484Y39818D01*
G01X1448056Y51274D02*
X1462437Y40542D01*
G01D02*
X1466132Y31008D01*
G01X1455088Y42622D02*
X1445697Y49913D01*
G01X1454131Y41908D02*
X1444660Y49262D01*
G01X1445697Y49913D02*
X1433799Y105524D01*
G01X1444660Y49262D02*
X1432720Y105069D01*
G01X1452766Y41144D02*
X1443350Y48297D01*
G01X1451815Y40421D02*
X1450740Y41238D01*
G01X1452766Y41144D02*
X1443350Y48297D01*
G01X1450740Y41238D02*
X1449829Y41113D01*
G01X1452766Y41144D02*
X1443350Y48297D01*
G01X1448630Y42841D02*
X1447555Y43658D01*
G01X1452766Y41144D02*
X1443350Y48297D01*
G01X1447555Y43658D02*
X1446644Y43533D01*
G01X1452766Y41144D02*
X1443350Y48297D01*
G01X1445445Y45261D02*
X1442314Y47639D01*
G01X1443350Y48297D02*
X1431269Y104769D01*
G01X1442314Y47639D02*
X1430190Y104314D01*
G01X1448187Y37023D02*
X1441997Y41807D01*
G01X1447178Y36348D02*
X1440960Y41154D01*
G01X1441997Y41807D02*
X1428681Y104051D01*
G01X1440960Y41154D02*
X1427602Y103596D01*
G01X1438593Y34692D02*
X1439057Y37014D01*
G01X1439766Y34692D02*
X1440232Y37021D01*
G01X1439057Y37014D02*
X1425104Y102693D01*
G01X1440232Y37021D02*
X1426184Y103148D01*
G01X1464402Y95897D02*
X1472522Y61061D01*
G01X1463400Y95126D02*
X1471462Y60537D01*
G01X1449279Y101144D02*
X1462090Y94130D01*
G01X1448259Y100390D02*
X1461086Y93367D01*
G01X1462090Y94130D02*
X1466868Y73635D01*
G01X1461086Y93367D02*
X1465747Y73374D01*
G01X1450195Y91336D02*
X1446059Y97535D01*
G01X1447142Y97984D02*
X1451025Y92166D01*
G01X1460237Y84642D02*
X1455216Y87989D01*
G01Y87990D02*
X1450195Y91336D01*
G01X1451025Y92166D02*
X1461254Y85347D01*
G01X1466494Y57802D02*
X1460300Y84372D01*
G01D02*
X1460237Y84642D01*
G01X1461254Y85347D02*
X1467553Y58325D01*
G01X1473397Y40537D02*
X1452753Y56584D01*
G01X1472559Y39731D02*
X1451714Y55934D01*
G01X1452753Y56584D02*
X1442050Y107250D01*
G01X1451714Y55934D02*
X1440970Y106796D01*
G01X1439017Y107048D02*
X1450672Y52570D01*
G01X1437938Y106593D02*
X1449638Y51905D01*
G01X1450672Y52570D02*
X1465659Y41440D01*
G01X1449638Y51905D02*
X1449985Y51647D01*
G01X1450672Y52570D02*
X1465659Y41440D01*
G01X1449985Y51647D02*
X1449986D01*
G01X1450672Y52570D02*
X1465659Y41440D01*
G01X1449986Y51647D02*
X1464711Y40710D01*
G01D02*
X1467636Y33385D01*
G01X1436206Y106665D02*
X1448056Y51274D01*
G01X1435127Y106210D02*
X1447021Y50610D01*
G01X1448056Y51274D02*
X1462437Y40542D01*
G01X1447021Y50610D02*
X1460000Y40925D01*
G01X1448056Y51274D02*
X1462437Y40542D01*
G01X1460000Y40925D02*
X1460300Y40701D01*
G01X1448056Y51274D02*
X1462437Y40542D01*
G01X1460300Y40701D02*
X1461484Y39818D01*
G01X1462437Y40542D02*
X1466132Y31008D01*
G01X1423094Y103128D02*
X1404625Y130834D01*
G01X1422015Y102673D02*
X1403795Y130004D01*
G01X1422015Y102673D02*
X1403795Y130004D01*
G01X1423094Y103128D02*
X1404625Y130834D01*
G01X1432720Y105069D02*
X1411062Y137556D01*
G01X1433799Y105524D02*
X1411892Y138386D01*
G01X1430190Y104314D02*
X1409371Y135544D01*
G01X1431269Y104769D02*
X1410201Y136374D01*
G01X1427602Y103596D02*
X1407479Y133781D01*
G01X1428681Y104051D02*
X1408309Y134611D01*
G01X1426184Y103148D02*
X1406488Y132690D01*
G01X1425104Y102693D02*
X1415381Y117277D01*
G01X1426184Y103148D02*
X1406488Y132690D01*
G01X1415381Y117277D02*
X1405658Y131860D01*
G01X1427633Y171868D02*
X1432011Y149993D01*
G01X1428717Y172315D02*
X1433095Y150442D01*
G01X1432011Y149993D02*
X1442667Y133977D01*
G01X1433095Y150442D02*
X1443497Y134806D01*
G01X1442667Y133977D02*
X1452688Y127296D01*
G01X1443497Y134806D02*
X1453515Y128127D01*
G01X1452688Y127296D02*
X1453712Y125776D01*
G01Y125775D02*
X1453719Y125765D01*
G01D02*
X1453860Y125555D01*
G01X1453515Y128127D02*
X1454667Y126418D01*
G01X1452688Y127296D02*
X1453712Y125776D01*
G01X1453719Y125765D02*
X1453860Y125555D01*
G01X1454670Y126414D02*
X1454695Y126376D01*
G01X1453860Y125555D02*
X1461301Y120403D01*
G01X1454695Y126376D02*
X1462332Y121089D01*
G01X1461301Y120403D02*
X1464934Y103245D01*
G01X1462332Y121089D02*
X1465950Y104001D01*
G01X1464934Y103245D02*
X1470362Y100277D01*
G01X1424979Y171250D02*
X1429438Y149346D01*
G01X1426062Y171699D02*
X1430520Y149796D01*
G01X1429438Y149346D02*
X1440921Y132086D01*
G01X1430520Y149796D02*
X1441751Y132915D01*
G01X1440921Y132086D02*
X1450579Y125655D01*
G01X1441751Y132915D02*
X1451414Y126481D01*
G01X1450579Y125655D02*
X1452050Y123394D01*
G01X1451414Y126481D02*
X1452891Y124212D01*
G01X1452050Y123394D02*
X1459002Y118585D01*
G01X1452891Y124212D02*
X1460030Y119273D01*
G01X1459002Y118585D02*
X1462793Y101306D01*
G01X1460030Y119273D02*
X1463805Y102066D01*
G01X1462793Y101306D02*
X1468071Y98437D01*
G01X1463805Y102066D02*
X1469074Y99201D01*
G01X1422643Y170006D02*
X1427705Y145042D01*
G01X1423726Y170454D02*
X1428788Y145492D01*
G01X1427705Y145042D02*
X1444205Y120249D01*
G01X1428788Y145492D02*
X1444900Y121282D01*
G01X1444205Y120249D02*
X1454813Y118094D01*
G01X1444900Y121282D02*
X1455272Y119175D01*
G01X1454813Y118094D02*
X1456702Y116797D01*
G01X1455272Y119175D02*
X1457727Y117489D01*
G01X1456702Y116797D02*
X1460532Y99585D01*
G01X1457727Y117489D02*
X1461541Y100348D01*
G01X1460532Y99585D02*
X1465735Y96780D01*
G01X1461541Y100348D02*
X1466738Y97547D01*
G01X1420227Y168925D02*
X1425273Y144103D01*
G01X1421310Y169374D02*
X1426356Y144553D01*
G01X1425273Y144103D02*
X1442697Y117955D01*
G01X1426356Y144553D02*
X1443390Y118990D01*
G01X1442697Y117955D02*
X1453450Y115806D01*
G01X1443390Y118990D02*
X1453899Y116890D01*
G01X1453450Y115806D02*
X1454289Y115246D01*
G01X1453899Y116890D02*
X1455310Y115948D01*
G01X1454289Y115246D02*
X1458213Y97880D01*
G01X1455310Y115948D02*
X1459219Y98649D01*
G01X1458213Y97880D02*
X1463400Y95126D01*
G01X1459219Y98649D02*
X1464402Y95897D01*
G01X1417872Y167917D02*
X1422932Y142965D01*
G01X1418955Y168365D02*
X1424015Y143415D01*
G01X1422932Y142964D02*
X1446880Y107094D01*
G01X1424015Y143413D02*
X1447962Y107546D01*
G01X1446880Y107094D02*
X1448259Y100390D01*
G01X1447962Y107546D02*
X1449279Y101144D01*
G01X1445368Y106857D02*
X1447142Y97984D01*
G01X1446059Y97535D02*
X1444285Y106408D01*
G01X1421539Y142601D02*
X1445368Y106857D01*
G01X1444285Y106408D02*
X1420456Y142151D01*
G01X1416515Y167383D02*
X1421539Y142601D01*
G01X1420456Y142151D02*
X1415432Y166935D01*
G01X1440970Y106796D02*
X1418047Y141178D01*
G01X1442050Y107250D02*
X1419130Y141629D01*
G01X1418047Y141178D02*
X1413015Y165916D01*
G01X1419130Y141629D02*
X1414142Y166145D01*
G01X1418047Y141178D02*
X1413015Y165916D01*
G01X1410590Y165006D02*
X1415639Y140043D01*
G01X1411673Y165454D02*
X1416722Y140493D01*
G01X1415639Y140043D02*
X1437938Y106593D01*
G01X1416722Y140493D02*
X1439017Y107048D01*
G01X1408191Y163950D02*
X1413189Y139115D01*
G01X1409274Y164398D02*
X1414272Y139564D01*
G01X1413189Y139115D02*
X1435127Y106210D01*
G01X1414272Y139564D02*
X1436206Y106665D01*
G01X1431014Y173617D02*
X1435374Y151821D01*
G01X1429930Y173170D02*
X1434290Y151373D01*
G01X1435374Y151821D02*
X1445539Y136539D01*
G01X1434290Y151373D02*
X1444709Y135710D01*
G01X1445539Y136539D02*
X1455937Y129605D01*
G01X1444709Y135710D02*
X1455107Y128776D01*
G01X1455937Y129605D02*
X1457093Y127869D01*
G01X1455107Y128776D02*
X1455955Y127501D01*
G01X1455937Y129605D02*
X1457093Y127869D01*
G01X1457094Y127868D02*
X1457152Y127782D01*
G01X1455956Y127501D02*
X1456316Y126960D01*
G01X1457152Y127782D02*
X1464700Y122579D01*
G01X1456316Y126960D02*
X1463667Y121893D01*
G01X1464700Y122579D02*
X1468205Y105661D01*
G01X1463667Y121893D02*
X1467186Y104908D01*
G01X1433799Y105524D02*
X1411892Y138386D01*
G01X1432720Y105069D02*
X1411062Y137556D01*
G01X1431269Y104769D02*
X1410201Y136374D01*
G01X1430190Y104314D02*
X1409371Y135544D01*
G01X1428681Y104051D02*
X1408309Y134611D01*
G01X1427602Y103596D02*
X1407479Y133781D01*
G01X1425104Y102693D02*
X1415381Y117277D01*
G01D02*
X1405658Y131860D01*
G01X1426184Y103148D02*
X1406488Y132690D01*
G01X1428717Y172315D02*
X1433095Y150442D01*
G01X1427633Y171868D02*
X1432011Y149993D01*
G01X1433095Y150442D02*
X1443497Y134806D01*
G01X1432011Y149993D02*
X1442667Y133977D01*
G01X1443497Y134806D02*
X1453515Y128127D01*
G01X1442667Y133977D02*
X1452688Y127296D01*
G01X1453515Y128127D02*
X1454667Y126418D01*
G01X1454670Y126414D02*
X1454695Y126376D01*
G01X1452688Y127296D02*
X1453712Y125776D01*
G01X1453515Y128127D02*
X1454667Y126418D01*
G01X1453712Y125775D02*
X1453719Y125765D01*
G01X1453515Y128127D02*
X1454667Y126418D01*
G01X1454670Y126414D02*
X1454695Y126376D01*
G01X1453719Y125765D02*
X1453860Y125555D01*
G01X1454695Y126376D02*
X1462332Y121089D01*
G01X1453860Y125555D02*
X1461301Y120403D01*
G01X1462332Y121089D02*
X1465950Y104001D01*
G01X1461301Y120403D02*
X1464934Y103245D01*
G01D02*
X1470362Y100277D01*
G01X1426062Y171699D02*
X1430520Y149796D01*
G01X1424979Y171250D02*
X1429438Y149346D01*
G01X1430520Y149796D02*
X1441751Y132915D01*
G01X1429438Y149346D02*
X1440921Y132086D01*
G01X1441751Y132915D02*
X1451414Y126481D01*
G01X1440921Y132086D02*
X1450579Y125655D01*
G01X1451414Y126481D02*
X1452891Y124212D01*
G01X1450579Y125655D02*
X1452050Y123394D01*
G01X1452891Y124212D02*
X1460030Y119273D01*
G01X1452050Y123394D02*
X1459002Y118585D01*
G01X1460030Y119273D02*
X1463805Y102066D01*
G01X1459002Y118585D02*
X1462793Y101306D01*
G01X1463805Y102066D02*
X1469074Y99201D01*
G01X1462793Y101306D02*
X1468071Y98437D01*
G01X1423726Y170454D02*
X1428788Y145492D01*
G01X1422643Y170006D02*
X1427705Y145042D01*
G01X1428788Y145492D02*
X1444900Y121282D01*
G01X1427705Y145042D02*
X1444205Y120249D01*
G01X1444900Y121282D02*
X1455272Y119175D01*
G01X1444205Y120249D02*
X1454813Y118094D01*
G01X1455272Y119175D02*
X1457727Y117489D01*
G01X1454813Y118094D02*
X1456702Y116797D01*
G01X1457727Y117489D02*
X1461541Y100348D01*
G01X1456702Y116797D02*
X1460532Y99585D01*
G01X1461541Y100348D02*
X1466738Y97547D01*
G01X1460532Y99585D02*
X1465735Y96780D01*
G01X1421310Y169374D02*
X1426356Y144553D01*
G01X1420227Y168925D02*
X1425273Y144103D01*
G01X1426356Y144553D02*
X1443390Y118990D01*
G01X1425273Y144103D02*
X1442697Y117955D01*
G01X1443390Y118990D02*
X1453899Y116890D01*
G01X1442697Y117955D02*
X1453450Y115806D01*
G01X1453899Y116890D02*
X1455310Y115948D01*
G01X1453450Y115806D02*
X1454289Y115246D01*
G01X1455310Y115948D02*
X1459219Y98649D01*
G01X1454289Y115246D02*
X1458213Y97880D01*
G01X1459219Y98649D02*
X1464402Y95897D01*
G01X1458213Y97880D02*
X1463400Y95126D01*
G01X1418955Y168365D02*
X1424015Y143415D01*
G01X1417872Y167917D02*
X1422932Y142965D01*
G01X1424015Y143413D02*
X1447962Y107546D01*
G01X1422932Y142964D02*
X1446880Y107094D01*
G01X1447962Y107546D02*
X1449279Y101144D01*
G01X1446880Y107094D02*
X1448259Y100390D01*
G01X1420456Y142151D02*
X1415432Y166935D01*
G01X1416515Y167383D02*
X1421539Y142601D01*
G01X1444285Y106408D02*
X1420456Y142151D01*
G01X1421539Y142601D02*
X1445368Y106857D01*
G01X1446059Y97535D02*
X1444285Y106408D01*
G01X1445368Y106857D02*
X1447142Y97984D01*
G01X1442050Y107250D02*
X1419130Y141629D01*
G01X1440970Y106796D02*
X1418047Y141178D01*
G01X1419130Y141629D02*
X1414142Y166145D01*
G01X1418047Y141178D02*
X1413015Y165916D01*
G01X1411673Y165454D02*
X1416722Y140493D01*
G01X1410590Y165006D02*
X1415639Y140043D01*
G01X1416722Y140493D02*
X1439017Y107048D01*
G01X1415639Y140043D02*
X1437938Y106593D01*
G01X1409274Y164398D02*
X1414272Y139564D01*
G01X1408191Y163950D02*
X1413189Y139115D01*
G01X1414272Y139564D02*
X1436206Y106665D01*
G01X1413189Y139115D02*
X1435127Y106210D01*
G01X1429930Y173170D02*
X1434290Y151373D01*
G01X1431014Y173617D02*
X1435374Y151821D01*
G01X1434290Y151373D02*
X1444709Y135710D01*
G01X1435374Y151821D02*
X1445539Y136539D01*
G01X1444709Y135710D02*
X1455107Y128776D01*
G01X1445539Y136539D02*
X1455937Y129605D01*
G01X1455107Y128776D02*
X1455955Y127501D01*
G01X1455956D02*
X1456316Y126960D01*
G01X1455937Y129605D02*
X1457093Y127869D01*
G01X1455956Y127501D02*
X1456316Y126960D01*
G01X1457094Y127868D02*
X1457152Y127782D01*
G01X1456316Y126960D02*
X1463667Y121893D01*
G01X1457152Y127782D02*
X1464700Y122579D01*
G01X1463667Y121893D02*
X1467186Y104908D01*
G01X1464700Y122579D02*
X1468205Y105661D01*
G01X1470333Y155731D02*
X1449106D01*
G01D02*
X1442217Y162620D01*
G01X1470333Y155731D02*
X1449106D01*
G01D02*
X1442217Y162620D01*
G01X1466485Y196123D02*
X1459408Y203200D01*
G01X1466962Y197273D02*
X1459885Y204350D01*
G01X1459408Y203200D02*
X1453473D01*
G01X1459885Y204350D02*
X1453950D01*
G01X1453473Y203200D02*
X1446423Y210250D01*
G01X1453950Y204350D02*
X1446900Y211400D01*
G01X1446423Y210250D02*
X1433940D01*
G01X1446900Y211400D02*
X1434202D01*
G01X1433900Y210290D02*
X1423173Y213211D01*
G01X1434202Y211400D02*
X1423655Y214272D01*
G01X1423173Y213211D02*
X1416636Y217558D01*
G01X1423655Y214272D02*
X1417465Y218388D01*
G01X1416636Y217558D02*
X1403933Y236619D01*
G01X1403788Y219160D02*
X1412716Y216164D01*
G01X1403976Y220310D02*
X1413244Y217200D01*
G01X1412716Y216164D02*
X1421301Y210050D01*
G01X1413244Y217200D02*
X1421803Y211106D01*
G01X1421301Y210050D02*
X1443306Y203993D01*
G01X1421803Y211106D02*
X1443904Y205022D01*
G01X1443306Y203993D02*
X1448423Y198878D01*
G01X1443904Y205022D02*
X1448900Y200028D01*
G01X1448423Y198878D02*
X1460137D01*
G01X1448900Y200028D02*
X1460614D01*
G01X1460137Y198878D02*
X1465392Y193623D01*
G01X1460614Y200028D02*
X1465869Y194773D01*
G01X1410453Y211243D02*
X1421586Y203321D01*
G01X1410981Y212279D02*
X1422097Y204369D01*
G01X1421586Y203321D02*
X1434601Y199440D01*
G01X1422097Y204369D02*
X1435209Y200460D01*
G01X1434601Y199440D02*
X1444215Y189826D01*
G01X1435209Y200460D02*
X1444692Y190976D01*
G01X1444215Y189826D02*
X1451995D01*
G01X1444692Y190976D02*
X1452472D01*
G01X1451995Y189826D02*
X1458115Y183706D01*
G01X1452472Y190976D02*
X1458592Y184856D01*
G01X1458115Y183706D02*
X1471637D01*
G01X1458592Y184856D02*
X1471160D01*
G01X1466962Y197273D02*
X1459885Y204350D01*
G01X1466485Y196123D02*
X1459408Y203200D01*
G01X1459885Y204350D02*
X1453950D01*
G01X1459408Y203200D02*
X1453473D01*
G01X1453950Y204350D02*
X1446900Y211400D01*
G01X1453473Y203200D02*
X1446423Y210250D01*
G01X1446900Y211400D02*
X1434202D01*
G01X1446423Y210250D02*
X1433940D01*
G01X1434202Y211400D02*
X1423655Y214272D01*
G01X1433900Y210290D02*
X1423173Y213211D01*
G01X1423655Y214272D02*
X1417465Y218388D01*
G01X1423173Y213211D02*
X1416636Y217558D01*
G01D02*
X1403933Y236619D01*
G01X1403976Y220310D02*
X1413244Y217200D01*
G01X1403788Y219160D02*
X1412716Y216164D01*
G01X1413244Y217200D02*
X1421803Y211106D01*
G01X1412716Y216164D02*
X1421301Y210050D01*
G01X1421803Y211106D02*
X1443904Y205022D01*
G01X1421301Y210050D02*
X1443306Y203993D01*
G01X1443904Y205022D02*
X1448900Y200028D01*
G01X1443306Y203993D02*
X1448423Y198878D01*
G01X1448900Y200028D02*
X1460614D01*
G01X1448423Y198878D02*
X1460137D01*
G01X1460614Y200028D02*
X1465869Y194773D01*
G01X1460137Y198878D02*
X1465392Y193623D01*
G01X1410981Y212279D02*
X1422097Y204369D01*
G01X1410453Y211243D02*
X1421586Y203321D01*
G01X1422097Y204369D02*
X1435209Y200460D01*
G01X1421586Y203321D02*
X1434601Y199440D01*
G01X1435209Y200460D02*
X1444692Y190976D01*
G01X1434601Y199440D02*
X1444215Y189826D01*
G01X1444692Y190976D02*
X1452472D01*
G01X1444215Y189826D02*
X1451995D01*
G01X1452472Y190976D02*
X1458592Y184856D01*
G01X1451995Y189826D02*
X1458115Y183706D01*
G01X1458592Y184856D02*
X1471160D01*
G01X1458115Y183706D02*
X1471637D01*
G01X1412982Y186936D02*
X1421307Y181428D01*
G01X1413461Y187999D02*
X1422137Y182258D01*
G01X1421307Y181428D02*
X1427633Y171868D01*
G01X1422137Y182258D02*
X1428717Y172315D01*
G01X1411654Y184667D02*
X1419565Y179432D01*
G01X1412133Y185730D02*
X1420395Y180262D01*
G01X1419565Y179432D02*
X1424979Y171250D01*
G01X1420395Y180262D02*
X1426062Y171699D01*
G01X1410233Y182444D02*
X1417670Y177520D01*
G01X1410712Y183507D02*
X1418500Y178350D01*
G01X1417670Y177520D02*
X1422643Y170006D01*
G01X1418500Y178350D02*
X1423726Y170454D01*
G01X1409300Y181245D02*
X1409749Y181125D01*
G01X1409271Y180062D02*
X1409300Y180043D01*
G01D02*
X1415649Y175841D01*
G01X1409749Y181125D02*
X1416479Y176671D01*
G01X1415649Y175841D02*
X1420227Y168925D01*
G01X1416479Y176671D02*
X1421310Y169374D01*
G01X1407748Y177877D02*
X1414034Y173718D01*
G01X1408227Y178940D02*
X1414864Y174548D01*
G01X1414034Y173718D02*
X1417872Y167917D01*
G01X1414864Y174548D02*
X1418955Y168365D01*
G01X1413014Y172675D02*
X1416515Y167383D01*
G01X1415432Y166935D02*
X1412184Y171845D01*
G01X1407033Y176633D02*
X1413014Y172675D01*
G01X1412184Y171845D02*
X1406554Y175570D01*
G01X1414143Y166145D02*
X1414098Y166365D01*
G01X1413015Y165916D02*
X1410411Y169850D01*
G01X1414098Y166365D02*
X1411241Y170680D01*
G01X1410411Y169850D02*
X1405216Y173289D01*
G01X1411241Y170680D02*
X1405695Y174352D01*
G01X1404088Y170923D02*
X1408688Y167879D01*
G01X1404567Y171986D02*
X1409518Y168709D01*
G01X1408688Y167879D02*
X1410590Y165006D01*
G01X1409518Y168709D02*
X1411673Y165454D01*
G01X1403803Y169447D02*
X1407590Y166939D01*
G01X1406760Y166109D02*
X1408191Y163950D01*
G01X1407590Y166939D02*
X1409274Y164399D01*
G01X1414511Y190354D02*
X1424163Y183968D01*
G01X1414030Y189293D02*
X1423333Y183138D01*
G01X1424163Y183968D02*
X1431014Y173617D01*
G01X1423333Y183138D02*
X1429930Y173170D01*
G01X1413461Y187999D02*
X1422137Y182258D01*
G01X1412982Y186936D02*
X1421307Y181428D01*
G01X1422137Y182258D02*
X1428717Y172315D01*
G01X1421307Y181428D02*
X1427633Y171868D01*
G01X1412133Y185730D02*
X1420395Y180262D01*
G01X1411654Y184667D02*
X1419565Y179432D01*
G01X1420395Y180262D02*
X1426062Y171699D01*
G01X1419565Y179432D02*
X1424979Y171250D01*
G01X1410712Y183507D02*
X1418500Y178350D01*
G01X1410233Y182444D02*
X1417670Y177520D01*
G01X1418500Y178350D02*
X1423726Y170454D01*
G01X1417670Y177520D02*
X1422643Y170006D01*
G01X1409300Y181245D02*
X1409749Y181125D01*
G01D02*
X1416479Y176671D01*
G01X1409271Y180062D02*
X1409300Y180043D01*
G01X1409749Y181125D02*
X1416479Y176671D01*
G01X1409300Y180043D02*
X1415649Y175841D01*
G01X1416479Y176671D02*
X1421310Y169374D01*
G01X1415649Y175841D02*
X1420227Y168925D01*
G01X1408227Y178940D02*
X1414864Y174548D01*
G01X1407748Y177877D02*
X1414034Y173718D01*
G01X1414864Y174548D02*
X1418955Y168365D01*
G01X1414034Y173718D02*
X1417872Y167917D01*
G01X1412184Y171845D02*
X1406554Y175570D01*
G01X1407033Y176633D02*
X1413014Y172675D01*
G01X1415432Y166935D02*
X1412184Y171845D01*
G01X1413014Y172675D02*
X1416515Y167383D01*
G01X1414143Y166145D02*
X1414098Y166365D01*
G01D02*
X1411241Y170680D01*
G01X1413015Y165916D02*
X1410411Y169850D01*
G01X1411241Y170680D02*
X1405695Y174352D01*
G01X1410411Y169850D02*
X1405216Y173289D01*
G01X1404567Y171986D02*
X1409518Y168709D01*
G01X1404088Y170923D02*
X1408688Y167879D01*
G01X1409518Y168709D02*
X1411673Y165454D01*
G01X1408688Y167879D02*
X1410590Y165006D01*
G01X1403803Y169447D02*
X1407590Y166939D01*
G01D02*
X1409274Y164399D01*
G01X1406760Y166109D02*
X1408191Y163950D01*
G01X1414030Y189293D02*
X1423333Y183138D01*
G01X1414511Y190354D02*
X1424163Y183968D01*
G01X1423333Y183138D02*
X1429930Y173170D01*
G01X1424163Y183968D02*
X1431014Y173617D01*
G01X1411177Y214031D02*
X1422567Y205925D01*
G01X1411705Y215067D02*
X1423073Y206977D01*
G01X1422567Y205925D02*
X1436261Y202016D01*
G01X1423073Y206977D02*
X1436864Y203041D01*
G01X1436261Y202016D02*
X1445953Y192326D01*
G01X1436864Y203041D02*
X1446430Y193476D01*
G01X1445953Y192326D02*
X1452976D01*
G01X1446430Y193476D02*
X1452499D01*
G01X1452976Y192326D02*
X1455061Y194411D01*
G01X1452499Y193476D02*
X1454584Y195561D01*
G01X1455061Y194411D02*
X1461067D01*
G01X1454584Y195561D02*
X1461544D01*
G01X1461067Y194411D02*
X1464355Y191123D01*
G01X1461544Y195561D02*
X1464832Y192273D01*
G01X1464355Y191123D02*
X1473872D01*
G01X1464832Y192273D02*
X1474349D01*
G01X1469856Y156881D02*
X1449583D01*
G01D02*
X1443367Y163097D01*
G01D02*
Y169632D01*
G01X1442217Y162620D02*
Y169155D01*
G01X1443367Y169632D02*
X1426915Y186084D01*
G01X1442217Y169155D02*
X1426185Y185187D01*
G01X1426915Y186084D02*
X1416210Y193115D01*
G01X1426185Y185187D02*
X1415730Y192054D01*
G01X1469296Y158231D02*
X1450347D01*
G01X1468819Y159381D02*
X1450824D01*
G01X1450347Y158231D02*
X1444981Y163597D01*
G01X1450824Y159381D02*
X1446131Y164074D01*
G01X1444981Y163597D02*
Y173555D01*
G01X1446131Y164074D02*
Y174032D01*
G01X1444981Y173555D02*
X1437188Y181348D01*
G01X1446131Y174032D02*
X1437917Y182246D01*
G01X1437188Y181348D02*
X1417569Y194161D01*
G01X1437917Y182246D02*
X1418051Y195220D01*
G01X1429331Y194518D02*
X1433724D01*
G01X1429165Y193368D02*
X1433247D01*
G01X1433724Y194518D02*
X1442266Y185976D01*
G01X1433247Y193368D02*
X1441789Y184826D01*
G01X1442266Y185976D02*
X1449014D01*
G01X1441789Y184826D02*
X1448537D01*
G01X1449014Y185976D02*
X1457589Y177401D01*
G01X1448537Y184826D02*
X1457112Y176251D01*
G01X1457589Y177401D02*
X1482226D01*
G01X1457112Y176251D02*
X1482703D01*
G01X1458766Y178900D02*
X1480216D01*
G01X1479739Y180050D02*
X1459243D01*
G01X1450340Y187326D02*
X1458766Y178900D01*
G01X1459243Y180050D02*
X1450817Y188476D01*
G01X1442836Y187326D02*
X1450340D01*
G01X1450817Y188476D02*
X1443313D01*
G01X1434137Y196025D02*
X1442836Y187326D01*
G01X1443313Y188476D02*
X1434741Y197049D01*
G01X1422986Y199234D02*
X1434137Y196025D01*
G01X1434741Y197049D02*
X1423476Y200291D01*
G01X1408528Y208874D02*
X1422986Y199234D01*
G01X1423476Y200291D02*
X1409039Y209916D01*
G01D02*
X1403733Y211696D01*
G01X1411705Y215067D02*
X1423073Y206977D01*
G01X1411177Y214031D02*
X1422567Y205925D01*
G01X1423073Y206977D02*
X1436864Y203041D01*
G01X1422567Y205925D02*
X1436261Y202016D01*
G01X1436864Y203041D02*
X1446430Y193476D01*
G01X1436261Y202016D02*
X1445953Y192326D01*
G01X1446430Y193476D02*
X1452499D01*
G01X1445953Y192326D02*
X1452976D01*
G01X1452499Y193476D02*
X1454584Y195561D01*
G01X1452976Y192326D02*
X1455061Y194411D01*
G01X1454584Y195561D02*
X1461544D01*
G01X1455061Y194411D02*
X1461067D01*
G01X1461544Y195561D02*
X1464832Y192273D01*
G01X1461067Y194411D02*
X1464355Y191123D01*
G01X1464832Y192273D02*
X1474349D01*
G01X1464355Y191123D02*
X1473872D01*
G01X1469856Y156881D02*
X1449583D01*
G01D02*
X1443367Y163097D01*
G01X1442217Y162620D02*
Y169155D01*
G01X1443367Y163097D02*
Y169632D01*
G01X1442217Y169155D02*
X1426185Y185187D01*
G01X1443367Y169632D02*
X1426915Y186084D01*
G01X1426185Y185187D02*
X1415730Y192054D01*
G01X1426915Y186084D02*
X1416210Y193115D01*
G01X1468819Y159381D02*
X1450824D01*
G01X1469296Y158231D02*
X1450347D01*
G01X1450824Y159381D02*
X1446131Y164074D01*
G01X1450347Y158231D02*
X1444981Y163597D01*
G01X1446131Y164074D02*
Y174032D01*
G01X1444981Y163597D02*
Y173555D01*
G01X1446131Y174032D02*
X1437917Y182246D01*
G01X1444981Y173555D02*
X1437188Y181348D01*
G01X1437917Y182246D02*
X1418051Y195220D01*
G01X1437188Y181348D02*
X1417569Y194161D01*
G01X1429165Y193368D02*
X1433247D01*
G01X1429331Y194518D02*
X1433724D01*
G01X1433247Y193368D02*
X1441789Y184826D01*
G01X1433724Y194518D02*
X1442266Y185976D01*
G01X1441789Y184826D02*
X1448537D01*
G01X1442266Y185976D02*
X1449014D01*
G01X1448537Y184826D02*
X1457112Y176251D01*
G01X1449014Y185976D02*
X1457589Y177401D01*
G01X1457112Y176251D02*
X1482703D01*
G01X1457589Y177401D02*
X1482226D01*
G01X1409039Y209916D02*
X1403733Y211696D01*
G01X1423476Y200291D02*
X1409039Y209916D01*
G01X1408528Y208874D02*
X1422986Y199234D01*
G01X1434741Y197049D02*
X1423476Y200291D01*
G01X1422986Y199234D02*
X1434137Y196025D01*
G01X1443313Y188476D02*
X1434741Y197049D01*
G01X1434137Y196025D02*
X1442836Y187326D01*
G01X1450817Y188476D02*
X1443313D01*
G01X1442836Y187326D02*
X1450340D01*
G01X1459243Y180050D02*
X1450817Y188476D01*
G01X1450340Y187326D02*
X1458766Y178900D01*
G01X1479739Y180050D02*
X1459243D01*
G01X1458766Y178900D02*
X1480216D01*
G01X1467400Y217800D02*
X1458332D01*
G01D02*
X1451500Y224632D01*
G01X1466058Y212542D02*
X1463500Y215100D01*
G01X1466535Y213692D02*
X1463977Y216250D01*
G01X1463500Y215100D02*
X1457016D01*
G01X1463977Y216250D02*
X1457493D01*
G01X1457016Y215100D02*
X1450846Y221270D01*
G01X1457493Y216250D02*
X1451323Y222420D01*
G01X1457221Y211300D02*
X1449821Y218700D01*
G01X1450298Y219850D02*
X1457698Y212450D01*
G01X1462767Y211300D02*
X1457221D01*
G01X1457698Y212450D02*
X1463244D01*
G01X1469817Y204250D02*
X1462767Y211300D01*
G01X1463244Y212450D02*
X1470294Y205400D01*
G01X1468780Y201750D02*
X1461730Y208800D01*
G01X1469257Y202900D02*
X1462207Y209950D01*
G01X1461730Y208800D02*
X1455795D01*
G01X1462207Y209950D02*
X1456272D01*
G01X1455795Y208800D02*
X1448445Y216150D01*
G01X1456272Y209950D02*
X1448922Y217300D01*
G01X1448445Y216150D02*
X1436465D01*
G01X1448922Y217300D02*
X1436942D01*
G01X1436465Y216150D02*
X1418170Y234445D01*
G01X1436942Y217300D02*
X1418902Y235341D01*
G01X1467743Y199250D02*
X1460693Y206300D01*
G01X1468220Y200400D02*
X1461170Y207450D01*
G01X1460693Y206300D02*
X1454758D01*
G01X1461170Y207450D02*
X1455235D01*
G01X1454758Y206300D02*
X1447678Y213380D01*
G01X1455235Y207450D02*
X1448155Y214530D01*
G01X1447678Y213380D02*
X1434549D01*
G01X1448155Y214530D02*
X1435026D01*
G01X1434549Y213380D02*
X1431608Y216321D01*
G01X1435026Y214530D02*
X1414035Y235522D01*
G01X1467400Y217800D02*
X1458332D01*
G01D02*
X1451500Y224632D01*
G01X1466535Y213692D02*
X1463977Y216250D01*
G01X1466058Y212542D02*
X1463500Y215100D01*
G01X1463977Y216250D02*
X1457493D01*
G01X1463500Y215100D02*
X1457016D01*
G01X1457493Y216250D02*
X1451323Y222420D01*
G01X1457016Y215100D02*
X1450846Y221270D01*
G01X1463244Y212450D02*
X1470294Y205400D01*
G01X1469817Y204250D02*
X1462767Y211300D01*
G01X1457698Y212450D02*
X1463244D01*
G01X1462767Y211300D02*
X1457221D01*
G01X1450298Y219850D02*
X1457698Y212450D01*
G01X1457221Y211300D02*
X1449821Y218700D01*
G01X1469257Y202900D02*
X1462207Y209950D01*
G01X1468780Y201750D02*
X1461730Y208800D01*
G01X1462207Y209950D02*
X1456272D01*
G01X1461730Y208800D02*
X1455795D01*
G01X1456272Y209950D02*
X1448922Y217300D01*
G01X1455795Y208800D02*
X1448445Y216150D01*
G01X1448922Y217300D02*
X1436942D01*
G01X1448445Y216150D02*
X1436465D01*
G01X1436942Y217300D02*
X1418902Y235341D01*
G01X1436465Y216150D02*
X1418170Y234445D01*
G01X1468220Y200400D02*
X1461170Y207450D01*
G01X1467743Y199250D02*
X1460693Y206300D01*
G01X1461170Y207450D02*
X1455235D01*
G01X1460693Y206300D02*
X1454758D01*
G01X1455235Y207450D02*
X1448155Y214530D01*
G01X1454758Y206300D02*
X1447678Y213380D01*
G01X1448155Y214530D02*
X1435026D01*
G01X1447678Y213380D02*
X1434549D01*
G01X1435026Y214530D02*
X1414035Y235522D01*
G01X1434549Y213380D02*
X1431608Y216321D01*
G01X1435026Y214530D02*
X1414035Y235522D01*
G01X1417465Y218388D02*
X1404763Y237449D01*
G01X1417465Y218388D02*
X1404763Y237449D01*
G01X1478417Y226100D02*
X1457474D01*
G01X1477940Y227250D02*
X1457951D01*
G01X1457474Y226100D02*
X1453927Y229647D01*
G01X1457951Y227250D02*
X1454404Y230797D01*
G01X1453927Y229647D02*
X1441126D01*
G01X1454404Y230797D02*
X1441603D01*
G01X1441126Y229647D02*
X1411804Y258969D01*
G01X1441603Y230797D02*
X1412281Y260119D01*
G01X1411804Y258969D02*
X1407785D01*
G01X1412281Y260119D02*
X1408261D01*
G01X1407785Y258969D02*
X1405214Y261532D01*
G01X1408261Y260119D02*
X1405780Y262592D01*
G01X1473900Y223600D02*
X1456437D01*
G01X1474377Y224750D02*
X1456914D01*
G01X1456437Y223600D02*
X1452905Y227132D01*
G01X1456914Y224750D02*
X1453382Y228282D01*
G01X1452905Y227132D02*
X1439941D01*
G01X1453382Y228282D02*
X1440418D01*
G01X1439941Y227132D02*
X1410657Y256416D01*
G01X1440418Y228282D02*
X1411134Y257566D01*
G01X1410657Y256416D02*
X1406710D01*
G01X1411134Y257566D02*
X1407186D01*
G01X1406710Y256416D02*
X1404104Y259013D01*
G01X1407186Y257566D02*
X1404670Y260073D01*
G01X1466923Y218950D02*
X1458809D01*
G01D02*
X1451977Y225782D01*
G01X1451500Y224632D02*
X1438742D01*
G01X1451977Y225782D02*
X1439219D01*
G01X1438742Y224632D02*
X1409533Y253841D01*
G01X1439219Y225782D02*
X1410009Y254992D01*
G01X1409533Y253841D02*
X1405745D01*
G01X1410009Y254992D02*
X1409057D01*
G01X1409533Y253841D02*
X1405745D01*
G01X1409056Y254991D02*
X1406219D01*
G01X1450846Y221270D02*
X1438503D01*
G01X1451323Y222420D02*
X1438980D01*
G01X1438503Y221270D02*
X1408556Y251217D01*
G01X1438980Y222420D02*
X1409033Y252367D01*
G01X1408556Y251217D02*
X1404668D01*
G01X1409033Y252367D02*
X1405142D01*
G01X1437474Y218700D02*
X1408623Y247551D01*
G01X1409190Y248611D02*
X1437951Y219850D01*
G01X1449821Y218700D02*
X1437474D01*
G01X1437951Y219850D02*
X1450298D01*
G01X1429734Y218195D02*
X1413312Y234617D01*
G01X1407030Y264954D02*
X1409333Y262651D01*
G01X1406463Y263894D02*
X1408856Y261501D01*
G01X1409333Y262651D02*
X1413286D01*
G01X1408856Y261501D02*
X1412809D01*
G01X1413286Y262651D02*
X1442590Y233347D01*
G01X1412809Y261501D02*
X1442113Y232197D01*
G01X1442590Y233347D02*
X1455580D01*
G01X1442113Y232197D02*
X1455103D01*
G01X1455580Y233347D02*
X1459177Y229750D01*
G01X1455103Y232197D02*
X1458700Y228600D01*
G01X1459177Y229750D02*
X1466623D01*
G01X1458700Y228600D02*
X1467100D01*
G01X1477940Y227250D02*
X1457951D01*
G01X1478417Y226100D02*
X1457474D01*
G01X1457951Y227250D02*
X1454404Y230797D01*
G01X1457474Y226100D02*
X1453927Y229647D01*
G01X1454404Y230797D02*
X1441603D01*
G01X1453927Y229647D02*
X1441126D01*
G01X1441603Y230797D02*
X1412281Y260119D01*
G01X1441126Y229647D02*
X1411804Y258969D01*
G01X1412281Y260119D02*
X1408261D01*
G01X1411804Y258969D02*
X1407785D01*
G01X1408261Y260119D02*
X1405780Y262592D01*
G01X1407785Y258969D02*
X1405214Y261532D01*
G01X1474377Y224750D02*
X1456914D01*
G01X1473900Y223600D02*
X1456437D01*
G01X1456914Y224750D02*
X1453382Y228282D01*
G01X1456437Y223600D02*
X1452905Y227132D01*
G01X1453382Y228282D02*
X1440418D01*
G01X1452905Y227132D02*
X1439941D01*
G01X1440418Y228282D02*
X1411134Y257566D01*
G01X1439941Y227132D02*
X1410657Y256416D01*
G01X1411134Y257566D02*
X1407186D01*
G01X1410657Y256416D02*
X1406710D01*
G01X1407186Y257566D02*
X1404670Y260073D01*
G01X1406710Y256416D02*
X1404104Y259013D01*
G01X1466923Y218950D02*
X1458809D01*
G01D02*
X1451977Y225782D01*
G01D02*
X1439219D01*
G01X1451500Y224632D02*
X1438742D01*
G01X1439219Y225782D02*
X1410009Y254992D01*
G01X1438742Y224632D02*
X1409533Y253841D01*
G01X1410009Y254992D02*
X1409057D01*
G01X1409056Y254991D02*
X1406219D01*
G01X1409533Y253841D02*
X1405745D01*
G01X1451323Y222420D02*
X1438980D01*
G01X1450846Y221270D02*
X1438503D01*
G01X1438980Y222420D02*
X1409033Y252367D01*
G01X1438503Y221270D02*
X1408556Y251217D01*
G01X1409033Y252367D02*
X1405142D01*
G01X1408556Y251217D02*
X1404668D01*
G01X1437951Y219850D02*
X1450298D01*
G01X1449821Y218700D02*
X1437474D01*
G01X1409190Y248611D02*
X1437951Y219850D01*
G01X1437474Y218700D02*
X1408623Y247551D01*
G01X1429734Y218195D02*
X1413312Y234617D01*
G01X1406463Y263894D02*
X1408856Y261501D01*
G01X1407030Y264954D02*
X1409333Y262651D01*
G01X1408856Y261501D02*
X1412809D01*
G01X1409333Y262651D02*
X1413286D01*
G01X1412809Y261501D02*
X1442113Y232197D01*
G01X1413286Y262651D02*
X1442590Y233347D01*
G01X1442113Y232197D02*
X1455103D01*
G01X1442590Y233347D02*
X1455580D01*
G01X1455103Y232197D02*
X1458700Y228600D01*
G01X1455580Y233347D02*
X1459177Y229750D01*
G01X1458700Y228600D02*
X1467100D01*
G01X1459177Y229750D02*
X1466623D01*
G01X1440744Y342656D02*
X1435437Y315841D01*
G01X1441917Y342656D02*
X1436515Y315362D01*
G01X1435437Y315841D02*
X1433786Y313627D01*
G01X1436515Y315362D02*
X1434864Y313148D01*
G01X1433784Y313620D02*
X1432084Y305031D01*
G01X1434863Y313146D02*
X1433257Y305034D01*
G01X1432085Y305031D02*
X1432887Y300982D01*
G01X1433257Y305034D02*
X1434082Y300869D01*
G01X1432887Y300982D02*
X1430145Y294205D01*
G01X1434082Y300869D02*
X1431091Y293475D01*
G01X1430145Y294205D02*
X1424759Y290190D01*
G01X1431091Y293475D02*
X1425238Y289112D01*
G01X1424759Y290190D02*
X1418496Y288952D01*
G01X1425235Y289111D02*
X1418496Y287779D01*
G01Y288952D02*
X1416495Y289348D01*
G01X1418496Y287779D02*
X1416495Y288175D01*
G01Y289348D02*
X1414530Y288959D01*
G01X1416495Y288175D02*
X1414530Y287786D01*
G01Y288959D02*
X1412611Y289339D01*
G01X1414530Y287786D02*
X1412611Y288166D01*
G01Y289339D02*
X1410599Y288941D01*
G01X1412611Y288166D02*
X1410599Y287768D01*
G01Y288941D02*
X1408641Y289329D01*
G01X1410599Y287768D02*
X1408641Y288156D01*
G01Y289329D02*
X1406725Y288950D01*
G01X1408641Y288156D02*
X1406725Y287777D01*
G01Y288950D02*
X1404762Y289340D01*
G01X1406725Y287777D02*
X1404762Y288167D01*
G01X1406725Y288950D02*
X1404762Y289340D01*
G01Y288167D02*
X1404761D01*
G01X1441917Y342656D02*
X1436515Y315362D01*
G01X1440744Y342656D02*
X1435437Y315841D01*
G01X1436515Y315362D02*
X1434864Y313148D01*
G01X1435437Y315841D02*
X1433786Y313627D01*
G01X1434863Y313146D02*
X1433257Y305034D01*
G01X1433784Y313620D02*
X1432084Y305031D01*
G01X1433257Y305034D02*
X1434082Y300869D01*
G01X1432085Y305031D02*
X1432887Y300982D01*
G01X1434082Y300869D02*
X1431091Y293475D01*
G01X1432887Y300982D02*
X1430145Y294205D01*
G01X1431091Y293475D02*
X1425238Y289112D01*
G01X1430145Y294205D02*
X1424759Y290190D01*
G01X1425235Y289111D02*
X1418496Y287779D01*
G01X1424759Y290190D02*
X1418496Y288952D01*
G01Y287779D02*
X1416495Y288175D01*
G01X1418496Y288952D02*
X1416495Y289348D01*
G01Y288175D02*
X1414530Y287786D01*
G01X1416495Y289348D02*
X1414530Y288959D01*
G01Y287786D02*
X1412611Y288166D01*
G01X1414530Y288959D02*
X1412611Y289339D01*
G01Y288166D02*
X1410599Y287768D01*
G01X1412611Y289339D02*
X1410599Y288941D01*
G01Y287768D02*
X1408641Y288156D01*
G01X1410599Y288941D02*
X1408641Y289329D01*
G01Y288156D02*
X1406725Y287777D01*
G01X1408641Y289329D02*
X1406725Y288950D01*
G01Y287777D02*
X1404762Y288167D01*
G01D02*
X1404761D01*
G01X1406725Y288950D02*
X1404762Y289340D01*
G01Y288167D02*
X1404761D01*
G01X1438122Y342537D02*
X1433049Y316906D01*
G01X1439295Y342537D02*
X1434127Y316427D01*
G01X1433048Y316906D02*
X1431397Y314690D01*
G01X1434127Y316428D02*
X1432475Y314211D01*
G01X1431397Y314690D02*
X1429485Y305033D01*
G01X1432475Y314211D02*
X1430658Y305031D01*
G01X1429485Y305033D02*
X1430237Y301233D01*
G01X1430658Y305031D02*
X1431432Y301120D01*
G01X1430237Y301233D02*
X1428049Y295823D01*
G01X1431432Y301120D02*
X1428995Y295093D01*
G01X1428049Y295823D02*
X1423702Y292581D01*
G01X1428995Y295093D02*
X1424179Y291501D01*
G01X1423702Y292581D02*
X1418496Y291552D01*
G01X1424178Y291502D02*
X1418496Y290379D01*
G01Y291552D02*
X1416495Y291948D01*
G01X1418496Y290379D02*
X1416495Y290775D01*
G01Y291948D02*
X1414531Y291559D01*
G01X1416495Y290775D02*
X1414530Y290386D01*
G01X1414531Y291559D02*
X1412611Y291939D01*
G01X1414530Y290386D02*
X1412611Y290766D01*
G01Y291939D02*
X1410599Y291541D01*
G01X1412611Y290766D02*
X1410599Y290368D01*
G01Y291541D02*
X1408641Y291929D01*
G01X1410599Y290368D02*
X1408641Y290756D01*
G01Y291929D02*
X1406726Y291550D01*
G01X1408641Y290756D02*
X1406726Y290377D01*
G01Y291550D02*
X1404764Y291939D01*
G01X1406726Y290377D02*
X1404764Y290766D01*
G01X1433720Y345563D02*
X1434921Y339497D01*
G01X1434893Y345563D02*
X1436094Y339497D01*
G01X1434921D02*
X1430659Y317964D01*
G01X1436094Y339497D02*
X1431737Y317486D01*
G01X1430659Y317964D02*
X1429007Y315748D01*
G01X1431737Y317486D02*
X1430084Y315267D01*
G01X1429006Y315745D02*
X1426885Y305031D01*
G01X1430084Y315267D02*
X1428058Y305031D01*
G01X1426885D02*
X1427588Y301484D01*
G01X1428058Y305031D02*
X1428783Y301371D01*
G01X1427588Y301484D02*
X1425952Y297441D01*
G01X1428783Y301371D02*
X1426898Y296711D01*
G01X1425952Y297441D02*
X1422636Y294969D01*
G01X1426898Y296711D02*
X1423115Y293891D01*
G01X1422636Y294969D02*
X1418498Y294151D01*
G01X1423115Y293891D02*
X1418498Y292978D01*
G01Y294151D02*
X1416535Y294539D01*
G01X1418498Y292978D02*
X1416535Y293366D01*
G01Y294539D02*
X1414573Y294151D01*
G01X1416535Y293366D02*
X1414573Y292978D01*
G01Y294151D02*
X1412611Y294539D01*
G01X1414573Y292978D02*
X1412611Y293366D01*
G01Y294539D02*
X1410599Y294141D01*
G01X1412611Y293366D02*
X1410599Y292968D01*
G01Y294141D02*
X1408641Y294529D01*
G01X1410599Y292968D02*
X1408641Y293356D01*
G01Y294529D02*
X1406726Y294150D01*
G01X1408641Y293356D02*
X1406726Y292977D01*
G01Y294150D02*
X1404764Y294538D01*
G01X1406726Y292977D02*
X1404764Y293365D01*
G01X1430520Y348598D02*
X1432321Y339497D01*
G01X1431693Y348598D02*
X1433494Y339497D01*
G01X1432321D02*
X1428271Y319027D01*
G01X1433494Y339497D02*
X1429349Y318549D01*
G01X1428270Y319027D02*
X1426618Y316810D01*
G01X1429344Y318542D02*
X1427696Y316331D01*
G01X1426618Y316810D02*
X1424286Y305031D01*
G01X1427696Y316331D02*
X1425459Y305031D01*
G01X1424286D02*
X1424939Y301735D01*
G01X1425459Y305031D02*
X1426134Y301622D01*
G01X1424939Y301735D02*
X1423856Y299059D01*
G01X1426134Y301622D02*
X1424802Y298329D01*
G01X1423856Y299059D02*
X1421577Y297360D01*
G01X1424802Y298329D02*
X1422056Y296282D01*
G01X1421577Y297360D02*
X1418496Y296751D01*
G01X1422056Y296282D02*
X1418496Y295578D01*
G01Y296751D02*
X1416535Y297138D01*
G01X1418496Y295578D02*
X1416535Y295965D01*
G01Y297138D02*
X1414573Y296750D01*
G01X1416535Y295965D02*
X1414573Y295577D01*
G01Y296750D02*
X1412611Y297138D01*
G01X1414573Y295577D02*
X1412611Y295965D01*
G01Y297138D02*
X1410649Y296750D01*
G01X1412611Y295965D02*
X1410649Y295577D01*
G01Y296750D02*
X1408688Y297138D01*
G01X1410649Y295577D02*
X1408688Y295965D01*
G01Y297138D02*
X1406726Y296750D01*
G01X1408688Y295965D02*
X1406726Y295577D01*
G01Y296750D02*
X1404764Y297138D01*
G01X1406726Y295577D02*
X1404764Y295965D01*
G01Y299738D02*
X1406726Y299350D01*
G01X1404764Y298565D02*
X1406726Y298177D01*
G01Y299350D02*
X1408688Y299738D01*
G01X1406726Y298177D02*
X1408688Y298565D01*
G01Y299738D02*
X1410649Y299350D01*
G01X1408688Y298565D02*
X1410649Y298177D01*
G01Y299350D02*
X1412611Y299738D01*
G01X1410649Y298177D02*
X1412611Y298565D01*
G01Y299738D02*
X1414573Y299350D01*
G01X1412611Y298565D02*
X1414573Y298177D01*
G01Y299350D02*
X1416535Y299738D01*
G01X1414573Y298177D02*
X1416535Y298565D01*
G01Y299738D02*
X1418496Y299350D01*
G01X1416535Y298565D02*
X1418496Y298177D01*
G01Y299350D02*
X1420516Y299750D01*
G01X1418496Y298177D02*
X1420995Y298672D01*
G01X1420516Y299750D02*
X1421760Y300677D01*
G01X1420995Y298672D02*
X1422706Y299947D01*
G01X1421760Y300677D02*
X1422290Y301986D01*
G01X1422706Y299947D02*
X1423485Y301873D01*
G01X1422290Y301986D02*
X1421687Y305031D01*
G01X1423485Y301873D02*
X1422860Y305031D01*
G01X1421687D02*
X1424229Y317871D01*
G01X1422860Y305031D02*
X1425307Y317392D01*
G01X1424229Y317870D02*
X1425879Y320085D01*
G01X1425307Y317392D02*
X1426958Y319608D01*
G01X1425879Y320085D02*
X1429722Y339497D01*
G01X1426958Y319608D02*
X1430895Y339497D01*
G01X1429722D02*
X1427525Y350599D01*
G01X1430895Y339497D02*
X1428698Y350599D01*
G01X1415294Y312600D02*
X1416935Y314241D01*
G01X1418809Y316115D02*
X1419764Y317070D01*
G01X1421638Y318944D02*
X1424898Y322204D01*
G01X1414817Y313750D02*
X1423837Y322771D01*
G01X1424898Y322204D02*
X1428307Y339434D01*
G01X1423837Y322771D02*
X1427134Y339434D01*
G01X1428307D02*
X1425758Y352318D01*
G01X1427134Y339434D02*
X1424584Y352314D01*
G01X1420247Y350740D02*
X1422784Y337919D01*
G01X1419074Y350740D02*
X1421611Y337919D01*
G01X1422784D02*
X1420590Y326834D01*
G01X1421611Y337919D02*
X1419529Y327400D01*
G01X1420590Y326834D02*
X1416655Y322899D01*
G01X1419529Y327400D02*
X1416178Y324049D01*
G01X1416655Y322899D02*
X1409599D01*
G01X1416178Y324049D02*
X1409122D01*
G01X1409599Y322899D02*
X1404380Y317680D01*
G01X1409122Y324049D02*
X1403903Y318830D01*
G01X1439295Y342537D02*
X1434127Y316427D01*
G01X1438122Y342537D02*
X1433049Y316906D01*
G01X1434127Y316428D02*
X1432475Y314211D01*
G01X1433048Y316906D02*
X1431397Y314690D01*
G01X1432475Y314211D02*
X1430658Y305031D01*
G01X1431397Y314690D02*
X1429485Y305033D01*
G01X1430658Y305031D02*
X1431432Y301120D01*
G01X1429485Y305033D02*
X1430237Y301233D01*
G01X1431432Y301120D02*
X1428995Y295093D01*
G01X1430237Y301233D02*
X1428049Y295823D01*
G01X1428995Y295093D02*
X1424179Y291501D01*
G01X1428049Y295823D02*
X1423702Y292581D01*
G01X1424178Y291502D02*
X1418496Y290379D01*
G01X1423702Y292581D02*
X1418496Y291552D01*
G01Y290379D02*
X1416495Y290775D01*
G01X1418496Y291552D02*
X1416495Y291948D01*
G01Y290775D02*
X1414530Y290386D01*
G01X1416495Y291948D02*
X1414531Y291559D01*
G01X1414530Y290386D02*
X1412611Y290766D01*
G01X1414531Y291559D02*
X1412611Y291939D01*
G01Y290766D02*
X1410599Y290368D01*
G01X1412611Y291939D02*
X1410599Y291541D01*
G01Y290368D02*
X1408641Y290756D01*
G01X1410599Y291541D02*
X1408641Y291929D01*
G01Y290756D02*
X1406726Y290377D01*
G01X1408641Y291929D02*
X1406726Y291550D01*
G01Y290377D02*
X1404764Y290766D01*
G01X1406726Y291550D02*
X1404764Y291939D01*
G01X1434893Y345563D02*
X1436094Y339497D01*
G01X1433720Y345563D02*
X1434921Y339497D01*
G01X1436094D02*
X1431737Y317486D01*
G01X1434921Y339497D02*
X1430659Y317964D01*
G01X1431737Y317486D02*
X1430084Y315267D01*
G01X1430659Y317964D02*
X1429007Y315748D01*
G01X1430084Y315267D02*
X1428058Y305031D01*
G01X1429006Y315745D02*
X1426885Y305031D01*
G01X1428058D02*
X1428783Y301371D01*
G01X1426885Y305031D02*
X1427588Y301484D01*
G01X1428783Y301371D02*
X1426898Y296711D01*
G01X1427588Y301484D02*
X1425952Y297441D01*
G01X1426898Y296711D02*
X1423115Y293891D01*
G01X1425952Y297441D02*
X1422636Y294969D01*
G01X1423115Y293891D02*
X1418498Y292978D01*
G01X1422636Y294969D02*
X1418498Y294151D01*
G01Y292978D02*
X1416535Y293366D01*
G01X1418498Y294151D02*
X1416535Y294539D01*
G01Y293366D02*
X1414573Y292978D01*
G01X1416535Y294539D02*
X1414573Y294151D01*
G01Y292978D02*
X1412611Y293366D01*
G01X1414573Y294151D02*
X1412611Y294539D01*
G01Y293366D02*
X1410599Y292968D01*
G01X1412611Y294539D02*
X1410599Y294141D01*
G01Y292968D02*
X1408641Y293356D01*
G01X1410599Y294141D02*
X1408641Y294529D01*
G01Y293356D02*
X1406726Y292977D01*
G01X1408641Y294529D02*
X1406726Y294150D01*
G01Y292977D02*
X1404764Y293365D01*
G01X1406726Y294150D02*
X1404764Y294538D01*
G01X1431693Y348598D02*
X1433494Y339497D01*
G01X1430520Y348598D02*
X1432321Y339497D01*
G01X1433494D02*
X1429349Y318549D01*
G01X1432321Y339497D02*
X1428271Y319027D01*
G01X1429344Y318542D02*
X1427696Y316331D01*
G01X1428270Y319027D02*
X1426618Y316810D01*
G01X1427696Y316331D02*
X1425459Y305031D01*
G01X1426618Y316810D02*
X1424286Y305031D01*
G01X1425459D02*
X1426134Y301622D01*
G01X1424286Y305031D02*
X1424939Y301735D01*
G01X1426134Y301622D02*
X1424802Y298329D01*
G01X1424939Y301735D02*
X1423856Y299059D01*
G01X1424802Y298329D02*
X1422056Y296282D01*
G01X1423856Y299059D02*
X1421577Y297360D01*
G01X1422056Y296282D02*
X1418496Y295578D01*
G01X1421577Y297360D02*
X1418496Y296751D01*
G01Y295578D02*
X1416535Y295965D01*
G01X1418496Y296751D02*
X1416535Y297138D01*
G01Y295965D02*
X1414573Y295577D01*
G01X1416535Y297138D02*
X1414573Y296750D01*
G01Y295577D02*
X1412611Y295965D01*
G01X1414573Y296750D02*
X1412611Y297138D01*
G01Y295965D02*
X1410649Y295577D01*
G01X1412611Y297138D02*
X1410649Y296750D01*
G01Y295577D02*
X1408688Y295965D01*
G01X1410649Y296750D02*
X1408688Y297138D01*
G01Y295965D02*
X1406726Y295577D01*
G01X1408688Y297138D02*
X1406726Y296750D01*
G01Y295577D02*
X1404764Y295965D01*
G01X1406726Y296750D02*
X1404764Y297138D01*
G01Y298565D02*
X1406726Y298177D01*
G01X1404764Y299738D02*
X1406726Y299350D01*
G01Y298177D02*
X1408688Y298565D01*
G01X1406726Y299350D02*
X1408688Y299738D01*
G01Y298565D02*
X1410649Y298177D01*
G01X1408688Y299738D02*
X1410649Y299350D01*
G01Y298177D02*
X1412611Y298565D01*
G01X1410649Y299350D02*
X1412611Y299738D01*
G01Y298565D02*
X1414573Y298177D01*
G01X1412611Y299738D02*
X1414573Y299350D01*
G01Y298177D02*
X1416535Y298565D01*
G01X1414573Y299350D02*
X1416535Y299738D01*
G01Y298565D02*
X1418496Y298177D01*
G01X1416535Y299738D02*
X1418496Y299350D01*
G01Y298177D02*
X1420995Y298672D01*
G01X1418496Y299350D02*
X1420516Y299750D01*
G01X1420995Y298672D02*
X1422706Y299947D01*
G01X1420516Y299750D02*
X1421760Y300677D01*
G01X1422706Y299947D02*
X1423485Y301873D01*
G01X1421760Y300677D02*
X1422290Y301986D01*
G01X1423485Y301873D02*
X1422860Y305031D01*
G01X1422290Y301986D02*
X1421687Y305031D01*
G01X1422860D02*
X1425307Y317392D01*
G01X1421687Y305031D02*
X1424229Y317871D01*
G01X1425307Y317392D02*
X1426958Y319608D01*
G01X1424229Y317870D02*
X1425879Y320085D01*
G01X1426958Y319608D02*
X1430895Y339497D01*
G01X1425879Y320085D02*
X1429722Y339497D01*
G01X1430895D02*
X1428698Y350599D01*
G01X1429722Y339497D02*
X1427525Y350599D01*
G01X1414817Y313750D02*
X1423837Y322771D01*
G01X1415294Y312600D02*
X1416935Y314241D01*
G01X1414817Y313750D02*
X1423837Y322771D01*
G01X1418809Y316115D02*
X1419764Y317070D01*
G01X1414817Y313750D02*
X1423837Y322771D01*
G01X1421638Y318944D02*
X1424898Y322204D01*
G01X1423837Y322771D02*
X1427134Y339434D01*
G01X1424898Y322204D02*
X1428307Y339434D01*
G01X1427134D02*
X1424584Y352314D01*
G01X1428307Y339434D02*
X1425758Y352318D01*
G01X1419074Y350740D02*
X1421611Y337919D01*
G01X1420247Y350740D02*
X1422784Y337919D01*
G01X1421611D02*
X1419529Y327400D01*
G01X1422784Y337919D02*
X1420590Y326834D01*
G01X1419529Y327400D02*
X1416178Y324049D01*
G01X1420590Y326834D02*
X1416655Y322899D01*
G01X1416178Y324049D02*
X1409122D01*
G01X1416655Y322899D02*
X1409599D01*
G01X1409122Y324049D02*
X1403903Y318830D01*
G01X1409599Y322899D02*
X1404380Y317680D01*
G01X1414712Y317558D02*
X1415784D01*
G01X1414712Y318708D02*
X1415307D01*
G01X1415784Y317558D02*
X1422727Y324501D01*
G01X1415307Y318708D02*
X1421666Y325068D01*
G01X1422727Y324501D02*
X1425358Y337795D01*
G01X1421666Y325068D02*
X1424185Y337795D01*
G01X1425358D02*
X1424374Y342769D01*
G01X1424185Y337795D02*
X1421648Y350617D01*
G01X1414712Y318708D02*
X1415307D01*
G01X1414712Y317558D02*
X1415784D01*
G01X1415307Y318708D02*
X1421666Y325068D01*
G01X1415784Y317558D02*
X1422727Y324501D01*
G01X1421666Y325068D02*
X1424185Y337795D01*
G01X1422727Y324501D02*
X1425358Y337795D01*
G01X1424185D02*
X1421648Y350617D01*
G01X1425358Y337795D02*
X1424374Y342769D01*
G01X1424185Y337795D02*
X1421648Y350617D01*
G01X1424185Y337795D02*
X1421648Y350617D01*
G01X1461295Y414154D02*
X1457368Y402464D01*
G01X1462285Y413489D02*
X1458392Y401899D01*
G01X1457368Y402464D02*
X1454261Y398657D01*
G01X1458392Y401899D02*
X1455335Y398153D01*
G01X1454261Y398657D02*
X1453539Y394961D01*
G01X1455335Y398153D02*
X1454712Y394962D01*
G01X1453539Y394961D02*
X1454407Y390573D01*
G01X1454712Y394962D02*
X1455580Y390570D01*
G01X1454407Y390573D02*
X1453767Y387428D01*
G01X1455580Y390570D02*
X1454941Y387428D01*
G01X1453767D02*
X1454102Y385785D01*
G01X1454941Y387428D02*
X1455276Y385785D01*
G01X1454102D02*
X1453492Y382790D01*
G01X1455276Y385785D02*
X1454666Y382790D01*
G01X1453492D02*
X1454383Y378410D01*
G01X1454666Y382790D02*
X1455593Y378236D01*
G01X1454383Y378410D02*
X1453328Y376417D01*
G01X1455593Y378236D02*
X1454538Y376243D01*
G01X1453328Y376417D02*
X1454235Y371978D01*
G01X1454538Y376243D02*
X1455460Y371732D01*
G01X1454235Y371978D02*
X1448445Y363474D01*
G01X1455460Y371732D02*
X1449396Y362827D01*
G01X1446954Y361284D02*
X1446194Y360168D01*
G01X1444703Y357978D02*
X1443943Y356862D01*
G01X1442451Y354672D02*
X1441248Y352904D01*
G01X1449396Y362826D02*
X1442324Y352439D01*
G01X1441248Y352904D02*
X1439912Y346865D01*
G01X1442324Y352439D02*
X1441087Y346852D01*
G01X1439912Y346865D02*
X1440744Y342656D01*
G01X1441087Y346852D02*
X1441917Y342656D01*
G01X1462285Y413489D02*
X1458392Y401899D01*
G01X1461295Y414154D02*
X1457368Y402464D01*
G01X1458392Y401899D02*
X1455335Y398153D01*
G01X1457368Y402464D02*
X1454261Y398657D01*
G01X1455335Y398153D02*
X1454712Y394962D01*
G01X1454261Y398657D02*
X1453539Y394961D01*
G01X1454712Y394962D02*
X1455580Y390570D01*
G01X1453539Y394961D02*
X1454407Y390573D01*
G01X1455580Y390570D02*
X1454941Y387428D01*
G01X1454407Y390573D02*
X1453767Y387428D01*
G01X1454941D02*
X1455276Y385785D01*
G01X1453767Y387428D02*
X1454102Y385785D01*
G01X1455276D02*
X1454666Y382790D01*
G01X1454102Y385785D02*
X1453492Y382790D01*
G01X1454666D02*
X1455593Y378236D01*
G01X1453492Y382790D02*
X1454383Y378410D01*
G01X1455593Y378236D02*
X1454538Y376243D01*
G01X1454383Y378410D02*
X1453328Y376417D01*
G01X1454538Y376243D02*
X1455460Y371732D01*
G01X1453328Y376417D02*
X1454235Y371978D01*
G01X1455460Y371732D02*
X1449396Y362827D01*
G01X1454235Y371978D02*
X1448445Y363474D01*
G01X1449396Y362826D02*
X1442324Y352439D01*
G01X1446954Y361284D02*
X1446194Y360168D01*
G01X1449396Y362826D02*
X1442324Y352439D01*
G01X1444703Y357978D02*
X1443943Y356862D01*
G01X1449396Y362826D02*
X1442324Y352439D01*
G01X1442451Y354672D02*
X1441248Y352904D01*
G01X1442324Y352439D02*
X1441087Y346852D01*
G01X1441248Y352904D02*
X1439912Y346865D01*
G01X1441087Y346852D02*
X1441917Y342656D01*
G01X1439912Y346865D02*
X1440744Y342656D01*
G01X1455071Y403636D02*
X1451788Y399613D01*
G01X1456095Y403071D02*
X1452850Y399094D01*
G01X1451788Y399613D02*
X1450850Y395510D01*
G01X1452850Y399094D02*
X1452026Y395490D01*
G01X1450850Y395510D02*
X1451808Y390563D01*
G01X1452026Y395490D02*
X1452981Y390557D01*
G01X1451808Y390563D02*
X1451159Y387379D01*
G01X1452981Y390557D02*
X1452333Y387379D01*
G01X1451159D02*
X1451491Y385746D01*
G01X1452333Y387379D02*
X1452665Y385746D01*
G01X1451491D02*
X1450875Y382720D01*
G01X1452665Y385746D02*
X1452049Y382720D01*
G01X1450875D02*
X1451517Y379566D01*
G01X1452049Y382720D02*
X1452727Y379392D01*
G01X1451517Y379566D02*
X1450255Y377181D01*
G01X1452724Y379386D02*
X1451465Y377007D01*
G01X1450255Y377181D02*
X1450922Y373913D01*
G01X1451465Y377007D02*
X1452146Y373667D01*
G01X1450922Y373913D02*
X1439181Y356663D01*
G01X1452146Y373667D02*
X1440253Y356194D01*
G01X1439181Y356663D02*
X1437104Y347680D01*
G01X1440253Y356193D02*
X1438281Y347661D01*
G01X1437104Y347680D02*
X1438122Y342537D01*
G01X1438281Y347661D02*
X1439295Y342537D01*
G01X1451911Y407749D02*
X1448395Y402535D01*
G01X1447502Y403270D02*
X1446498Y402266D01*
G01X1448395Y402535D02*
X1447230Y401370D01*
G01X1446498Y402266D02*
X1441734Y399112D01*
G01X1447230Y401370D02*
X1442564Y398282D01*
G01X1441734Y399112D02*
X1440915Y397878D01*
G01X1442564Y398282D02*
X1442000Y397431D01*
G01X1440915Y397878D02*
X1439477Y390620D01*
G01X1438946Y387942D02*
X1438684Y386618D01*
G01X1438153Y383940D02*
X1437891Y382616D01*
G01X1442000Y397431D02*
X1439064Y382616D01*
G01X1437891D02*
X1439472Y374630D01*
G01X1439064Y382616D02*
X1440645Y374631D01*
G01X1439472Y374630D02*
X1436150Y357842D01*
G01X1435635Y355243D02*
X1435373Y353918D01*
G01X1434859Y351319D02*
X1434597Y349995D01*
G01X1434082Y347395D02*
X1433720Y345563D01*
G01X1440600Y374406D02*
X1434893Y345563D01*
G01X1445450Y405491D02*
X1441664Y402939D01*
G01X1446279Y404662D02*
X1442442Y402075D01*
G01X1441664Y402939D02*
X1436998Y397375D01*
G01X1442442Y402075D02*
X1438069Y396862D01*
G01X1436998Y397375D02*
X1433944Y381951D01*
G01X1438069Y396862D02*
X1435117Y381951D01*
G01X1433944D02*
X1435532Y373924D01*
G01X1435117Y381951D02*
X1436705Y373924D01*
G01X1435532D02*
X1433716Y364752D01*
G01X1433202Y362152D02*
X1432940Y360828D01*
G01X1432426Y358228D02*
X1432164Y356904D01*
G01X1431649Y354304D02*
X1431387Y352980D01*
G01X1430873Y350380D02*
X1430520Y348598D01*
G01X1436705Y373924D02*
X1431693Y348598D01*
G01X1427525Y350599D02*
X1432537Y375926D01*
G01X1428698Y350599D02*
X1433710Y375926D01*
G01X1432537D02*
X1430851Y384443D01*
G01X1433710Y375926D02*
X1432024Y384443D01*
G01X1430851D02*
X1436678Y413909D01*
G01X1432024Y384443D02*
X1437725Y413270D01*
G01X1425758Y352318D02*
X1430771Y377645D01*
G01X1424584Y352314D02*
X1429598Y377645D01*
G01X1430771D02*
X1428844Y387387D01*
G01X1429598Y377645D02*
X1427671Y387387D01*
G01X1428844D02*
X1429351Y389950D01*
G01X1429866Y392549D02*
X1430128Y393874D01*
G01X1430642Y396473D02*
X1433993Y413409D01*
G01X1427671Y387387D02*
X1432820Y413409D01*
G01X1428631Y414235D02*
X1423479Y388219D01*
G01X1427458Y414235D02*
X1422306Y388219D01*
G01X1423479D02*
X1425572Y377644D01*
G01X1422306Y388219D02*
X1424399Y377644D01*
G01X1425572D02*
X1420247Y350740D01*
G01X1424399Y377644D02*
X1419074Y350740D01*
G01X1456095Y403071D02*
X1452850Y399094D01*
G01X1455071Y403636D02*
X1451788Y399613D01*
G01X1452850Y399094D02*
X1452026Y395490D01*
G01X1451788Y399613D02*
X1450850Y395510D01*
G01X1452026Y395490D02*
X1452981Y390557D01*
G01X1450850Y395510D02*
X1451808Y390563D01*
G01X1452981Y390557D02*
X1452333Y387379D01*
G01X1451808Y390563D02*
X1451159Y387379D01*
G01X1452333D02*
X1452665Y385746D01*
G01X1451159Y387379D02*
X1451491Y385746D01*
G01X1452665D02*
X1452049Y382720D01*
G01X1451491Y385746D02*
X1450875Y382720D01*
G01X1452049D02*
X1452727Y379392D01*
G01X1450875Y382720D02*
X1451517Y379566D01*
G01X1452724Y379386D02*
X1451465Y377007D01*
G01X1451517Y379566D02*
X1450255Y377181D01*
G01X1451465Y377007D02*
X1452146Y373667D01*
G01X1450255Y377181D02*
X1450922Y373913D01*
G01X1452146Y373667D02*
X1440253Y356194D01*
G01X1450922Y373913D02*
X1439181Y356663D01*
G01X1440253Y356193D02*
X1438281Y347661D01*
G01X1439181Y356663D02*
X1437104Y347680D01*
G01X1438281Y347661D02*
X1439295Y342537D01*
G01X1437104Y347680D02*
X1438122Y342537D01*
G01X1451911Y407749D02*
X1448395Y402535D01*
G01X1451911Y407749D02*
X1448395Y402535D01*
G01D02*
X1447230Y401370D01*
G01X1448395Y402535D02*
X1447230Y401370D01*
G01X1447502Y403270D02*
X1446498Y402266D01*
G01X1447230Y401370D02*
X1442564Y398282D01*
G01X1446498Y402266D02*
X1441734Y399112D01*
G01X1442564Y398282D02*
X1442000Y397431D01*
G01X1441734Y399112D02*
X1440915Y397878D01*
G01X1442000Y397431D02*
X1439064Y382616D01*
G01X1440915Y397878D02*
X1439477Y390620D01*
G01X1442000Y397431D02*
X1439064Y382616D01*
G01X1438946Y387942D02*
X1438684Y386618D01*
G01X1442000Y397431D02*
X1439064Y382616D01*
G01X1438153Y383940D02*
X1437891Y382616D01*
G01X1439064D02*
X1440645Y374631D01*
G01X1437891Y382616D02*
X1439472Y374630D01*
G01X1440600Y374406D02*
X1434893Y345563D01*
G01X1439472Y374630D02*
X1436150Y357842D01*
G01X1440600Y374406D02*
X1434893Y345563D01*
G01X1435635Y355243D02*
X1435373Y353918D01*
G01X1440600Y374406D02*
X1434893Y345563D01*
G01X1434859Y351319D02*
X1434597Y349995D01*
G01X1440600Y374406D02*
X1434893Y345563D01*
G01X1434082Y347395D02*
X1433720Y345563D01*
G01X1446279Y404662D02*
X1442442Y402075D01*
G01X1445450Y405491D02*
X1441664Y402939D01*
G01X1442442Y402075D02*
X1438069Y396862D01*
G01X1441664Y402939D02*
X1436998Y397375D01*
G01X1438069Y396862D02*
X1435117Y381951D01*
G01X1436998Y397375D02*
X1433944Y381951D01*
G01X1435117D02*
X1436705Y373924D01*
G01X1433944Y381951D02*
X1435532Y373924D01*
G01X1436705D02*
X1431693Y348598D01*
G01X1435532Y373924D02*
X1433716Y364752D01*
G01X1436705Y373924D02*
X1431693Y348598D01*
G01X1433202Y362152D02*
X1432940Y360828D01*
G01X1436705Y373924D02*
X1431693Y348598D01*
G01X1432426Y358228D02*
X1432164Y356904D01*
G01X1436705Y373924D02*
X1431693Y348598D01*
G01X1431649Y354304D02*
X1431387Y352980D01*
G01X1436705Y373924D02*
X1431693Y348598D01*
G01X1430873Y350380D02*
X1430520Y348598D01*
G01X1428698Y350599D02*
X1433710Y375926D01*
G01X1427525Y350599D02*
X1432537Y375926D01*
G01X1433710D02*
X1432024Y384443D01*
G01X1432537Y375926D02*
X1430851Y384443D01*
G01X1432024D02*
X1437725Y413270D01*
G01X1430851Y384443D02*
X1436678Y413909D01*
G01X1424584Y352314D02*
X1429598Y377645D01*
G01X1425758Y352318D02*
X1430771Y377645D01*
G01X1429598D02*
X1427671Y387387D01*
G01X1430771Y377645D02*
X1428844Y387387D01*
G01X1427671D02*
X1432820Y413409D01*
G01X1428844Y387387D02*
X1429351Y389950D01*
G01X1427671Y387387D02*
X1432820Y413409D01*
G01X1429866Y392549D02*
X1430128Y393874D01*
G01X1427671Y387387D02*
X1432820Y413409D01*
G01X1430642Y396473D02*
X1433993Y413409D01*
G01X1427458Y414235D02*
X1422306Y388219D01*
G01X1428631Y414235D02*
X1423479Y388219D01*
G01X1422306D02*
X1424399Y377644D01*
G01X1423479Y388219D02*
X1425572Y377644D01*
G01X1424399D02*
X1419074Y350740D01*
G01X1425572Y377644D02*
X1420247Y350740D01*
G01X1423859Y345369D02*
X1423597Y346693D01*
G01X1423083Y349293D02*
X1422821Y350617D01*
G01D02*
X1428171Y377644D01*
G01X1421648Y350617D02*
X1426998Y377644D01*
G01X1428171D02*
X1426211Y387549D01*
G01X1426998Y377644D02*
X1425038Y387549D01*
G01X1426211D02*
X1431361Y413573D01*
G01X1425038Y387549D02*
X1430188Y413573D01*
G01X1423859Y345369D02*
X1423597Y346693D01*
G01X1423083Y349293D02*
X1422821Y350617D01*
G01X1421648D02*
X1426998Y377644D01*
G01X1422821Y350617D02*
X1428171Y377644D01*
G01X1426998D02*
X1425038Y387549D01*
G01X1428171Y377644D02*
X1426211Y387549D01*
G01X1425038D02*
X1430188Y413573D01*
G01X1426211Y387549D02*
X1431361Y413573D01*
G01X1464805Y400500D02*
X1462625Y398320D01*
G01X1465048Y402370D02*
X1461475Y398797D01*
G01X1462625Y398320D02*
Y389226D01*
G01X1461475Y398797D02*
Y388749D01*
G01X1462625Y389226D02*
X1463430Y388421D01*
G01X1461475Y388749D02*
X1462953Y387271D01*
G01X1463430Y388421D02*
X1466505D01*
G01X1462953Y387271D02*
X1466028D01*
G01X1465048Y402370D02*
X1461475Y398797D01*
G01X1464805Y400500D02*
X1462625Y398320D01*
G01X1461475Y398797D02*
Y388749D01*
G01X1462625Y398320D02*
Y389226D01*
G01X1461475Y388749D02*
X1462953Y387271D01*
G01X1462625Y389226D02*
X1463430Y388421D01*
G01X1462953Y387271D02*
X1466028D01*
G01X1463430Y388421D02*
X1466505D01*
G01X1467849Y418604D02*
X1465396Y417692D01*
G01D02*
X1461295Y414154D01*
G01X1465991Y416686D02*
X1462285Y413489D01*
G01X1467849Y418604D02*
X1465396Y417692D01*
G01X1465991Y416686D02*
X1462285Y413489D01*
G01X1465396Y417692D02*
X1461295Y414154D01*
G01X1462356Y449241D02*
Y447317D01*
G01X1463506Y449303D02*
Y447794D01*
G01X1462356Y447317D02*
X1467967Y441706D01*
G01X1463506Y447794D02*
X1468920Y442380D01*
G01X1464852Y424364D02*
X1463429Y424024D01*
G01X1473981Y425361D02*
X1463859Y422943D01*
G01X1463429Y424024D02*
X1459524Y421747D01*
G01X1463859Y422943D02*
X1460552Y421015D01*
G01X1459524Y421747D02*
X1457202Y409982D01*
G01X1460552Y421015D02*
X1458316Y409686D01*
G01X1457202Y409982D02*
X1455071Y403636D01*
G01X1458316Y409686D02*
X1456095Y403071D01*
G01X1459578Y444257D02*
X1460388Y443447D01*
G01X1460391Y445071D02*
X1461538Y443924D01*
G01X1460388Y443447D02*
Y442014D01*
G01X1461538Y443924D02*
Y441898D01*
G01X1460388Y442014D02*
X1459846Y439346D01*
G01X1461538Y441898D02*
X1460925Y438876D01*
G01X1459846Y439346D02*
X1456333Y434444D01*
G01X1460925Y438876D02*
X1457414Y433978D01*
G01X1456333Y434444D02*
X1456013Y432824D01*
G01X1457414Y433978D02*
X1457186Y432824D01*
G01X1456013D02*
X1456407Y430838D01*
G01X1457186Y432824D02*
X1457580Y430838D01*
G01X1456407D02*
X1456018Y428876D01*
G01X1457580Y430838D02*
X1457191Y428876D01*
G01X1456018D02*
X1456401Y426938D01*
G01X1457191Y428876D02*
X1457574Y426938D01*
G01X1456401D02*
X1456014Y424976D01*
G01X1457574Y426938D02*
X1457187Y424977D01*
G01X1456014Y424976D02*
X1456789Y421057D01*
G01X1457187Y424977D02*
X1457962Y421057D01*
G01X1456789D02*
X1454820Y411085D01*
G01X1457962Y421057D02*
X1455856Y410395D01*
G01X1454820Y411085D02*
X1451083Y408579D01*
G01X1455856Y410395D02*
X1451911Y407749D01*
G01X1451083Y408579D02*
X1450956Y408392D01*
G01X1450957D02*
X1447503Y403270D01*
G01D02*
X1447502D01*
G01X1454742Y453358D02*
Y452512D01*
G01X1455892Y453392D02*
Y452035D01*
G01X1454742Y452512D02*
X1453494Y451264D01*
G01X1455892Y452035D02*
X1454519Y450662D01*
G01X1453494Y451264D02*
X1452670Y448363D01*
G01X1454519Y450662D02*
X1453852Y448315D01*
G01X1452670Y448363D02*
X1454190Y440671D01*
G01X1453852Y448315D02*
X1455363Y440671D01*
G01X1454190D02*
X1453414Y436747D01*
G01X1455363Y440671D02*
X1454587Y436747D01*
G01X1453414D02*
X1453802Y434785D01*
G01X1454587Y436747D02*
X1454975Y434785D01*
G01X1453802D02*
X1453414Y432824D01*
G01X1454975Y434785D02*
X1454587Y432824D01*
G01X1453414Y432822D02*
X1453807Y430838D01*
G01X1454587Y432824D02*
X1454980Y430838D01*
G01X1453807D02*
X1453419Y428876D01*
G01X1454980Y430838D02*
X1454592Y428876D01*
G01X1453419D02*
X1453802Y426938D01*
G01X1454592Y428876D02*
X1454975Y426938D01*
G01X1453802D02*
X1453414Y424976D01*
G01X1454975Y426938D02*
X1454587Y424976D01*
G01X1453414D02*
X1454191Y421052D01*
G01X1454587Y424976D02*
X1455364Y421052D01*
G01X1454191D02*
X1452521Y412616D01*
G01X1455364Y421052D02*
X1453558Y411926D01*
G01X1452521Y412616D02*
X1448376Y409830D01*
G01X1453558Y411926D02*
X1449205Y409000D01*
G01X1448376Y409830D02*
X1445450Y405491D01*
G01X1449205Y409000D02*
X1446279Y404662D01*
G01X1436678Y413909D02*
X1439381Y416051D01*
G01X1437725Y413270D02*
X1439661Y414804D01*
G01X1439381Y416051D02*
X1447580Y414142D01*
G01X1439661Y414804D02*
X1447643Y412946D01*
G01X1447580Y414142D02*
X1450419Y415126D01*
G01X1447643Y412946D02*
X1451419Y414255D01*
G01X1450419Y415126D02*
X1451591Y421051D01*
G01X1451419Y414255D02*
X1452764Y421051D01*
G01X1451591D02*
X1450814Y424976D01*
G01X1452764Y421051D02*
X1451987Y424976D01*
G01X1450814D02*
X1451203Y426938D01*
G01X1451987Y424976D02*
X1452376Y426938D01*
G01X1451203D02*
X1450835Y428800D01*
G01X1452376Y426938D02*
X1452008Y428800D01*
G01X1450834D02*
X1451222Y430762D01*
G01X1452007Y428800D02*
X1452395Y430762D01*
G01X1451222D02*
X1450805Y432872D01*
G01X1452395Y430762D02*
X1451978Y432872D01*
G01X1450805Y432874D02*
X1451193Y434832D01*
G01X1451978Y432872D02*
X1452366Y434832D01*
G01X1451193D02*
X1450814Y436748D01*
G01X1452366Y434832D02*
X1451987Y436749D01*
G01X1450814Y436748D02*
X1451591Y440668D01*
G01X1451987Y436749D02*
X1452017Y436900D01*
G01X1450814Y436748D02*
X1451591Y440668D01*
G01X1452017Y436900D02*
X1452764Y440668D01*
G01X1451591D02*
X1451117Y443066D01*
G01X1450603Y445666D02*
X1450341Y446990D01*
G01X1449827Y449590D02*
X1449654Y450465D01*
G01X1452764Y440668D02*
X1450715Y451031D01*
G01X1449654Y450465D02*
X1447575Y452544D01*
G01X1450715Y451031D02*
X1448725Y453021D01*
G01X1447575Y452544D02*
Y454438D01*
G01X1448725Y453021D02*
Y453961D01*
G01X1447575Y454438D02*
X1448231Y455094D01*
G01Y455095D02*
X1448232Y455096D01*
G01X1448725Y453961D02*
X1449045Y454281D01*
G01X1433993Y413409D02*
X1433515Y415825D01*
G01X1432820Y413409D02*
X1432342Y415825D01*
G01X1433515D02*
X1433903Y417787D01*
G01X1432342Y415825D02*
X1432730Y417787D01*
G01X1433903D02*
X1433515Y419749D01*
G01X1432730Y417787D02*
X1432342Y419749D01*
G01X1433515D02*
X1433890Y421642D01*
G01X1432342Y419749D02*
X1432717Y421642D01*
G01X1433890D02*
X1433502Y423604D01*
G01X1432717Y421642D02*
X1432329Y423604D01*
G01X1433502D02*
X1433836Y425297D01*
G01X1432329Y423604D02*
X1432737Y425674D01*
G01X1433836Y425297D02*
X1436256Y430113D01*
G01X1432737Y425674D02*
X1435398Y430967D01*
G01X1436256Y430113D02*
X1439199Y431609D01*
G01X1435398Y430967D02*
X1438395Y432491D01*
G01X1436256Y430113D02*
X1439199Y431609D01*
G01X1438395Y432491D02*
X1438396D01*
G01X1439199Y431609D02*
X1440462Y433606D01*
G01X1441879Y435847D02*
X1442600Y436988D01*
G01X1438396Y432491D02*
X1441450Y437322D01*
G01X1442600Y436988D02*
Y456283D01*
G01X1441450Y437322D02*
Y456760D01*
G01X1442600Y456283D02*
X1443917Y457601D01*
G01X1441450Y456760D02*
X1443103Y458414D01*
G01X1440173Y466419D02*
X1437500Y463746D01*
G01X1445353Y473226D02*
X1436350Y464223D01*
G01X1437500Y463746D02*
Y438453D01*
G01X1436350Y464223D02*
Y438787D01*
G01X1437500Y438453D02*
X1436518Y436900D01*
G01D02*
X1435648Y435525D01*
G01X1436350Y438787D02*
X1435157Y436900D01*
G01X1436518D02*
X1435648Y435525D01*
G01X1435157Y436900D02*
X1434845Y436407D01*
G01X1435648Y435525D02*
X1432066Y433703D01*
G01X1434845Y436407D02*
X1431267Y434587D01*
G01X1432066Y433703D02*
X1429513Y429730D01*
G01X1431267Y434587D02*
X1428427Y430168D01*
G01X1429513Y429730D02*
X1428315Y423672D01*
G01X1428427Y430168D02*
X1427142Y423672D01*
G01X1428315D02*
X1428694Y421757D01*
G01X1427142Y423672D02*
X1427521Y421757D01*
G01X1428694D02*
X1428306Y419799D01*
G01X1427521Y421757D02*
X1427133Y419799D01*
G01X1428306D02*
X1428704Y417787D01*
G01X1427133Y419799D02*
X1427531Y417787D01*
G01X1428704D02*
X1428316Y415825D01*
G01X1427531Y417787D02*
X1427143Y415825D01*
G01X1428316D02*
X1428631Y414235D01*
G01X1427143Y415825D02*
X1427458Y414235D01*
G01X1463506Y449303D02*
Y447794D01*
G01X1462356Y449241D02*
Y447317D01*
G01X1463506Y447794D02*
X1468920Y442380D01*
G01X1462356Y447317D02*
X1467967Y441706D01*
G01X1473981Y425361D02*
X1463859Y422943D01*
G01X1473981Y425361D02*
X1463859Y422943D01*
G01X1473981Y425361D02*
X1463859Y422943D01*
G01X1464852Y424364D02*
X1463429Y424024D01*
G01X1463859Y422943D02*
X1460552Y421015D01*
G01X1463429Y424024D02*
X1459524Y421747D01*
G01X1460552Y421015D02*
X1458316Y409686D01*
G01X1459524Y421747D02*
X1457202Y409982D01*
G01X1458316Y409686D02*
X1456095Y403071D01*
G01X1457202Y409982D02*
X1455071Y403636D01*
G01X1460391Y445071D02*
X1461538Y443924D01*
G01X1459578Y444257D02*
X1460388Y443447D01*
G01X1461538Y443924D02*
Y441898D01*
G01X1460388Y443447D02*
Y442014D01*
G01X1461538Y441898D02*
X1460925Y438876D01*
G01X1460388Y442014D02*
X1459846Y439346D01*
G01X1460925Y438876D02*
X1457414Y433978D01*
G01X1459846Y439346D02*
X1456333Y434444D01*
G01X1457414Y433978D02*
X1457186Y432824D01*
G01X1456333Y434444D02*
X1456013Y432824D01*
G01X1457186D02*
X1457580Y430838D01*
G01X1456013Y432824D02*
X1456407Y430838D01*
G01X1457580D02*
X1457191Y428876D01*
G01X1456407Y430838D02*
X1456018Y428876D01*
G01X1457191D02*
X1457574Y426938D01*
G01X1456018Y428876D02*
X1456401Y426938D01*
G01X1457574D02*
X1457187Y424977D01*
G01X1456401Y426938D02*
X1456014Y424976D01*
G01X1457187Y424977D02*
X1457962Y421057D01*
G01X1456014Y424976D02*
X1456789Y421057D01*
G01X1457962D02*
X1455856Y410395D01*
G01X1456789Y421057D02*
X1454820Y411085D01*
G01X1455856Y410395D02*
X1451911Y407749D01*
G01X1454820Y411085D02*
X1451083Y408579D01*
G01D02*
X1450956Y408392D01*
G01X1450957D02*
X1447503Y403270D01*
G01D02*
X1447502D01*
G01X1455892Y453392D02*
Y452035D01*
G01X1454742Y453358D02*
Y452512D01*
G01X1455892Y452035D02*
X1454519Y450662D01*
G01X1454742Y452512D02*
X1453494Y451264D01*
G01X1454519Y450662D02*
X1453852Y448315D01*
G01X1453494Y451264D02*
X1452670Y448363D01*
G01X1453852Y448315D02*
X1455363Y440671D01*
G01X1452670Y448363D02*
X1454190Y440671D01*
G01X1455363D02*
X1454587Y436747D01*
G01X1454190Y440671D02*
X1453414Y436747D01*
G01X1454587D02*
X1454975Y434785D01*
G01X1453414Y436747D02*
X1453802Y434785D01*
G01X1454975D02*
X1454587Y432824D01*
G01X1453802Y434785D02*
X1453414Y432824D01*
G01X1454587D02*
X1454980Y430838D01*
G01X1453414Y432822D02*
X1453807Y430838D01*
G01X1454980D02*
X1454592Y428876D01*
G01X1453807Y430838D02*
X1453419Y428876D01*
G01X1454592D02*
X1454975Y426938D01*
G01X1453419Y428876D02*
X1453802Y426938D01*
G01X1454975D02*
X1454587Y424976D01*
G01X1453802Y426938D02*
X1453414Y424976D01*
G01X1454587D02*
X1455364Y421052D01*
G01X1453414Y424976D02*
X1454191Y421052D01*
G01X1455364D02*
X1453558Y411926D01*
G01X1454191Y421052D02*
X1452521Y412616D01*
G01X1453558Y411926D02*
X1449205Y409000D01*
G01X1452521Y412616D02*
X1448376Y409830D01*
G01X1449205Y409000D02*
X1446279Y404662D01*
G01X1448376Y409830D02*
X1445450Y405491D01*
G01X1437725Y413270D02*
X1439661Y414804D01*
G01X1436678Y413909D02*
X1439381Y416051D01*
G01X1439661Y414804D02*
X1447643Y412946D01*
G01X1439381Y416051D02*
X1447580Y414142D01*
G01X1447643Y412946D02*
X1451419Y414255D01*
G01X1447580Y414142D02*
X1450419Y415126D01*
G01X1451419Y414255D02*
X1452764Y421051D01*
G01X1450419Y415126D02*
X1451591Y421051D01*
G01X1452764D02*
X1451987Y424976D01*
G01X1451591Y421051D02*
X1450814Y424976D01*
G01X1451987D02*
X1452376Y426938D01*
G01X1450814Y424976D02*
X1451203Y426938D01*
G01X1452376D02*
X1452008Y428800D01*
G01X1451203Y426938D02*
X1450835Y428800D01*
G01X1452007D02*
X1452395Y430762D01*
G01X1450834Y428800D02*
X1451222Y430762D01*
G01X1452395D02*
X1451978Y432872D01*
G01X1451222Y430762D02*
X1450805Y432872D01*
G01X1451978D02*
X1452366Y434832D01*
G01X1450805Y432874D02*
X1451193Y434832D01*
G01X1452366D02*
X1451987Y436749D01*
G01X1451193Y434832D02*
X1450814Y436748D01*
G01X1451987Y436749D02*
X1452017Y436900D01*
G01D02*
X1452764Y440668D01*
G01X1450814Y436748D02*
X1451591Y440668D01*
G01X1452764D02*
X1450715Y451031D01*
G01X1451591Y440668D02*
X1451117Y443066D01*
G01X1452764Y440668D02*
X1450715Y451031D01*
G01X1450603Y445666D02*
X1450341Y446990D01*
G01X1452764Y440668D02*
X1450715Y451031D01*
G01X1449827Y449590D02*
X1449654Y450465D01*
G01X1450715Y451031D02*
X1448725Y453021D01*
G01X1449654Y450465D02*
X1447575Y452544D01*
G01X1448725Y453021D02*
Y453961D01*
G01X1447575Y452544D02*
Y454438D01*
G01X1448725Y453961D02*
X1449045Y454281D01*
G01X1447575Y454438D02*
X1448231Y455094D01*
G01X1448725Y453961D02*
X1449045Y454281D01*
G01X1448231Y455095D02*
X1448232Y455096D01*
G01X1432820Y413409D02*
X1432342Y415825D01*
G01X1433993Y413409D02*
X1433515Y415825D01*
G01X1432342D02*
X1432730Y417787D01*
G01X1433515Y415825D02*
X1433903Y417787D01*
G01X1432730D02*
X1432342Y419749D01*
G01X1433903Y417787D02*
X1433515Y419749D01*
G01X1432342D02*
X1432717Y421642D01*
G01X1433515Y419749D02*
X1433890Y421642D01*
G01X1432717D02*
X1432329Y423604D01*
G01X1433890Y421642D02*
X1433502Y423604D01*
G01X1432329D02*
X1432737Y425674D01*
G01X1433502Y423604D02*
X1433836Y425297D01*
G01X1432737Y425674D02*
X1435398Y430967D01*
G01X1433836Y425297D02*
X1436256Y430113D01*
G01X1435398Y430967D02*
X1438395Y432491D01*
G01D02*
X1438396D01*
G01X1436256Y430113D02*
X1439199Y431609D01*
G01X1438396Y432491D02*
X1441450Y437322D01*
G01X1439199Y431609D02*
X1440462Y433606D01*
G01X1438396Y432491D02*
X1441450Y437322D01*
G01X1441879Y435847D02*
X1442600Y436988D01*
G01X1441450Y437322D02*
Y456760D01*
G01X1442600Y436988D02*
Y456283D01*
G01X1441450Y456760D02*
X1443103Y458414D01*
G01X1442600Y456283D02*
X1443917Y457601D01*
G01X1445353Y473226D02*
X1436350Y464223D01*
G01X1445353Y473226D02*
X1436350Y464223D01*
G01X1445353Y473226D02*
X1436350Y464223D01*
G01X1440173Y466419D02*
X1437500Y463746D01*
G01X1436350Y464223D02*
Y438787D01*
G01X1437500Y463746D02*
Y438453D01*
G01X1436350Y438787D02*
X1435157Y436900D01*
G01X1437500Y438453D02*
X1436518Y436900D01*
G01X1436350Y438787D02*
X1435157Y436900D01*
G01D02*
X1434845Y436407D01*
G01X1436518Y436900D02*
X1435648Y435525D01*
G01X1434845Y436407D02*
X1431267Y434587D01*
G01X1435648Y435525D02*
X1432066Y433703D01*
G01X1431267Y434587D02*
X1428427Y430168D01*
G01X1432066Y433703D02*
X1429513Y429730D01*
G01X1428427Y430168D02*
X1427142Y423672D01*
G01X1429513Y429730D02*
X1428315Y423672D01*
G01X1427142D02*
X1427521Y421757D01*
G01X1428315Y423672D02*
X1428694Y421757D01*
G01X1427521D02*
X1427133Y419799D01*
G01X1428694Y421757D02*
X1428306Y419799D01*
G01X1427133D02*
X1427531Y417787D01*
G01X1428306Y419799D02*
X1428704Y417787D01*
G01X1427531D02*
X1427143Y415825D01*
G01X1428704Y417787D02*
X1428316Y415825D01*
G01X1427143D02*
X1427458Y414235D01*
G01X1428316Y415825D02*
X1428631Y414235D01*
G01X1407172Y477920D02*
X1417023Y458917D01*
G01X1405959Y477760D02*
X1415873Y458636D01*
G01X1417023Y458917D02*
Y452296D01*
G01X1415873Y458636D02*
Y452773D01*
G01X1417023Y452296D02*
X1414077Y449350D01*
G01X1415873Y452773D02*
X1413600Y450500D01*
G01X1404977Y438050D02*
X1406773Y436254D01*
G01X1404500Y436900D02*
X1405623Y435777D01*
G01X1406773Y436254D02*
Y433274D01*
G01X1405623Y435777D02*
Y433751D01*
G01X1406773Y433274D02*
X1405199Y431700D01*
G01X1405623Y433751D02*
X1404722Y432850D01*
G01X1405959Y477760D02*
X1415873Y458636D01*
G01X1407172Y477920D02*
X1417023Y458917D01*
G01X1415873Y458636D02*
Y452773D01*
G01X1417023Y458917D02*
Y452296D01*
G01X1415873Y452773D02*
X1413600Y450500D01*
G01X1417023Y452296D02*
X1414077Y449350D01*
G01X1404500Y436900D02*
X1405623Y435777D01*
G01X1404977Y438050D02*
X1406773Y436254D01*
G01X1405623Y435777D02*
Y433751D01*
G01X1406773Y436254D02*
Y433274D01*
G01X1405623Y433751D02*
X1404722Y432850D01*
G01X1406773Y433274D02*
X1405199Y431700D01*
G01X1408498Y469820D02*
Y456566D01*
G01X1407348Y469539D02*
Y456089D01*
G01X1408498Y456566D02*
X1408928Y456136D01*
G01X1407348Y456089D02*
X1408451Y454986D01*
G01X1408928Y456136D02*
X1410025D01*
G01X1408451Y454986D02*
X1410025D01*
G01X1407348Y469539D02*
Y456089D01*
G01X1408498Y469820D02*
Y456566D01*
G01X1407348Y456089D02*
X1408451Y454986D01*
G01X1408498Y456566D02*
X1408928Y456136D01*
G01X1408451Y454986D02*
X1410025D01*
G01X1408928Y456136D02*
X1410025D01*
G01X1431361Y413573D02*
X1430916Y415825D01*
G01X1430188Y413573D02*
X1429743Y415825D01*
G01X1430916D02*
X1431304Y417787D01*
G01X1429743Y415825D02*
X1430131Y417787D01*
G01X1431304D02*
X1430916Y419749D01*
G01X1430131Y417787D02*
X1429743Y419749D01*
G01X1430916D02*
X1431303Y421710D01*
G01X1429743Y419749D02*
X1430130Y421710D01*
G01X1431303D02*
X1430915Y423672D01*
G01X1430130Y421710D02*
X1429742Y423672D01*
G01X1430915D02*
X1431751Y427900D01*
G01X1429742Y423672D02*
X1430665Y428338D01*
G01X1431751Y427900D02*
X1434406Y432033D01*
G01X1430665Y428338D02*
X1433607Y432917D01*
G01X1434406Y432033D02*
X1437419Y433566D01*
G01X1433607Y432917D02*
X1436616Y434448D01*
G01X1437419Y433565D02*
X1440100Y437805D01*
G01X1436616Y434448D02*
X1438950Y438139D01*
G01X1440100Y437805D02*
Y458763D01*
G01X1438950Y438139D02*
Y459240D01*
G01X1440100Y458763D02*
X1443381Y462044D01*
G01X1445254Y463917D02*
X1446209Y464872D01*
G01X1438950Y459240D02*
X1448560Y468850D01*
G01X1430188Y413573D02*
X1429743Y415825D01*
G01X1431361Y413573D02*
X1430916Y415825D01*
G01X1429743D02*
X1430131Y417787D01*
G01X1430916Y415825D02*
X1431304Y417787D01*
G01X1430131D02*
X1429743Y419749D01*
G01X1431304Y417787D02*
X1430916Y419749D01*
G01X1429743D02*
X1430130Y421710D01*
G01X1430916Y419749D02*
X1431303Y421710D01*
G01X1430130D02*
X1429742Y423672D01*
G01X1431303Y421710D02*
X1430915Y423672D01*
G01X1429742D02*
X1430665Y428338D01*
G01X1430915Y423672D02*
X1431751Y427900D01*
G01X1430665Y428338D02*
X1433607Y432917D01*
G01X1431751Y427900D02*
X1434406Y432033D01*
G01X1433607Y432917D02*
X1436616Y434448D01*
G01X1434406Y432033D02*
X1437419Y433566D01*
G01X1436616Y434448D02*
X1438950Y438139D01*
G01X1437419Y433565D02*
X1440100Y437805D01*
G01X1438950Y438139D02*
Y459240D01*
G01X1440100Y437805D02*
Y458763D01*
G01X1438950Y459240D02*
X1448560Y468850D01*
G01X1440100Y458763D02*
X1443381Y462044D01*
G01X1438950Y459240D02*
X1448560Y468850D01*
G01X1445254Y463917D02*
X1446209Y464872D01*
G01X1438950Y459240D02*
X1448560Y468850D01*
G01X1409860Y478274D02*
X1419573Y459539D01*
G01X1408647Y478114D02*
X1418423Y459258D01*
G01X1419573Y459539D02*
Y449175D01*
G01X1418423Y459258D02*
Y449652D01*
G01X1419573Y449175D02*
X1417302Y446904D01*
G01X1418423Y449652D02*
X1416152Y447381D01*
G01X1417302Y446904D02*
Y437351D01*
G01X1416152Y447381D02*
Y437828D01*
G01X1417302Y437351D02*
X1415718Y435767D01*
G01X1416152Y437828D02*
X1414568Y436244D01*
G01X1415718Y435767D02*
Y433317D01*
G01X1414568Y436244D02*
Y433794D01*
G01X1415718Y433317D02*
X1414101Y431700D01*
G01X1414568Y433794D02*
X1413624Y432850D01*
G01X1414101Y431700D02*
X1409750D01*
G01X1413624Y432850D02*
X1409750D01*
G01X1415500Y418827D02*
X1417154D01*
G01X1415597Y419977D02*
X1416677D01*
G01X1417154Y418827D02*
X1418268Y419941D01*
G01X1416677Y419977D02*
X1417118Y420418D01*
G01X1418268Y419941D02*
Y434779D01*
G01X1417118Y420418D02*
Y435256D01*
G01X1418268Y434779D02*
X1419805Y436316D01*
G01X1417118Y435256D02*
X1418655Y436793D01*
G01X1419805Y436316D02*
Y445870D01*
G01X1418655Y436793D02*
Y446347D01*
G01X1419805Y445870D02*
X1422207Y448272D01*
G01X1418655Y446347D02*
X1421057Y448749D01*
G01X1422207Y448272D02*
Y469728D01*
G01X1421057Y448749D02*
Y469841D01*
G01X1424707Y469038D02*
Y447235D01*
G01X1423557Y469151D02*
Y447712D01*
G01X1424707Y447235D02*
X1422305Y444833D01*
G01X1423557Y447712D02*
X1421155Y445310D01*
G01X1422305Y444833D02*
Y435279D01*
G01X1421155Y445310D02*
Y435756D01*
G01X1422305Y435279D02*
X1420768Y433742D01*
G01X1421155Y435756D02*
X1419618Y434219D01*
G01X1420768Y433742D02*
Y417069D01*
G01X1419618Y434219D02*
Y417546D01*
G01X1420768Y417069D02*
X1416149Y412450D01*
G01X1419618Y417546D02*
X1415672Y413600D01*
G01X1416149Y412450D02*
X1411260D01*
G01X1415672Y413600D02*
X1411737D01*
G01X1411260Y412450D02*
X1409623Y414087D01*
G01X1411737Y413600D02*
X1410773Y414564D01*
G01X1409623Y414087D02*
Y417997D01*
G01X1410773Y414564D02*
Y418474D01*
G01X1409623Y417997D02*
X1409173Y418447D01*
G01X1410773Y418474D02*
X1409650Y419597D01*
G01X1409173Y418447D02*
X1407608D01*
G01X1409650Y419597D02*
X1407608D01*
G01X1406692Y409550D02*
X1417777D01*
G01X1408004Y410700D02*
X1417300D01*
G01X1417777Y409550D02*
X1423268Y415041D01*
G01X1417300Y410700D02*
X1422118Y415518D01*
G01X1423268Y415041D02*
Y432705D01*
G01X1422118Y415518D02*
Y433182D01*
G01X1423268Y432705D02*
X1424925Y434362D01*
G01X1422118Y433182D02*
X1423775Y434839D01*
G01X1424925Y434362D02*
Y443916D01*
G01X1423775Y434839D02*
Y444393D01*
G01X1424925Y443916D02*
X1427231Y446222D01*
G01X1423775Y444393D02*
X1426081Y446699D01*
G01X1427231Y446222D02*
Y468426D01*
G01X1426081Y446699D02*
Y468539D01*
G01X1408647Y478114D02*
X1418423Y459258D01*
G01X1409860Y478274D02*
X1419573Y459539D01*
G01X1418423Y459258D02*
Y449652D01*
G01X1419573Y459539D02*
Y449175D01*
G01X1418423Y449652D02*
X1416152Y447381D01*
G01X1419573Y449175D02*
X1417302Y446904D01*
G01X1416152Y447381D02*
Y437828D01*
G01X1417302Y446904D02*
Y437351D01*
G01X1416152Y437828D02*
X1414568Y436244D01*
G01X1417302Y437351D02*
X1415718Y435767D01*
G01X1414568Y436244D02*
Y433794D01*
G01X1415718Y435767D02*
Y433317D01*
G01X1414568Y433794D02*
X1413624Y432850D01*
G01X1415718Y433317D02*
X1414101Y431700D01*
G01X1413624Y432850D02*
X1409750D01*
G01X1414101Y431700D02*
X1409750D01*
G01X1415597Y419977D02*
X1416677D01*
G01X1415500Y418827D02*
X1417154D01*
G01X1416677Y419977D02*
X1417118Y420418D01*
G01X1417154Y418827D02*
X1418268Y419941D01*
G01X1417118Y420418D02*
Y435256D01*
G01X1418268Y419941D02*
Y434779D01*
G01X1417118Y435256D02*
X1418655Y436793D01*
G01X1418268Y434779D02*
X1419805Y436316D01*
G01X1418655Y436793D02*
Y446347D01*
G01X1419805Y436316D02*
Y445870D01*
G01X1418655Y446347D02*
X1421057Y448749D01*
G01X1419805Y445870D02*
X1422207Y448272D01*
G01X1421057Y448749D02*
Y469841D01*
G01X1422207Y448272D02*
Y469728D01*
G01X1423557Y469151D02*
Y447712D01*
G01X1424707Y469038D02*
Y447235D01*
G01X1423557Y447712D02*
X1421155Y445310D01*
G01X1424707Y447235D02*
X1422305Y444833D01*
G01X1421155Y445310D02*
Y435756D01*
G01X1422305Y444833D02*
Y435279D01*
G01X1421155Y435756D02*
X1419618Y434219D01*
G01X1422305Y435279D02*
X1420768Y433742D01*
G01X1419618Y434219D02*
Y417546D01*
G01X1420768Y433742D02*
Y417069D01*
G01X1419618Y417546D02*
X1415672Y413600D01*
G01X1420768Y417069D02*
X1416149Y412450D01*
G01X1415672Y413600D02*
X1411737D01*
G01X1416149Y412450D02*
X1411260D01*
G01X1411737Y413600D02*
X1410773Y414564D01*
G01X1411260Y412450D02*
X1409623Y414087D01*
G01X1410773Y414564D02*
Y418474D01*
G01X1409623Y414087D02*
Y417997D01*
G01X1410773Y418474D02*
X1409650Y419597D01*
G01X1409623Y417997D02*
X1409173Y418447D01*
G01X1409650Y419597D02*
X1407608D01*
G01X1409173Y418447D02*
X1407608D01*
G01X1408004Y410700D02*
X1417300D01*
G01X1406692Y409550D02*
X1417777D01*
G01X1417300Y410700D02*
X1422118Y415518D01*
G01X1417777Y409550D02*
X1423268Y415041D01*
G01X1422118Y415518D02*
Y433182D01*
G01X1423268Y415041D02*
Y432705D01*
G01X1422118Y433182D02*
X1423775Y434839D01*
G01X1423268Y432705D02*
X1424925Y434362D01*
G01X1423775Y434839D02*
Y444393D01*
G01X1424925Y434362D02*
Y443916D01*
G01X1423775Y444393D02*
X1426081Y446699D01*
G01X1424925Y443916D02*
X1427231Y446222D01*
G01X1426081Y446699D02*
Y468539D01*
G01X1427231Y446222D02*
Y468426D01*
G01X1462525Y467559D02*
Y468867D01*
G01X1463675Y467607D02*
Y469344D01*
G01X1462525Y468867D02*
X1459316Y472076D01*
G01X1463675Y469344D02*
X1459793Y473226D01*
G01X1459316Y472076D02*
X1457966D01*
G01X1455316D02*
X1453966D01*
G01X1451316D02*
X1445830D01*
G01X1459793Y473226D02*
X1445353D01*
G01X1445830Y472076D02*
X1444875Y471121D01*
G01X1443002Y469248D02*
X1442047Y468293D01*
G01X1463675Y467607D02*
Y469344D01*
G01X1462525Y467559D02*
Y468867D01*
G01X1463675Y469344D02*
X1459793Y473226D01*
G01X1462525Y468867D02*
X1459316Y472076D01*
G01X1459793Y473226D02*
X1445353D01*
G01X1459316Y472076D02*
X1457966D01*
G01X1459793Y473226D02*
X1445353D01*
G01X1455316Y472076D02*
X1453966D01*
G01X1459793Y473226D02*
X1445353D01*
G01X1451316Y472076D02*
X1445830D01*
G01D02*
X1444875Y471121D01*
G01X1443002Y469248D02*
X1442047Y468293D01*
G01X1465587Y519681D02*
X1460739Y520762D01*
G01X1465520Y520875D02*
X1460740Y521941D01*
G01X1460739Y520762D02*
X1457291Y519999D01*
G01X1460740Y521941D02*
X1456953Y521103D01*
G01X1457291Y519999D02*
X1424373Y506961D01*
G01X1456953Y521103D02*
X1423850Y507991D01*
G01X1424373Y506961D02*
X1408786Y497119D01*
G01X1423850Y507991D02*
X1407844Y497886D01*
G01X1408786Y497119D02*
X1406298Y490443D01*
G01X1407844Y497886D02*
X1405099Y490521D01*
G01X1406298Y490443D02*
X1408158Y482414D01*
G01X1405099Y490521D02*
X1406979Y482407D01*
G01X1408158Y482414D02*
X1407172Y477920D01*
G01X1406979Y482407D02*
X1405959Y477760D01*
G01X1406155Y505314D02*
X1407297Y506035D01*
G01X1409538Y507450D02*
X1410679Y508171D01*
G01X1412920Y509586D02*
X1414061Y510307D01*
G01X1416302Y511722D02*
X1417443Y512443D01*
G01X1416920Y513473D02*
X1440034Y522629D01*
G01X1417443Y512443D02*
X1440758Y521678D01*
G01X1440034Y522629D02*
X1445579Y529985D01*
G01X1440758Y521678D02*
X1446570Y529389D01*
G01X1448768Y528066D02*
X1447178Y525957D01*
G01X1445583Y523841D02*
X1444770Y522763D01*
G01X1443175Y520647D02*
X1442362Y519569D01*
G01X1447774Y528658D02*
X1441640Y520522D01*
G01X1442362Y519569D02*
X1421902Y511467D01*
G01X1441640Y520522D02*
X1421376Y512496D01*
G01X1421900Y511466D02*
X1404327Y500370D01*
G01X1465520Y520875D02*
X1460740Y521941D01*
G01X1465587Y519681D02*
X1460739Y520762D01*
G01X1460740Y521941D02*
X1456953Y521103D01*
G01X1460739Y520762D02*
X1457291Y519999D01*
G01X1456953Y521103D02*
X1423850Y507991D01*
G01X1457291Y519999D02*
X1424373Y506961D01*
G01X1423850Y507991D02*
X1407844Y497886D01*
G01X1424373Y506961D02*
X1408786Y497119D01*
G01X1407844Y497886D02*
X1405099Y490521D01*
G01X1408786Y497119D02*
X1406298Y490443D01*
G01X1405099Y490521D02*
X1406979Y482407D01*
G01X1406298Y490443D02*
X1408158Y482414D01*
G01X1406979Y482407D02*
X1405959Y477760D01*
G01X1408158Y482414D02*
X1407172Y477920D01*
G01X1406155Y505314D02*
X1407297Y506035D01*
G01X1409538Y507450D02*
X1410679Y508171D01*
G01X1412920Y509586D02*
X1414061Y510307D01*
G01X1416302Y511722D02*
X1417443Y512443D01*
G01D02*
X1440758Y521678D01*
G01X1416920Y513473D02*
X1440034Y522629D01*
G01X1440758Y521678D02*
X1446570Y529389D01*
G01X1440034Y522629D02*
X1445579Y529985D01*
G01X1447774Y528658D02*
X1441640Y520522D01*
G01X1448768Y528066D02*
X1447178Y525957D01*
G01X1447774Y528658D02*
X1441640Y520522D01*
G01X1445583Y523841D02*
X1444770Y522763D01*
G01X1447774Y528658D02*
X1441640Y520522D01*
G01X1443175Y520647D02*
X1442362Y519569D01*
G01X1441640Y520522D02*
X1421376Y512496D01*
G01X1442362Y519569D02*
X1421902Y511467D01*
G01X1421900Y511466D02*
X1404327Y500370D01*
G01X1467094Y525797D02*
X1464459Y525124D01*
G01X1466581Y526855D02*
X1464435Y526306D01*
G01X1464459Y525124D02*
X1460092Y526057D01*
G01X1464435Y526306D02*
X1460024Y527248D01*
G01X1460092Y526057D02*
X1457636Y525230D01*
G01X1460024Y527248D02*
X1457098Y526263D01*
G01X1457636Y525230D02*
X1450712Y520129D01*
G01X1457098Y526263D02*
X1450150Y521144D01*
G01X1450712Y520129D02*
X1423060Y509183D01*
G01X1450150Y521144D02*
X1422537Y510213D01*
G01X1423060Y509183D02*
X1406716Y498863D01*
G01X1422537Y510213D02*
X1405787Y499638D01*
G01X1405544Y482399D02*
X1404483Y477566D01*
G01D02*
X1408450Y469913D01*
G01X1466581Y526855D02*
X1464435Y526306D01*
G01X1467094Y525797D02*
X1464459Y525124D01*
G01X1464435Y526306D02*
X1460024Y527248D01*
G01X1464459Y525124D02*
X1460092Y526057D01*
G01X1460024Y527248D02*
X1457098Y526263D01*
G01X1460092Y526057D02*
X1457636Y525230D01*
G01X1457098Y526263D02*
X1450150Y521144D01*
G01X1457636Y525230D02*
X1450712Y520129D01*
G01X1450150Y521144D02*
X1422537Y510213D01*
G01X1450712Y520129D02*
X1423060Y509183D01*
G01X1422537Y510213D02*
X1405787Y499638D01*
G01X1423060Y509183D02*
X1406716Y498863D01*
G01X1405544Y482399D02*
X1404483Y477566D01*
G01D02*
X1408450Y469913D01*
G01X1448082Y466745D02*
X1449037Y467700D01*
G01D02*
X1453800D01*
G01X1448560Y468850D02*
X1454277D01*
G01X1453800Y467700D02*
X1454600Y466900D01*
G01X1454277Y468850D02*
X1455750Y467377D01*
G01X1454600Y466900D02*
Y466100D01*
G01X1455750Y467377D02*
Y466350D01*
G01X1448082Y466745D02*
X1449037Y467700D01*
G01X1448560Y468850D02*
X1454277D01*
G01X1449037Y467700D02*
X1453800D01*
G01X1454277Y468850D02*
X1455750Y467377D01*
G01X1453800Y467700D02*
X1454600Y466900D01*
G01X1455750Y467377D02*
Y466350D01*
G01X1454600Y466900D02*
Y466100D01*
G01X1465735Y517036D02*
X1460737Y518149D01*
G01X1465668Y518230D02*
X1460738Y519328D01*
G01X1460737Y518149D02*
X1457973Y517537D01*
G01X1460738Y519328D02*
X1457634Y518641D01*
G01X1457973Y517537D02*
X1425380Y504616D01*
G01X1457634Y518641D02*
X1424857Y505646D01*
G01X1425380Y504616D02*
X1410977Y495521D01*
G01X1424857Y505646D02*
X1410034Y496287D01*
G01X1410977Y495521D02*
X1408982Y490168D01*
G01X1410034Y496287D02*
X1407783Y490246D01*
G01X1408982Y490168D02*
X1410772Y482429D01*
G01X1407783Y490246D02*
X1409593Y482423D01*
G01X1410772Y482429D02*
X1409860Y478274D01*
G01X1409593Y482423D02*
X1408647Y478114D01*
G01X1422207Y469728D02*
X1422715Y472294D01*
G01X1421057Y469841D02*
X1421542Y472294D01*
G01X1422715D02*
X1422327Y474256D01*
G01X1421542Y472294D02*
X1421154Y474256D01*
G01X1422327D02*
X1422715Y476218D01*
G01X1421154Y474256D02*
X1421542Y476218D01*
G01X1422715D02*
X1422327Y478180D01*
G01X1421542Y476218D02*
X1421154Y478180D01*
G01X1422327D02*
X1422715Y480142D01*
G01X1421154Y478180D02*
X1421542Y480142D01*
G01X1422715D02*
X1422327Y482104D01*
G01X1421542Y480142D02*
X1421154Y482104D01*
G01X1422327D02*
X1422715Y484066D01*
G01X1421154Y482104D02*
X1421542Y484066D01*
G01X1422715D02*
X1422327Y486028D01*
G01X1421542Y484066D02*
X1421154Y486028D01*
G01X1422327D02*
X1422715Y487990D01*
G01X1421154Y486028D02*
X1421542Y487990D01*
G01X1422715D02*
X1422327Y489952D01*
G01X1421542Y487990D02*
X1421154Y489952D01*
G01X1422327D02*
X1422715Y491914D01*
G01X1421154Y489952D02*
X1421542Y491914D01*
G01X1422715D02*
X1422327Y493876D01*
G01X1421542Y491914D02*
X1421154Y493876D01*
G01X1422327D02*
X1422897Y496757D01*
G01X1421154Y493876D02*
X1421813Y497208D01*
G01X1422897Y496757D02*
X1426694Y502393D01*
G01X1421813Y497208D02*
X1425939Y503331D01*
G01X1426694Y502393D02*
X1431827Y504428D01*
G01X1425939Y503331D02*
X1431498Y505535D01*
G01X1431827Y504428D02*
X1454872Y509120D01*
G01X1431498Y505535D02*
X1447044Y508700D01*
G01X1431827Y504428D02*
X1454872Y509120D01*
G01X1449641Y509229D02*
X1450963Y509498D01*
G01X1431827Y504428D02*
X1454872Y509120D01*
G01X1453560Y510027D02*
X1454883Y510296D01*
G01X1454872Y509120D02*
X1458528Y508304D01*
G01X1454883Y510296D02*
X1458419Y509507D01*
G01X1458528Y508304D02*
X1467319Y512032D01*
G01X1458419Y509507D02*
X1466994Y513144D01*
G01X1465894Y501985D02*
X1454171Y506374D01*
G01X1465997Y503175D02*
X1454265Y507567D01*
G01X1454171Y506374D02*
X1432557Y501974D01*
G01X1454265Y507567D02*
X1432228Y503081D01*
G01X1432557Y501974D02*
X1428329Y500298D01*
G01X1432228Y503081D02*
X1427574Y501236D01*
G01X1428329Y500298D02*
X1425310Y495818D01*
G01X1427574Y501236D02*
X1424226Y496269D01*
G01X1425310Y495818D02*
X1424927Y493876D01*
G01X1424226Y496269D02*
X1423754Y493876D01*
G01X1424927D02*
X1425315Y491914D01*
G01X1423754Y493876D02*
X1424142Y491914D01*
G01X1425315D02*
X1424927Y489952D01*
G01X1424142Y491914D02*
X1423754Y489952D01*
G01X1424927D02*
X1425295Y488090D01*
G01X1423754Y489952D02*
X1424122Y488090D01*
G01X1425295D02*
X1424907Y486128D01*
G01X1424122Y488090D02*
X1423734Y486128D01*
G01X1424907D02*
X1425315Y484066D01*
G01X1423734Y486128D02*
X1424142Y484066D01*
G01X1425315D02*
X1424927Y482104D01*
G01X1424142Y484066D02*
X1423754Y482104D01*
G01X1424927D02*
X1425333Y480053D01*
G01X1423754Y482104D02*
X1424160Y480053D01*
G01X1425333D02*
X1424945Y478090D01*
G01X1424160Y480053D02*
X1423772Y478089D01*
G01X1424945Y478090D02*
X1425315Y476218D01*
G01X1423772Y478089D02*
X1424142Y476218D01*
G01X1425315D02*
X1424927Y474256D01*
G01X1424142Y476218D02*
X1423754Y474256D01*
G01X1424927D02*
X1425333Y472205D01*
G01X1423754Y474256D02*
X1424160Y472205D01*
G01X1425333D02*
X1424707Y469038D01*
G01X1424160Y472205D02*
X1423557Y469151D01*
G01X1427231Y468426D02*
X1427955Y472089D01*
G01X1426081Y468539D02*
X1426782Y472089D01*
G01X1427955D02*
X1427526Y474256D01*
G01X1426782Y472089D02*
X1426353Y474256D01*
G01X1427526D02*
X1427914Y476218D01*
G01X1426353Y474256D02*
X1426741Y476218D01*
G01X1427914D02*
X1427562Y478000D01*
G01X1426741Y476218D02*
X1426389Y478000D01*
G01X1427562D02*
X1427950Y479964D01*
G01X1426389Y478000D02*
X1426777Y479964D01*
G01X1427950D02*
X1427526Y482104D01*
G01X1426777Y479964D02*
X1426353Y482104D01*
G01X1427526D02*
X1427914Y484066D01*
G01X1426353Y482104D02*
X1426741Y484066D01*
G01X1427914D02*
X1427527Y486023D01*
G01X1426741Y484066D02*
X1426354Y486023D01*
G01X1427527D02*
X1427915Y487985D01*
G01X1426354Y486023D02*
X1426742Y487985D01*
G01X1427915D02*
X1427526Y489952D01*
G01X1426742Y487985D02*
X1426353Y489952D01*
G01X1427526D02*
X1427915Y491914D01*
G01X1426353Y489952D02*
X1426742Y491914D01*
G01X1427915D02*
X1427536Y493829D01*
G01X1426742Y491914D02*
X1426363Y493829D01*
G01X1427536D02*
X1427754Y494931D01*
G01X1426363Y493829D02*
X1426670Y495382D01*
G01X1427754Y494931D02*
X1429958Y498200D01*
G01X1426670Y495382D02*
X1429203Y499139D01*
G01X1429958Y498200D02*
X1432756Y499308D01*
G01X1429203Y499139D02*
X1432427Y500415D01*
G01X1432756Y499308D02*
X1454143Y503662D01*
G01X1432427Y500415D02*
X1454237Y504855D01*
G01X1454143Y503662D02*
X1465666Y499347D01*
G01X1454237Y504855D02*
X1465769Y500537D01*
G01X1465668Y518230D02*
X1460738Y519328D01*
G01X1465735Y517036D02*
X1460737Y518149D01*
G01X1460738Y519328D02*
X1457634Y518641D01*
G01X1460737Y518149D02*
X1457973Y517537D01*
G01X1457634Y518641D02*
X1424857Y505646D01*
G01X1457973Y517537D02*
X1425380Y504616D01*
G01X1424857Y505646D02*
X1410034Y496287D01*
G01X1425380Y504616D02*
X1410977Y495521D01*
G01X1410034Y496287D02*
X1407783Y490246D01*
G01X1410977Y495521D02*
X1408982Y490168D01*
G01X1407783Y490246D02*
X1409593Y482423D01*
G01X1408982Y490168D02*
X1410772Y482429D01*
G01X1409593Y482423D02*
X1408647Y478114D01*
G01X1410772Y482429D02*
X1409860Y478274D01*
G01X1421057Y469841D02*
X1421542Y472294D01*
G01X1422207Y469728D02*
X1422715Y472294D01*
G01X1421542D02*
X1421154Y474256D01*
G01X1422715Y472294D02*
X1422327Y474256D01*
G01X1421154D02*
X1421542Y476218D01*
G01X1422327Y474256D02*
X1422715Y476218D01*
G01X1421542D02*
X1421154Y478180D01*
G01X1422715Y476218D02*
X1422327Y478180D01*
G01X1421154D02*
X1421542Y480142D01*
G01X1422327Y478180D02*
X1422715Y480142D01*
G01X1421542D02*
X1421154Y482104D01*
G01X1422715Y480142D02*
X1422327Y482104D01*
G01X1421154D02*
X1421542Y484066D01*
G01X1422327Y482104D02*
X1422715Y484066D01*
G01X1421542D02*
X1421154Y486028D01*
G01X1422715Y484066D02*
X1422327Y486028D01*
G01X1421154D02*
X1421542Y487990D01*
G01X1422327Y486028D02*
X1422715Y487990D01*
G01X1421542D02*
X1421154Y489952D01*
G01X1422715Y487990D02*
X1422327Y489952D01*
G01X1421154D02*
X1421542Y491914D01*
G01X1422327Y489952D02*
X1422715Y491914D01*
G01X1421542D02*
X1421154Y493876D01*
G01X1422715Y491914D02*
X1422327Y493876D01*
G01X1421154D02*
X1421813Y497208D01*
G01X1422327Y493876D02*
X1422897Y496757D01*
G01X1421813Y497208D02*
X1425939Y503331D01*
G01X1422897Y496757D02*
X1426694Y502393D01*
G01X1425939Y503331D02*
X1431498Y505535D01*
G01X1426694Y502393D02*
X1431827Y504428D01*
G01X1431498Y505535D02*
X1447044Y508700D01*
G01X1449641Y509229D02*
X1450963Y509498D01*
G01X1453560Y510027D02*
X1454883Y510296D01*
G01X1431827Y504428D02*
X1454872Y509120D01*
G01X1454883Y510296D02*
X1458419Y509507D01*
G01X1454872Y509120D02*
X1458528Y508304D01*
G01X1458419Y509507D02*
X1466994Y513144D01*
G01X1458528Y508304D02*
X1467319Y512032D01*
G01X1465997Y503175D02*
X1454265Y507567D01*
G01X1465894Y501985D02*
X1454171Y506374D01*
G01X1454265Y507567D02*
X1432228Y503081D01*
G01X1454171Y506374D02*
X1432557Y501974D01*
G01X1432228Y503081D02*
X1427574Y501236D01*
G01X1432557Y501974D02*
X1428329Y500298D01*
G01X1427574Y501236D02*
X1424226Y496269D01*
G01X1428329Y500298D02*
X1425310Y495818D01*
G01X1424226Y496269D02*
X1423754Y493876D01*
G01X1425310Y495818D02*
X1424927Y493876D01*
G01X1423754D02*
X1424142Y491914D01*
G01X1424927Y493876D02*
X1425315Y491914D01*
G01X1424142D02*
X1423754Y489952D01*
G01X1425315Y491914D02*
X1424927Y489952D01*
G01X1423754D02*
X1424122Y488090D01*
G01X1424927Y489952D02*
X1425295Y488090D01*
G01X1424122D02*
X1423734Y486128D01*
G01X1425295Y488090D02*
X1424907Y486128D01*
G01X1423734D02*
X1424142Y484066D01*
G01X1424907Y486128D02*
X1425315Y484066D01*
G01X1424142D02*
X1423754Y482104D01*
G01X1425315Y484066D02*
X1424927Y482104D01*
G01X1423754D02*
X1424160Y480053D01*
G01X1424927Y482104D02*
X1425333Y480053D01*
G01X1424160D02*
X1423772Y478089D01*
G01X1425333Y480053D02*
X1424945Y478090D01*
G01X1423772Y478089D02*
X1424142Y476218D01*
G01X1424945Y478090D02*
X1425315Y476218D01*
G01X1424142D02*
X1423754Y474256D01*
G01X1425315Y476218D02*
X1424927Y474256D01*
G01X1423754D02*
X1424160Y472205D01*
G01X1424927Y474256D02*
X1425333Y472205D01*
G01X1424160D02*
X1423557Y469151D01*
G01X1425333Y472205D02*
X1424707Y469038D01*
G01X1426081Y468539D02*
X1426782Y472089D01*
G01X1427231Y468426D02*
X1427955Y472089D01*
G01X1426782D02*
X1426353Y474256D01*
G01X1427955Y472089D02*
X1427526Y474256D01*
G01X1426353D02*
X1426741Y476218D01*
G01X1427526Y474256D02*
X1427914Y476218D01*
G01X1426741D02*
X1426389Y478000D01*
G01X1427914Y476218D02*
X1427562Y478000D01*
G01X1426389D02*
X1426777Y479964D01*
G01X1427562Y478000D02*
X1427950Y479964D01*
G01X1426777D02*
X1426353Y482104D01*
G01X1427950Y479964D02*
X1427526Y482104D01*
G01X1426353D02*
X1426741Y484066D01*
G01X1427526Y482104D02*
X1427914Y484066D01*
G01X1426741D02*
X1426354Y486023D01*
G01X1427914Y484066D02*
X1427527Y486023D01*
G01X1426354D02*
X1426742Y487985D01*
G01X1427527Y486023D02*
X1427915Y487985D01*
G01X1426742D02*
X1426353Y489952D01*
G01X1427915Y487985D02*
X1427526Y489952D01*
G01X1426353D02*
X1426742Y491914D01*
G01X1427526Y489952D02*
X1427915Y491914D01*
G01X1426742D02*
X1426363Y493829D01*
G01X1427915Y491914D02*
X1427536Y493829D01*
G01X1426363D02*
X1426670Y495382D01*
G01X1427536Y493829D02*
X1427754Y494931D01*
G01X1426670Y495382D02*
X1429203Y499139D01*
G01X1427754Y494931D02*
X1429958Y498200D01*
G01X1429203Y499139D02*
X1432427Y500415D01*
G01X1429958Y498200D02*
X1432756Y499308D01*
G01X1432427Y500415D02*
X1454237Y504855D01*
G01X1432756Y499308D02*
X1454143Y503662D01*
G01X1454237Y504855D02*
X1465769Y500537D01*
G01X1454143Y503662D02*
X1465666Y499347D01*
G01X1416994Y527400D02*
X1434484D01*
G01X1416517Y528550D02*
X1434007D01*
G01X1434484Y527400D02*
X1436905Y529821D01*
G01X1434007Y528550D02*
X1435755Y530298D01*
G01X1436905Y529821D02*
Y546853D01*
G01X1435755Y530298D02*
Y547330D01*
G01X1436905Y546853D02*
X1441359Y551307D01*
G01X1435755Y547330D02*
X1440882Y552457D01*
G01X1441359Y551307D02*
X1457392D01*
G01X1440882Y552457D02*
X1457869D01*
G01X1457392Y551307D02*
X1459194Y549505D01*
G01X1457869Y552457D02*
X1459671Y550655D01*
G01X1459194Y549505D02*
X1513660D01*
G01X1459671Y550655D02*
X1514137D01*
G01X1416517Y528550D02*
X1434007D01*
G01X1416994Y527400D02*
X1434484D01*
G01X1434007Y528550D02*
X1435755Y530298D01*
G01X1434484Y527400D02*
X1436905Y529821D01*
G01X1435755Y530298D02*
Y547330D01*
G01X1436905Y529821D02*
Y546853D01*
G01X1435755Y547330D02*
X1440882Y552457D01*
G01X1436905Y546853D02*
X1441359Y551307D01*
G01X1440882Y552457D02*
X1457869D01*
G01X1441359Y551307D02*
X1457392D01*
G01X1457869Y552457D02*
X1459671Y550655D01*
G01X1457392Y551307D02*
X1459194Y549505D01*
G01X1459671Y550655D02*
X1514137D01*
G01X1459194Y549505D02*
X1513660D01*
G01X1445579Y529985D02*
X1448880Y537042D01*
G01X1446570Y529389D02*
X1449801Y536294D01*
G01X1448880Y537042D02*
X1451640Y539113D01*
G01X1449801Y536294D02*
X1452128Y538041D01*
G01X1451640Y539113D02*
X1454981Y539826D01*
G01X1452128Y538041D02*
X1454880Y538628D01*
G01X1454981Y539826D02*
X1460132Y537782D01*
G01X1454880Y538628D02*
X1460029Y536585D01*
G01X1460132Y537782D02*
X1467195Y539263D01*
G01X1460029Y536585D02*
X1467607Y538174D01*
G01X1468521Y535761D02*
X1459777Y533926D01*
G01X1468109Y536850D02*
X1459880Y535123D01*
G01X1459777Y533926D02*
X1454633Y535967D01*
G01X1459880Y535123D02*
X1454734Y537165D01*
G01X1454633Y535967D02*
X1453210Y535664D01*
G01X1454734Y537165D02*
X1452722Y536736D01*
G01X1453210Y535664D02*
X1451842Y534636D01*
G01X1452722Y536736D02*
X1450921Y535384D01*
G01X1451842Y534636D02*
X1448768Y528066D01*
G01X1450921Y535384D02*
X1447774Y528658D01*
G01X1446570Y529389D02*
X1449801Y536294D01*
G01X1445579Y529985D02*
X1448880Y537042D01*
G01X1449801Y536294D02*
X1452128Y538041D01*
G01X1448880Y537042D02*
X1451640Y539113D01*
G01X1452128Y538041D02*
X1454880Y538628D01*
G01X1451640Y539113D02*
X1454981Y539826D01*
G01X1454880Y538628D02*
X1460029Y536585D01*
G01X1454981Y539826D02*
X1460132Y537782D01*
G01X1460029Y536585D02*
X1467607Y538174D01*
G01X1460132Y537782D02*
X1467195Y539263D01*
G01X1468109Y536850D02*
X1459880Y535123D01*
G01X1468521Y535761D02*
X1459777Y533926D01*
G01X1459880Y535123D02*
X1454734Y537165D01*
G01X1459777Y533926D02*
X1454633Y535967D01*
G01X1454734Y537165D02*
X1452722Y536736D01*
G01X1454633Y535967D02*
X1453210Y535664D01*
G01X1452722Y536736D02*
X1450921Y535384D01*
G01X1453210Y535664D02*
X1451842Y534636D01*
G01X1450921Y535384D02*
X1447774Y528658D01*
G01X1451842Y534636D02*
X1448768Y528066D01*
G01X1465761Y643618D02*
X1464850Y644922D01*
G01D02*
X1466328Y653297D01*
G01X1463356Y654307D02*
X1461689Y644835D01*
G01X1464406Y653637D02*
X1462740Y644164D01*
G01X1461689Y644835D02*
X1461165Y644470D01*
G01D02*
X1460133Y644650D01*
G01X1462740Y644164D02*
X1461434Y643255D01*
G01X1461165Y644470D02*
X1460133Y644650D01*
G01X1461434Y643255D02*
X1459463Y643599D01*
G01X1460133Y644650D02*
X1459768Y645174D01*
G01X1459463Y643599D02*
X1458552Y644906D01*
G01X1459768Y645174D02*
X1461254Y653599D01*
G01X1458552Y644906D02*
X1460038Y653330D01*
G01X1457066Y654340D02*
X1455400Y644883D01*
G01X1458116Y653670D02*
X1456450Y644214D01*
G01X1455400Y644883D02*
X1454840Y644491D01*
G01D02*
X1453872Y644661D01*
G01X1456450Y644214D02*
X1455110Y643275D01*
G01X1454840Y644491D02*
X1453872Y644661D01*
G01X1455110Y643275D02*
X1453202Y643610D01*
G01X1453872Y644661D02*
X1453481Y645221D01*
G01X1453202Y643610D02*
X1452265Y644952D01*
G01X1453481Y645221D02*
X1454956Y653594D01*
G01X1452265Y644952D02*
X1453741Y653326D01*
G01X1450768Y654332D02*
X1449115Y644987D01*
G01X1451818Y653663D02*
X1450165Y644317D01*
G01X1449115Y644987D02*
X1448594Y644622D01*
G01D02*
X1447560Y644804D01*
G01X1450165Y644317D02*
X1448864Y643406D01*
G01X1448594Y644622D02*
X1447560Y644804D01*
G01X1448864Y643406D02*
X1446890Y643753D01*
G01X1447560Y644804D02*
X1447195Y645326D01*
G01X1446890Y643753D02*
X1445979Y645057D01*
G01X1447195Y645326D02*
X1448628Y653442D01*
G01X1445979Y645057D02*
X1447412Y653172D01*
G01X1444442Y654185D02*
X1442808Y644926D01*
G01X1445492Y653516D02*
X1443859Y644257D01*
G01X1442808Y644926D02*
X1442287Y644561D01*
G01D02*
X1441253Y644743D01*
G01X1443859Y644257D02*
X1442557Y643345D01*
G01X1442287Y644561D02*
X1441253Y644743D01*
G01X1442557Y643345D02*
X1440583Y643692D01*
G01X1441253Y644743D02*
X1440888Y645265D01*
G01X1440583Y643692D02*
X1439672Y644996D01*
G01X1440888Y645265D02*
X1442321Y653381D01*
G01X1439672Y644996D02*
X1441105Y653111D01*
G01X1438135Y654124D02*
X1436521Y644979D01*
G01X1439185Y653455D02*
X1437572Y644310D01*
G01X1436521Y644979D02*
X1436000Y644614D01*
G01D02*
X1434966Y644796D01*
G01X1437572Y644310D02*
X1436270Y643398D01*
G01X1436000Y644614D02*
X1434966Y644796D01*
G01X1436270Y643398D02*
X1434296Y643745D01*
G01X1434966Y644796D02*
X1434601Y645318D01*
G01X1434296Y643745D02*
X1433385Y645049D01*
G01X1434601Y645318D02*
X1436014Y653320D01*
G01X1433385Y645049D02*
X1434798Y653050D01*
G01X1431828Y654063D02*
X1430212Y644901D01*
G01X1432878Y653394D02*
X1431262Y644232D01*
G01X1430212Y644901D02*
X1429690Y644536D01*
G01D02*
X1428657Y644717D01*
G01X1431262Y644232D02*
X1429960Y643320D01*
G01X1429690Y644536D02*
X1428657Y644717D01*
G01X1429960Y643320D02*
X1427986Y643667D01*
G01X1428657Y644717D02*
X1428292Y645240D01*
G01X1427986Y643667D02*
X1427075Y644970D01*
G01X1428292Y645240D02*
X1429707Y653259D01*
G01X1427075Y644970D02*
X1428491Y652989D01*
G01X1425521Y654002D02*
X1423905Y644840D01*
G01X1426571Y653333D02*
X1424955Y644171D01*
G01X1423905Y644840D02*
X1423381Y644473D01*
G01D02*
X1422349Y644654D01*
G01X1424955Y644171D02*
X1423651Y643257D01*
G01X1423381Y644473D02*
X1422349Y644654D01*
G01X1423651Y643257D02*
X1421677Y643605D01*
G01X1422349Y644654D02*
X1421984Y645177D01*
G01X1421677Y643605D02*
X1420768Y644909D01*
G01X1421984Y645177D02*
X1423408Y653244D01*
G01X1420768Y644909D02*
X1422192Y652975D01*
G01X1419220Y653983D02*
X1417612Y644854D01*
G01X1420270Y653313D02*
X1418663Y644184D01*
G01X1417612Y644854D02*
X1417090Y644489D01*
G01D02*
X1416057Y644670D01*
G01X1418663Y644184D02*
X1417360Y643274D01*
G01X1417090Y644489D02*
X1416057Y644670D01*
G01X1417360Y643274D02*
X1415388Y643619D01*
G01X1416057Y644670D02*
X1415692Y645192D01*
G01X1415388Y643619D02*
X1414476Y644923D01*
G01X1415692Y645192D02*
X1417112Y653243D01*
G01X1414476Y644923D02*
X1415896Y652974D01*
G01X1412924Y653982D02*
X1411310Y644818D01*
G01X1413975Y653312D02*
X1412360Y644148D01*
G01X1411310Y644818D02*
X1410788Y644454D01*
G01D02*
X1409755Y644635D01*
G01X1412360Y644148D02*
X1411057Y643239D01*
G01X1410788Y644454D02*
X1409755Y644635D01*
G01X1411057Y643239D02*
X1409088Y643584D01*
G01X1409755Y644635D02*
X1409389Y645155D01*
G01X1409088Y643584D02*
X1408173Y644884D01*
G01X1409389Y645155D02*
X1410821Y653276D01*
G01X1408173Y644884D02*
X1409605Y653007D01*
G01X1406637Y654015D02*
X1405015Y644821D01*
G01X1407687Y653346D02*
X1406066Y644153D01*
G01X1405015Y644821D02*
X1404491Y644453D01*
G01X1406066Y644153D02*
X1404762Y643237D01*
G01X1465761Y643618D02*
X1464850Y644922D01*
G01D02*
X1466328Y653297D01*
G01X1464406Y653637D02*
X1462740Y644164D01*
G01X1463356Y654307D02*
X1461689Y644835D01*
G01X1462740Y644164D02*
X1461434Y643255D01*
G01X1461689Y644835D02*
X1461165Y644470D01*
G01X1462740Y644164D02*
X1461434Y643255D01*
G01D02*
X1459463Y643599D01*
G01X1461165Y644470D02*
X1460133Y644650D01*
G01X1459463Y643599D02*
X1458552Y644906D01*
G01X1460133Y644650D02*
X1459768Y645174D01*
G01X1458552Y644906D02*
X1460038Y653330D01*
G01X1459768Y645174D02*
X1461254Y653599D01*
G01X1458116Y653670D02*
X1456450Y644214D01*
G01X1457066Y654340D02*
X1455400Y644883D01*
G01X1456450Y644214D02*
X1455110Y643275D01*
G01X1455400Y644883D02*
X1454840Y644491D01*
G01X1456450Y644214D02*
X1455110Y643275D01*
G01D02*
X1453202Y643610D01*
G01X1454840Y644491D02*
X1453872Y644661D01*
G01X1453202Y643610D02*
X1452265Y644952D01*
G01X1453872Y644661D02*
X1453481Y645221D01*
G01X1452265Y644952D02*
X1453741Y653326D01*
G01X1453481Y645221D02*
X1454956Y653594D01*
G01X1451818Y653663D02*
X1450165Y644317D01*
G01X1450768Y654332D02*
X1449115Y644987D01*
G01X1450165Y644317D02*
X1448864Y643406D01*
G01X1449115Y644987D02*
X1448594Y644622D01*
G01X1450165Y644317D02*
X1448864Y643406D01*
G01D02*
X1446890Y643753D01*
G01X1448594Y644622D02*
X1447560Y644804D01*
G01X1446890Y643753D02*
X1445979Y645057D01*
G01X1447560Y644804D02*
X1447195Y645326D01*
G01X1445979Y645057D02*
X1447412Y653172D01*
G01X1447195Y645326D02*
X1448628Y653442D01*
G01X1445492Y653516D02*
X1443859Y644257D01*
G01X1444442Y654185D02*
X1442808Y644926D01*
G01X1443859Y644257D02*
X1442557Y643345D01*
G01X1442808Y644926D02*
X1442287Y644561D01*
G01X1443859Y644257D02*
X1442557Y643345D01*
G01D02*
X1440583Y643692D01*
G01X1442287Y644561D02*
X1441253Y644743D01*
G01X1440583Y643692D02*
X1439672Y644996D01*
G01X1441253Y644743D02*
X1440888Y645265D01*
G01X1439672Y644996D02*
X1441105Y653111D01*
G01X1440888Y645265D02*
X1442321Y653381D01*
G01X1439185Y653455D02*
X1437572Y644310D01*
G01X1438135Y654124D02*
X1436521Y644979D01*
G01X1437572Y644310D02*
X1436270Y643398D01*
G01X1436521Y644979D02*
X1436000Y644614D01*
G01X1437572Y644310D02*
X1436270Y643398D01*
G01D02*
X1434296Y643745D01*
G01X1436000Y644614D02*
X1434966Y644796D01*
G01X1434296Y643745D02*
X1433385Y645049D01*
G01X1434966Y644796D02*
X1434601Y645318D01*
G01X1433385Y645049D02*
X1434798Y653050D01*
G01X1434601Y645318D02*
X1436014Y653320D01*
G01X1432878Y653394D02*
X1431262Y644232D01*
G01X1431828Y654063D02*
X1430212Y644901D01*
G01X1431262Y644232D02*
X1429960Y643320D01*
G01X1430212Y644901D02*
X1429690Y644536D01*
G01X1431262Y644232D02*
X1429960Y643320D01*
G01D02*
X1427986Y643667D01*
G01X1429690Y644536D02*
X1428657Y644717D01*
G01X1427986Y643667D02*
X1427075Y644970D01*
G01X1428657Y644717D02*
X1428292Y645240D01*
G01X1427075Y644970D02*
X1428491Y652989D01*
G01X1428292Y645240D02*
X1429707Y653259D01*
G01X1426571Y653333D02*
X1424955Y644171D01*
G01X1425521Y654002D02*
X1423905Y644840D01*
G01X1424955Y644171D02*
X1423651Y643257D01*
G01X1423905Y644840D02*
X1423381Y644473D01*
G01X1424955Y644171D02*
X1423651Y643257D01*
G01D02*
X1421677Y643605D01*
G01X1423381Y644473D02*
X1422349Y644654D01*
G01X1421677Y643605D02*
X1420768Y644909D01*
G01X1422349Y644654D02*
X1421984Y645177D01*
G01X1420768Y644909D02*
X1422192Y652975D01*
G01X1421984Y645177D02*
X1423408Y653244D01*
G01X1420270Y653313D02*
X1418663Y644184D01*
G01X1419220Y653983D02*
X1417612Y644854D01*
G01X1418663Y644184D02*
X1417360Y643274D01*
G01X1417612Y644854D02*
X1417090Y644489D01*
G01X1418663Y644184D02*
X1417360Y643274D01*
G01D02*
X1415388Y643619D01*
G01X1417090Y644489D02*
X1416057Y644670D01*
G01X1415388Y643619D02*
X1414476Y644923D01*
G01X1416057Y644670D02*
X1415692Y645192D01*
G01X1414476Y644923D02*
X1415896Y652974D01*
G01X1415692Y645192D02*
X1417112Y653243D01*
G01X1413975Y653312D02*
X1412360Y644148D01*
G01X1412924Y653982D02*
X1411310Y644818D01*
G01X1412360Y644148D02*
X1411057Y643239D01*
G01X1411310Y644818D02*
X1410788Y644454D01*
G01X1412360Y644148D02*
X1411057Y643239D01*
G01D02*
X1409088Y643584D01*
G01X1410788Y644454D02*
X1409755Y644635D01*
G01X1409088Y643584D02*
X1408173Y644884D01*
G01X1409755Y644635D02*
X1409389Y645155D01*
G01X1408173Y644884D02*
X1409605Y653007D01*
G01X1409389Y645155D02*
X1410821Y653276D01*
G01X1407687Y653346D02*
X1406066Y644153D01*
G01X1406637Y654015D02*
X1405015Y644821D01*
G01X1406066Y644153D02*
X1404762Y643237D01*
G01X1405015Y644821D02*
X1404491Y644453D01*
G01X1406066Y644153D02*
X1404762Y643237D01*
G01X1466633Y654870D02*
X1464659Y655216D01*
G01D02*
X1463356Y654307D01*
G01X1465963Y653819D02*
X1464928Y654001D01*
G01X1464659Y655216D02*
X1463356Y654307D01*
G01X1464928Y654001D02*
X1464406Y653637D01*
G01X1461254Y653599D02*
X1460343Y654903D01*
G01X1460038Y653330D02*
X1459673Y653852D01*
G01X1460343Y654903D02*
X1458369Y655249D01*
G01D02*
X1457066Y654340D01*
G01X1459673Y653852D02*
X1458638Y654034D01*
G01X1458369Y655249D02*
X1457066Y654340D01*
G01X1458638Y654034D02*
X1458116Y653670D01*
G01X1454956Y653594D02*
X1454048Y654899D01*
G01X1453741Y653326D02*
X1453377Y653849D01*
G01X1454048Y654899D02*
X1452073Y655247D01*
G01D02*
X1450768Y654332D01*
G01X1453377Y653849D02*
X1452343Y654031D01*
G01X1452073Y655247D02*
X1450768Y654332D01*
G01X1452343Y654031D02*
X1451818Y653663D01*
G01X1448628Y653442D02*
X1447715Y654746D01*
G01X1447412Y653172D02*
X1447045Y653696D01*
G01X1447715Y654746D02*
X1445742Y655095D01*
G01D02*
X1444442Y654185D01*
G01X1447045Y653696D02*
X1446011Y653879D01*
G01X1445742Y655095D02*
X1444442Y654185D01*
G01X1446011Y653879D02*
X1445492Y653516D01*
G01X1442321Y653381D02*
X1441408Y654685D01*
G01X1441105Y653111D02*
X1440738Y653635D01*
G01X1441408Y654685D02*
X1439435Y655034D01*
G01D02*
X1438135Y654124D01*
G01X1440738Y653635D02*
X1439704Y653818D01*
G01X1439435Y655034D02*
X1438135Y654124D01*
G01X1439704Y653818D02*
X1439185Y653455D01*
G01X1436014Y653320D02*
X1435101Y654624D01*
G01X1434798Y653050D02*
X1434431Y653574D01*
G01X1435101Y654624D02*
X1433128Y654973D01*
G01D02*
X1431828Y654063D01*
G01X1434431Y653574D02*
X1433397Y653757D01*
G01X1433128Y654973D02*
X1431828Y654063D01*
G01X1433397Y653757D02*
X1432878Y653394D01*
G01X1429707Y653259D02*
X1428794Y654563D01*
G01X1428491Y652989D02*
X1428124Y653513D01*
G01X1428794Y654563D02*
X1426821Y654912D01*
G01D02*
X1425521Y654002D01*
G01X1428124Y653513D02*
X1427090Y653696D01*
G01X1426821Y654912D02*
X1425521Y654002D01*
G01X1427090Y653696D02*
X1426571Y653333D01*
G01X1423408Y653244D02*
X1422498Y654547D01*
G01X1422192Y652975D02*
X1421828Y653496D01*
G01X1422498Y654547D02*
X1420524Y654893D01*
G01D02*
X1419220Y653983D01*
G01X1421828Y653496D02*
X1420793Y653678D01*
G01X1420524Y654893D02*
X1419220Y653983D01*
G01X1420793Y653678D02*
X1420270Y653313D01*
G01X1417112Y653243D02*
X1416202Y654546D01*
G01X1415896Y652974D02*
X1415532Y653495D01*
G01X1416202Y654546D02*
X1414228Y654892D01*
G01D02*
X1412924Y653982D01*
G01X1415532Y653495D02*
X1414498Y653677D01*
G01X1414228Y654892D02*
X1412924Y653982D01*
G01X1414498Y653677D02*
X1413975Y653312D01*
G01X1410821Y653276D02*
X1409911Y654579D01*
G01X1409605Y653007D02*
X1409241Y653528D01*
G01X1409911Y654579D02*
X1407937Y654926D01*
G01D02*
X1406637Y654015D01*
G01X1409241Y653528D02*
X1408207Y653710D01*
G01X1407937Y654926D02*
X1406637Y654015D01*
G01X1408207Y653710D02*
X1407687Y653346D01*
G01X1465963Y653819D02*
X1464928Y654001D01*
G01X1466633Y654870D02*
X1464659Y655216D01*
G01X1465963Y653819D02*
X1464928Y654001D01*
G01D02*
X1464406Y653637D01*
G01X1464659Y655216D02*
X1463356Y654307D01*
G01X1460038Y653330D02*
X1459673Y653852D01*
G01X1461254Y653599D02*
X1460343Y654903D01*
G01X1459673Y653852D02*
X1458638Y654034D01*
G01X1460343Y654903D02*
X1458369Y655249D01*
G01X1459673Y653852D02*
X1458638Y654034D01*
G01D02*
X1458116Y653670D01*
G01X1458369Y655249D02*
X1457066Y654340D01*
G01X1453741Y653326D02*
X1453377Y653849D01*
G01X1454956Y653594D02*
X1454048Y654899D01*
G01X1453377Y653849D02*
X1452343Y654031D01*
G01X1454048Y654899D02*
X1452073Y655247D01*
G01X1453377Y653849D02*
X1452343Y654031D01*
G01D02*
X1451818Y653663D01*
G01X1452073Y655247D02*
X1450768Y654332D01*
G01X1447412Y653172D02*
X1447045Y653696D01*
G01X1448628Y653442D02*
X1447715Y654746D01*
G01X1447045Y653696D02*
X1446011Y653879D01*
G01X1447715Y654746D02*
X1445742Y655095D01*
G01X1447045Y653696D02*
X1446011Y653879D01*
G01D02*
X1445492Y653516D01*
G01X1445742Y655095D02*
X1444442Y654185D01*
G01X1441105Y653111D02*
X1440738Y653635D01*
G01X1442321Y653381D02*
X1441408Y654685D01*
G01X1440738Y653635D02*
X1439704Y653818D01*
G01X1441408Y654685D02*
X1439435Y655034D01*
G01X1440738Y653635D02*
X1439704Y653818D01*
G01D02*
X1439185Y653455D01*
G01X1439435Y655034D02*
X1438135Y654124D01*
G01X1434798Y653050D02*
X1434431Y653574D01*
G01X1436014Y653320D02*
X1435101Y654624D01*
G01X1434431Y653574D02*
X1433397Y653757D01*
G01X1435101Y654624D02*
X1433128Y654973D01*
G01X1434431Y653574D02*
X1433397Y653757D01*
G01D02*
X1432878Y653394D01*
G01X1433128Y654973D02*
X1431828Y654063D01*
G01X1428491Y652989D02*
X1428124Y653513D01*
G01X1429707Y653259D02*
X1428794Y654563D01*
G01X1428124Y653513D02*
X1427090Y653696D01*
G01X1428794Y654563D02*
X1426821Y654912D01*
G01X1428124Y653513D02*
X1427090Y653696D01*
G01D02*
X1426571Y653333D01*
G01X1426821Y654912D02*
X1425521Y654002D01*
G01X1422192Y652975D02*
X1421828Y653496D01*
G01X1423408Y653244D02*
X1422498Y654547D01*
G01X1421828Y653496D02*
X1420793Y653678D01*
G01X1422498Y654547D02*
X1420524Y654893D01*
G01X1421828Y653496D02*
X1420793Y653678D01*
G01D02*
X1420270Y653313D01*
G01X1420524Y654893D02*
X1419220Y653983D01*
G01X1415896Y652974D02*
X1415532Y653495D01*
G01X1417112Y653243D02*
X1416202Y654546D01*
G01X1415532Y653495D02*
X1414498Y653677D01*
G01X1416202Y654546D02*
X1414228Y654892D01*
G01X1415532Y653495D02*
X1414498Y653677D01*
G01D02*
X1413975Y653312D01*
G01X1414228Y654892D02*
X1412924Y653982D01*
G01X1409605Y653007D02*
X1409241Y653528D01*
G01X1410821Y653276D02*
X1409911Y654579D01*
G01X1409241Y653528D02*
X1408207Y653710D01*
G01X1409911Y654579D02*
X1407937Y654926D01*
G01X1409241Y653528D02*
X1408207Y653710D01*
G01D02*
X1407687Y653346D01*
G01X1407937Y654926D02*
X1406637Y654015D01*
G01X1471313Y6039D02*
Y18403D01*
G01X1472463Y6012D02*
Y18880D01*
G01X1471313Y18403D02*
X1470358Y19358D01*
G01X1468484Y21231D02*
X1467530Y22186D01*
G01X1517272Y33276D02*
X1519781Y32744D01*
G01D02*
X1534439Y35854D01*
G01X1494685Y32349D02*
X1495470Y31251D01*
G01X1497010Y29094D02*
X1499468Y25654D01*
G01X1491181Y39234D02*
X1500141Y26691D01*
G01X1499468Y25654D02*
X1506862Y24152D01*
G01X1500141Y26691D02*
X1506642Y25371D01*
G01X1506862Y24152D02*
X1514071Y28645D01*
G01X1506642Y25371D02*
X1513634Y29728D01*
G01X1514071Y28645D02*
X1516032Y29061D01*
G01X1518624Y29611D02*
X1534763Y33038D01*
G01X1513634Y29728D02*
X1534835Y34229D01*
G01X1519631Y20075D02*
X1529145Y18054D01*
G01Y16878D02*
X1519631Y18899D01*
G01X1504728Y16907D02*
X1519631Y20075D01*
G01Y18899D02*
X1504605Y15705D01*
G01X1499915Y19015D02*
X1504728Y16907D01*
G01X1504605Y15705D02*
X1499201Y18071D01*
G01X1467553Y58325D02*
X1499915Y19015D01*
G01X1499201Y18071D02*
X1495801Y22201D01*
G01X1467553Y58325D02*
X1499915Y19015D01*
G01X1494116Y24247D02*
X1493258Y25290D01*
G01X1467553Y58325D02*
X1499915Y19015D01*
G01X1491574Y27336D02*
X1490716Y28378D01*
G01X1467553Y58325D02*
X1499915Y19015D01*
G01X1489032Y30424D02*
X1466494Y57802D01*
G01X1529143Y14169D02*
X1519281Y16264D01*
G01X1529143Y15345D02*
X1519281Y17440D01*
G01Y16264D02*
X1515832Y15532D01*
G01X1513240Y14982D02*
X1511920Y14701D01*
G01X1509327Y14151D02*
X1508007Y13871D01*
G01X1505415Y13320D02*
X1504094Y13040D01*
G01X1519281Y17440D02*
X1504217Y14242D01*
G01X1504094Y13040D02*
X1485997Y20968D01*
G01X1504217Y14242D02*
X1486748Y21895D01*
G01X1485997Y20968D02*
X1472559Y39731D01*
G01X1486748Y21895D02*
X1473397Y40537D01*
G01X1467636Y33385D02*
X1470491Y30531D01*
G01X1468617Y34032D02*
X1470968Y31681D01*
G01X1470491Y30531D02*
X1472324D01*
G01X1470968Y31681D02*
X1472801D01*
G01X1470491Y30531D02*
X1472324D01*
G01D02*
X1473279Y29576D01*
G01X1474233Y27703D02*
X1475152D01*
G01D02*
X1476107Y26748D01*
G01X1477062Y24874D02*
X1477981D01*
G01D02*
X1478935Y23920D01*
G01X1479890Y22046D02*
X1480809D01*
G01D02*
X1490695Y12160D01*
G01X1472801Y31681D02*
X1491845Y12637D01*
G01X1490695Y12160D02*
Y7359D01*
G01X1491845Y12637D02*
Y7359D01*
G01X1470701Y23893D02*
X1471620D01*
G01D02*
X1472575Y22938D01*
G01X1473529Y21064D02*
X1474449D01*
G01D02*
X1475403Y20110D01*
G01X1476358Y18236D02*
X1477277D01*
G01D02*
X1478232Y17281D01*
G01X1479186Y15408D02*
X1480105D01*
G01D02*
X1481060Y14453D01*
G01X1466132Y31008D02*
X1482210Y14930D01*
G01X1481060Y14453D02*
Y12013D01*
G01X1482210Y14930D02*
Y12013D01*
G01X1472463Y6012D02*
Y18880D01*
G01X1471313Y6039D02*
Y18403D01*
G01D02*
X1470358Y19358D01*
G01X1468484Y21231D02*
X1467530Y22186D01*
G01X1517272Y33276D02*
X1519781Y32744D01*
G01D02*
X1534439Y35854D01*
G01X1491181Y39234D02*
X1500141Y26691D01*
G01X1491181Y39234D02*
X1500141Y26691D01*
G01X1494685Y32349D02*
X1495470Y31251D01*
G01X1491181Y39234D02*
X1500141Y26691D01*
G01X1497010Y29094D02*
X1499468Y25654D01*
G01X1500141Y26691D02*
X1506642Y25371D01*
G01X1499468Y25654D02*
X1506862Y24152D01*
G01X1506642Y25371D02*
X1513634Y29728D01*
G01X1506862Y24152D02*
X1514071Y28645D01*
G01X1513634Y29728D02*
X1534835Y34229D01*
G01X1514071Y28645D02*
X1516032Y29061D01*
G01X1513634Y29728D02*
X1534835Y34229D01*
G01X1518624Y29611D02*
X1534763Y33038D01*
G01X1499201Y18071D02*
X1495801Y22201D01*
G01X1494116Y24247D02*
X1493258Y25290D01*
G01X1491574Y27336D02*
X1490716Y28378D01*
G01X1489032Y30424D02*
X1466494Y57802D01*
G01X1467553Y58325D02*
X1499915Y19015D01*
G01X1504605Y15705D02*
X1499201Y18071D01*
G01X1499915Y19015D02*
X1504728Y16907D01*
G01X1519631Y18899D02*
X1504605Y15705D01*
G01X1504728Y16907D02*
X1519631Y20075D01*
G01X1529145Y16878D02*
X1519631Y18899D01*
G01Y20075D02*
X1529145Y18054D01*
G01X1529143Y15345D02*
X1519281Y17440D01*
G01X1529143Y14169D02*
X1519281Y16264D01*
G01Y17440D02*
X1504217Y14242D01*
G01X1519281Y16264D02*
X1515832Y15532D01*
G01X1519281Y17440D02*
X1504217Y14242D01*
G01X1513240Y14982D02*
X1511920Y14701D01*
G01X1519281Y17440D02*
X1504217Y14242D01*
G01X1509327Y14151D02*
X1508007Y13871D01*
G01X1519281Y17440D02*
X1504217Y14242D01*
G01X1505415Y13320D02*
X1504094Y13040D01*
G01X1504217Y14242D02*
X1486748Y21895D01*
G01X1504094Y13040D02*
X1485997Y20968D01*
G01X1486748Y21895D02*
X1473397Y40537D01*
G01X1485997Y20968D02*
X1472559Y39731D01*
G01X1468617Y34032D02*
X1470968Y31681D01*
G01X1467636Y33385D02*
X1470491Y30531D01*
G01X1470968Y31681D02*
X1472801D01*
G01D02*
X1491845Y12637D01*
G01X1470491Y30531D02*
X1472324D01*
G01X1472801Y31681D02*
X1491845Y12637D01*
G01X1472324Y30531D02*
X1473279Y29576D01*
G01X1472801Y31681D02*
X1491845Y12637D01*
G01X1474233Y27703D02*
X1475152D01*
G01X1472801Y31681D02*
X1491845Y12637D01*
G01X1475152Y27703D02*
X1476107Y26748D01*
G01X1472801Y31681D02*
X1491845Y12637D01*
G01X1477062Y24874D02*
X1477981D01*
G01X1472801Y31681D02*
X1491845Y12637D01*
G01X1477981Y24874D02*
X1478935Y23920D01*
G01X1472801Y31681D02*
X1491845Y12637D01*
G01X1479890Y22046D02*
X1480809D01*
G01X1472801Y31681D02*
X1491845Y12637D01*
G01X1480809Y22046D02*
X1490695Y12160D01*
G01X1491845Y12637D02*
Y7359D01*
G01X1490695Y12160D02*
Y7359D01*
G01X1466132Y31008D02*
X1482210Y14930D01*
G01X1466132Y31008D02*
X1482210Y14930D01*
G01X1470701Y23893D02*
X1471620D01*
G01X1466132Y31008D02*
X1482210Y14930D01*
G01X1471620Y23893D02*
X1472575Y22938D01*
G01X1466132Y31008D02*
X1482210Y14930D01*
G01X1473529Y21064D02*
X1474449D01*
G01X1466132Y31008D02*
X1482210Y14930D01*
G01X1474449Y21064D02*
X1475403Y20110D01*
G01X1466132Y31008D02*
X1482210Y14930D01*
G01X1476358Y18236D02*
X1477277D01*
G01X1466132Y31008D02*
X1482210Y14930D01*
G01X1477277Y18236D02*
X1478232Y17281D01*
G01X1466132Y31008D02*
X1482210Y14930D01*
G01X1479186Y15408D02*
X1480105D01*
G01X1466132Y31008D02*
X1482210Y14930D01*
G01X1480105Y15408D02*
X1481060Y14453D01*
G01X1482210Y14930D02*
Y12013D01*
G01X1481060Y14453D02*
Y12013D01*
G01X1470362Y100277D02*
X1478787Y64154D01*
G01X1471366Y101040D02*
X1479846Y64677D01*
G01X1478787Y64154D02*
X1489903Y50649D01*
G01X1479846Y64677D02*
X1490647Y51555D01*
G01X1489903Y50649D02*
X1500469Y44978D01*
G01X1490647Y51555D02*
X1500869Y46070D01*
G01X1500469Y44978D02*
X1514744Y41948D01*
G01X1500869Y46070D02*
X1514746Y43124D01*
G01X1514744Y41948D02*
X1516427Y42300D01*
G01X1519021Y42842D02*
X1520343Y43118D01*
G01X1522937Y43660D02*
X1524258Y43936D01*
G01X1526852Y44478D02*
X1536486Y46490D01*
G01X1514746Y43124D02*
X1536478Y47664D01*
G01X1468071Y98437D02*
X1476347Y62943D01*
G01X1469074Y99201D02*
X1477407Y63467D01*
G01X1476347Y62943D02*
X1488185Y48564D01*
G01X1477407Y63467D02*
X1488929Y49470D01*
G01X1488185Y48564D02*
X1499537Y42471D01*
G01X1488929Y49470D02*
X1499937Y43563D01*
G01X1499537Y42471D02*
X1516964Y38769D01*
G01X1499937Y43563D02*
X1516971Y39944D01*
G01X1516964Y38769D02*
X1522302Y39836D01*
G01X1524900Y40356D02*
X1526224Y40621D01*
G01X1516971Y39944D02*
X1539387Y44426D01*
G01X1465735Y96780D02*
X1473903Y61746D01*
G01X1466738Y97547D02*
X1474962Y62269D01*
G01X1473903Y61746D02*
X1486472Y46477D01*
G01X1474962Y62270D02*
X1487216Y47383D01*
G01X1486472Y46477D02*
X1498621Y39956D01*
G01X1487216Y47383D02*
X1499021Y41048D01*
G01X1498621Y39956D02*
X1518710Y35686D01*
G01X1499021Y41048D02*
X1518710Y36862D01*
G01Y35686D02*
X1533491Y38828D01*
G01X1518710Y36862D02*
X1533563Y40019D01*
G01X1471462Y60537D02*
X1484758Y44390D01*
G01X1472522Y61061D02*
X1485502Y45296D01*
G01X1484758Y44390D02*
X1497729Y37428D01*
G01X1485502Y45296D02*
X1498129Y38520D01*
G01X1497729Y37428D02*
X1506855Y35489D01*
G01X1509447Y34939D02*
X1510768Y34658D01*
G01X1513360Y34108D02*
X1514680Y33827D01*
G01X1498129Y38520D02*
X1519781Y33920D01*
G01D02*
X1534511Y37045D01*
G01X1465747Y73374D02*
X1469020Y59334D01*
G01X1466868Y73635D02*
X1470080Y59858D01*
G01X1469020Y59334D02*
X1483074Y42263D01*
G01X1470080Y59858D02*
X1483817Y43170D01*
G01X1483074Y42263D02*
X1490401Y38346D01*
G01X1483817Y43170D02*
X1491181Y39234D01*
G01X1490401Y38346D02*
X1493145Y34506D01*
G01X1465659Y41440D02*
X1468617Y34032D01*
G01X1473608Y102690D02*
X1482153Y66042D01*
G01X1472604Y101929D02*
X1481094Y65519D01*
G01X1482153Y66042D02*
X1492356Y53646D01*
G01X1481094Y65519D02*
X1491612Y52740D01*
G01X1492356Y53646D02*
X1501789Y48586D01*
G01X1491612Y52740D02*
X1501390Y47495D01*
G01X1501789Y48586D02*
X1512485Y46314D01*
G01X1501390Y47495D02*
X1512483Y45138D01*
G01X1512485Y46314D02*
X1534299Y50873D01*
G01X1512483Y45138D02*
X1513804Y45414D01*
G01X1512485Y46314D02*
X1534299Y50873D01*
G01X1516398Y45956D02*
X1517720Y46233D01*
G01X1512485Y46314D02*
X1534299Y50873D01*
G01X1520314Y46775D02*
X1521635Y47051D01*
G01X1512485Y46314D02*
X1534299Y50873D01*
G01X1524229Y47593D02*
X1534304Y49699D01*
G01X1471366Y101040D02*
X1479846Y64677D01*
G01X1470362Y100277D02*
X1478787Y64154D01*
G01X1479846Y64677D02*
X1490647Y51555D01*
G01X1478787Y64154D02*
X1489903Y50649D01*
G01X1490647Y51555D02*
X1500869Y46070D01*
G01X1489903Y50649D02*
X1500469Y44978D01*
G01X1500869Y46070D02*
X1514746Y43124D01*
G01X1500469Y44978D02*
X1514744Y41948D01*
G01X1514746Y43124D02*
X1536478Y47664D01*
G01X1514744Y41948D02*
X1516427Y42300D01*
G01X1514746Y43124D02*
X1536478Y47664D01*
G01X1519021Y42842D02*
X1520343Y43118D01*
G01X1514746Y43124D02*
X1536478Y47664D01*
G01X1522937Y43660D02*
X1524258Y43936D01*
G01X1514746Y43124D02*
X1536478Y47664D01*
G01X1526852Y44478D02*
X1536486Y46490D01*
G01X1469074Y99201D02*
X1477407Y63467D01*
G01X1468071Y98437D02*
X1476347Y62943D01*
G01X1477407Y63467D02*
X1488929Y49470D01*
G01X1476347Y62943D02*
X1488185Y48564D01*
G01X1488929Y49470D02*
X1499937Y43563D01*
G01X1488185Y48564D02*
X1499537Y42471D01*
G01X1499937Y43563D02*
X1516971Y39944D01*
G01X1499537Y42471D02*
X1516964Y38769D01*
G01X1516971Y39944D02*
X1539387Y44426D01*
G01X1516964Y38769D02*
X1522302Y39836D01*
G01X1516971Y39944D02*
X1539387Y44426D01*
G01X1524900Y40356D02*
X1526224Y40621D01*
G01X1516971Y39944D02*
X1539387Y44426D01*
G01X1516971Y39944D02*
X1539387Y44426D01*
G01X1516971Y39944D02*
X1539387Y44426D01*
G01X1466738Y97547D02*
X1474962Y62269D01*
G01X1465735Y96780D02*
X1473903Y61746D01*
G01X1474962Y62270D02*
X1487216Y47383D01*
G01X1473903Y61746D02*
X1486472Y46477D01*
G01X1487216Y47383D02*
X1499021Y41048D01*
G01X1486472Y46477D02*
X1498621Y39956D01*
G01X1499021Y41048D02*
X1518710Y36862D01*
G01X1498621Y39956D02*
X1518710Y35686D01*
G01Y36862D02*
X1533563Y40019D01*
G01X1518710Y35686D02*
X1533491Y38828D01*
G01X1472522Y61061D02*
X1485502Y45296D01*
G01X1471462Y60537D02*
X1484758Y44390D01*
G01X1485502Y45296D02*
X1498129Y38520D01*
G01X1484758Y44390D02*
X1497729Y37428D01*
G01X1498129Y38520D02*
X1519781Y33920D01*
G01X1497729Y37428D02*
X1506855Y35489D01*
G01X1498129Y38520D02*
X1519781Y33920D01*
G01X1509447Y34939D02*
X1510768Y34658D01*
G01X1498129Y38520D02*
X1519781Y33920D01*
G01X1513360Y34108D02*
X1514680Y33827D01*
G01X1498129Y38520D02*
X1519781Y33920D01*
G01D02*
X1534511Y37045D01*
G01X1466868Y73635D02*
X1470080Y59858D01*
G01X1465747Y73374D02*
X1469020Y59334D01*
G01X1470080Y59858D02*
X1483817Y43170D01*
G01X1469020Y59334D02*
X1483074Y42263D01*
G01X1483817Y43170D02*
X1491181Y39234D01*
G01X1483074Y42263D02*
X1490401Y38346D01*
G01D02*
X1493145Y34506D01*
G01X1465659Y41440D02*
X1468617Y34032D01*
G01X1472604Y101929D02*
X1481094Y65519D01*
G01X1473608Y102690D02*
X1482153Y66042D01*
G01X1481094Y65519D02*
X1491612Y52740D01*
G01X1482153Y66042D02*
X1492356Y53646D01*
G01X1491612Y52740D02*
X1501390Y47495D01*
G01X1492356Y53646D02*
X1501789Y48586D01*
G01X1501390Y47495D02*
X1512483Y45138D01*
G01X1501789Y48586D02*
X1512485Y46314D01*
G01X1512483Y45138D02*
X1513804Y45414D01*
G01X1516398Y45956D02*
X1517720Y46233D01*
G01X1520314Y46775D02*
X1521635Y47051D01*
G01X1524229Y47593D02*
X1534304Y49699D01*
G01X1512485Y46314D02*
X1534299Y50873D01*
G01X1465950Y104001D02*
X1471366Y101040D01*
G01X1468205Y105661D02*
X1470905Y104176D01*
G01D02*
X1470906D01*
G01D02*
X1473608Y102690D01*
G01X1467186Y104908D02*
X1472604Y101929D01*
G01X1465950Y104001D02*
X1471366Y101040D01*
G01X1467186Y104908D02*
X1472604Y101929D01*
G01X1468205Y105661D02*
X1470905Y104176D01*
G01X1467186Y104908D02*
X1472604Y101929D01*
G01X1470905Y104176D02*
X1470906D01*
G01X1467186Y104908D02*
X1472604Y101929D01*
G01X1470906Y104176D02*
X1473608Y102690D01*
G01X1474832Y160230D02*
X1470333Y155731D01*
G01X1474832Y160230D02*
X1470333Y155731D01*
G01X1538898Y203482D02*
X1526334D01*
G01X1538421Y204632D02*
X1525857D01*
G01X1526334Y203482D02*
X1519502Y196650D01*
G01X1525857Y204632D02*
X1519025Y197800D01*
G01X1519502Y196650D02*
X1501177D01*
G01X1519025Y197800D02*
X1500700D01*
G01X1501177Y196650D02*
X1499189Y194662D01*
G01X1500700Y197800D02*
X1498712Y195812D01*
G01X1499189Y194662D02*
X1477975D01*
G01X1498712Y195812D02*
X1478452D01*
G01X1477975Y194662D02*
X1476514Y196123D01*
G01X1478452Y195812D02*
X1476991Y197273D01*
G01X1476514Y196123D02*
X1466485D01*
G01X1476991Y197273D02*
X1466962D01*
G01X1465392Y193623D02*
X1475105D01*
G01X1465869Y194773D02*
X1475582D01*
G01X1475105Y193623D02*
X1476566Y192162D01*
G01X1475582Y194773D02*
X1477043Y193312D01*
G01X1476566Y192162D02*
X1500538D01*
G01X1477043Y193312D02*
X1501015D01*
G01X1500538Y192162D02*
X1503199Y189500D01*
G01Y189501D02*
X1503536Y189164D01*
G01X1501015Y193312D02*
X1504013Y190314D01*
G01X1503199Y189501D02*
X1503536Y189164D01*
G01D02*
X1515759D01*
G01X1504013Y190314D02*
X1516236D01*
G01X1515759Y189164D02*
X1517023Y187900D01*
G01X1516236Y190314D02*
X1517500Y189050D01*
G01X1517023Y187900D02*
X1520900D01*
G01X1517500Y189050D02*
X1520423D01*
G01X1520900Y187900D02*
X1523500Y190500D01*
G01X1520423Y189050D02*
X1522350Y190977D01*
G01X1523500Y190500D02*
Y194173D01*
G01X1522350Y190977D02*
Y194650D01*
G01X1523500Y194173D02*
X1527140Y197813D01*
G01X1522350Y194650D02*
X1526663Y198963D01*
G01D02*
X1536936D01*
G01X1471637Y183706D02*
X1474897Y186966D01*
G01X1471160Y184856D02*
X1474420Y188116D01*
G01X1474897Y186966D02*
X1497140D01*
G01X1474420Y188116D02*
X1496663D01*
G01X1474897Y186966D02*
X1497140D01*
G01X1496664Y188117D02*
X1497616D01*
G01X1497140Y186966D02*
X1503306Y180800D01*
G01X1497616Y188117D02*
X1503783Y181950D01*
G01X1503306Y180800D02*
X1519465D01*
G01X1503783Y181950D02*
X1518988D01*
G01X1519465Y180800D02*
X1520466Y181801D01*
G01D02*
X1522028D01*
G01X1518988Y181950D02*
X1519989Y182951D01*
G01X1520466Y181801D02*
X1522028D01*
G01X1519989Y182951D02*
X1521551D01*
G01X1522028Y181801D02*
X1533040Y192813D01*
G01X1521551Y182951D02*
X1532563Y193963D01*
G01X1538421Y204632D02*
X1525857D01*
G01X1538898Y203482D02*
X1526334D01*
G01X1525857Y204632D02*
X1519025Y197800D01*
G01X1526334Y203482D02*
X1519502Y196650D01*
G01X1519025Y197800D02*
X1500700D01*
G01X1519502Y196650D02*
X1501177D01*
G01X1500700Y197800D02*
X1498712Y195812D01*
G01X1501177Y196650D02*
X1499189Y194662D01*
G01X1498712Y195812D02*
X1478452D01*
G01X1499189Y194662D02*
X1477975D01*
G01X1478452Y195812D02*
X1476991Y197273D01*
G01X1477975Y194662D02*
X1476514Y196123D01*
G01X1476991Y197273D02*
X1466962D01*
G01X1476514Y196123D02*
X1466485D01*
G01X1465869Y194773D02*
X1475582D01*
G01X1465392Y193623D02*
X1475105D01*
G01X1475582Y194773D02*
X1477043Y193312D01*
G01X1475105Y193623D02*
X1476566Y192162D01*
G01X1477043Y193312D02*
X1501015D01*
G01X1476566Y192162D02*
X1500538D01*
G01X1501015Y193312D02*
X1504013Y190314D01*
G01X1500538Y192162D02*
X1503199Y189500D01*
G01X1501015Y193312D02*
X1504013Y190314D01*
G01D02*
X1516236D01*
G01X1503199Y189501D02*
X1503536Y189164D01*
G01X1504013Y190314D02*
X1516236D01*
G01X1503536Y189164D02*
X1515759D01*
G01X1516236Y190314D02*
X1517500Y189050D01*
G01X1515759Y189164D02*
X1517023Y187900D01*
G01X1517500Y189050D02*
X1520423D01*
G01X1517023Y187900D02*
X1520900D01*
G01X1520423Y189050D02*
X1522350Y190977D01*
G01X1520900Y187900D02*
X1523500Y190500D01*
G01X1522350Y190977D02*
Y194650D01*
G01X1523500Y190500D02*
Y194173D01*
G01X1522350Y194650D02*
X1526663Y198963D01*
G01X1523500Y194173D02*
X1527140Y197813D01*
G01X1526663Y198963D02*
X1536936D01*
G01X1471160Y184856D02*
X1474420Y188116D01*
G01X1471637Y183706D02*
X1474897Y186966D01*
G01X1474420Y188116D02*
X1496663D01*
G01X1496664Y188117D02*
X1497616D01*
G01X1474897Y186966D02*
X1497140D01*
G01X1497616Y188117D02*
X1503783Y181950D01*
G01X1497140Y186966D02*
X1503306Y180800D01*
G01X1503783Y181950D02*
X1518988D01*
G01X1503306Y180800D02*
X1519465D01*
G01X1518988Y181950D02*
X1519989Y182951D01*
G01X1519465Y180800D02*
X1520466Y181801D01*
G01X1518988Y181950D02*
X1519989Y182951D01*
G01D02*
X1521551D01*
G01X1520466Y181801D02*
X1522028D01*
G01X1521551Y182951D02*
X1532563Y193963D01*
G01X1522028Y181801D02*
X1533040Y192813D01*
G01X1473872Y191123D02*
X1475518Y189477D01*
G01X1474349Y192273D02*
X1475995Y190627D01*
G01X1475518Y189477D02*
X1498275D01*
G01X1475995Y190627D02*
X1497798D01*
G01X1475518Y189477D02*
X1498275D01*
G01X1497799Y190628D02*
X1498751D01*
G01X1498275Y189477D02*
X1504452Y183300D01*
G01X1498751Y190628D02*
X1504929Y184450D01*
G01X1504452Y183300D02*
X1518428D01*
G01X1504929Y184450D02*
X1517951D01*
G01X1518428Y183300D02*
X1519429Y184301D01*
G01D02*
X1520902D01*
G01X1517951Y184450D02*
X1518952Y185451D01*
G01X1519429Y184301D02*
X1520902D01*
G01D02*
X1526937Y190336D01*
G01X1518952Y185451D02*
X1520425D01*
G01X1520902Y184301D02*
X1526937Y190336D01*
G01X1520425Y185451D02*
X1525787Y190813D01*
G01X1526937Y190336D02*
Y194073D01*
G01X1525787Y190813D02*
Y194550D01*
G01X1526937Y194073D02*
X1528177Y195313D01*
G01X1525787Y194550D02*
X1527700Y196463D01*
G01X1527647Y174510D02*
X1525537Y172400D01*
G01D02*
X1524673D01*
G01X1528124Y173360D02*
X1526014Y171250D01*
G01X1525537Y172400D02*
X1524673D01*
G01D02*
X1521771Y169498D01*
G01X1526014Y171250D02*
X1525150D01*
G01X1524673Y172400D02*
X1521771Y169498D01*
G01X1525150Y171250D02*
X1522248Y168348D01*
G01X1521771Y169498D02*
X1499898D01*
G01X1522248Y168348D02*
X1500375D01*
G01X1499898Y169498D02*
X1498257Y167857D01*
G01X1500375Y168348D02*
X1498734Y166707D01*
G01X1498257Y167857D02*
X1495097D01*
G01X1498734Y166707D02*
X1495574D01*
G01X1495091Y167851D02*
X1484271D01*
G01X1495568Y166701D02*
X1484748D01*
G01X1484271Y167851D02*
X1477800Y161380D01*
G01X1484748Y166701D02*
X1478277Y160230D01*
G01X1477800Y161380D02*
X1474355D01*
G01X1478277Y160230D02*
X1474832D01*
G01X1474355Y161380D02*
X1469856Y156881D01*
G01X1529677Y178450D02*
X1524977Y173750D01*
G01X1529200Y179600D02*
X1524500Y174900D01*
G01X1524977Y173750D02*
X1524113D01*
G01X1524500Y174900D02*
X1523636D01*
G01X1524977Y173750D02*
X1524113D01*
G01D02*
X1521211Y170848D01*
G01X1523636Y174900D02*
X1520734Y171998D01*
G01X1521211Y170848D02*
X1498948D01*
G01X1520734Y171998D02*
X1498471D01*
G01X1498948Y170848D02*
X1497400Y169300D01*
G01X1498471Y171998D02*
X1496923Y170450D01*
G01X1497400Y169300D02*
X1483527D01*
G01X1496923Y170450D02*
X1483050D01*
G01X1483527Y169300D02*
X1477077Y162850D01*
G01X1483050Y170450D02*
X1476600Y164000D01*
G01X1477077Y162850D02*
X1473915D01*
G01X1476600Y164000D02*
X1473438D01*
G01X1473915Y162850D02*
X1469296Y158231D01*
G01X1473438Y164000D02*
X1468819Y159381D01*
G01X1482226Y177401D02*
X1487887Y183062D01*
G01X1482703Y176251D02*
X1488364Y181912D01*
G01X1487887Y183062D02*
X1495342D01*
G01X1488364Y181912D02*
X1494865D01*
G01X1495342Y183062D02*
X1501454Y176950D01*
G01X1494865Y181912D02*
X1500977Y175800D01*
G01X1501454Y176950D02*
X1521062D01*
G01X1500977Y175800D02*
X1521539D01*
G01X1521062Y176950D02*
X1522063Y177951D01*
G01X1521539Y175800D02*
X1522540Y176801D01*
G01X1522063Y177951D02*
X1523625D01*
G01X1522540Y176801D02*
X1524102D01*
G01X1523625Y177951D02*
X1527974Y182300D01*
G01X1524102Y176801D02*
X1528451Y181150D01*
G01X1523065Y179301D02*
X1528714Y184950D01*
G01X1528237Y186100D02*
X1522588Y180451D01*
G01X1521503Y179301D02*
X1523065D01*
G01X1522588Y180451D02*
X1521026D01*
G01X1520502Y178300D02*
X1521503Y179301D01*
G01D02*
X1523065D01*
G01X1521026Y180451D02*
X1520025Y179450D01*
G01X1502097Y178300D02*
X1520502D01*
G01X1520025Y179450D02*
X1502574D01*
G01X1495973Y184424D02*
X1502097Y178300D01*
G01X1502574Y179450D02*
X1496449Y185575D01*
G01X1483438Y184424D02*
X1495973D01*
G01X1496449Y185575D02*
X1495497D01*
G01X1483438Y184424D02*
X1495973D01*
G01X1495496Y185574D02*
X1482961D01*
G01X1481852Y182838D02*
X1483438Y184424D01*
G01X1482961Y185574D02*
X1480702Y183315D01*
G01X1481852Y180536D02*
Y182838D01*
G01X1480702Y183315D02*
Y181013D01*
G01X1480216Y178900D02*
X1481852Y180536D01*
G01X1480702Y181013D02*
X1479739Y180050D01*
G01X1474349Y192273D02*
X1475995Y190627D01*
G01X1473872Y191123D02*
X1475518Y189477D01*
G01X1475995Y190627D02*
X1497798D01*
G01X1497799Y190628D02*
X1498751D01*
G01X1475518Y189477D02*
X1498275D01*
G01X1498751Y190628D02*
X1504929Y184450D01*
G01X1498275Y189477D02*
X1504452Y183300D01*
G01X1504929Y184450D02*
X1517951D01*
G01X1504452Y183300D02*
X1518428D01*
G01X1517951Y184450D02*
X1518952Y185451D01*
G01X1518428Y183300D02*
X1519429Y184301D01*
G01X1517951Y184450D02*
X1518952Y185451D01*
G01D02*
X1520425D01*
G01X1519429Y184301D02*
X1520902D01*
G01X1518952Y185451D02*
X1520425D01*
G01D02*
X1525787Y190813D01*
G01X1520902Y184301D02*
X1526937Y190336D01*
G01X1525787Y190813D02*
Y194550D01*
G01X1526937Y190336D02*
Y194073D01*
G01X1525787Y194550D02*
X1527700Y196463D01*
G01X1526937Y194073D02*
X1528177Y195313D01*
G01X1528124Y173360D02*
X1526014Y171250D01*
G01X1527647Y174510D02*
X1525537Y172400D01*
G01X1528124Y173360D02*
X1526014Y171250D01*
G01D02*
X1525150D01*
G01X1525537Y172400D02*
X1524673D01*
G01X1526014Y171250D02*
X1525150D01*
G01D02*
X1522248Y168348D01*
G01X1524673Y172400D02*
X1521771Y169498D01*
G01X1522248Y168348D02*
X1500375D01*
G01X1521771Y169498D02*
X1499898D01*
G01X1500375Y168348D02*
X1498734Y166707D01*
G01X1499898Y169498D02*
X1498257Y167857D01*
G01X1498734Y166707D02*
X1495574D01*
G01X1498257Y167857D02*
X1495097D01*
G01X1495568Y166701D02*
X1484748D01*
G01X1495091Y167851D02*
X1484271D01*
G01X1484748Y166701D02*
X1478277Y160230D01*
G01X1484271Y167851D02*
X1477800Y161380D01*
G01X1478277Y160230D02*
X1474832D01*
G01X1477800Y161380D02*
X1474355D01*
G01D02*
X1469856Y156881D01*
G01X1529200Y179600D02*
X1524500Y174900D01*
G01X1529677Y178450D02*
X1524977Y173750D01*
G01X1524500Y174900D02*
X1523636D01*
G01D02*
X1520734Y171998D01*
G01X1524977Y173750D02*
X1524113D01*
G01X1523636Y174900D02*
X1520734Y171998D01*
G01X1524113Y173750D02*
X1521211Y170848D01*
G01X1520734Y171998D02*
X1498471D01*
G01X1521211Y170848D02*
X1498948D01*
G01X1498471Y171998D02*
X1496923Y170450D01*
G01X1498948Y170848D02*
X1497400Y169300D01*
G01X1496923Y170450D02*
X1483050D01*
G01X1497400Y169300D02*
X1483527D01*
G01X1483050Y170450D02*
X1476600Y164000D01*
G01X1483527Y169300D02*
X1477077Y162850D01*
G01X1476600Y164000D02*
X1473438D01*
G01X1477077Y162850D02*
X1473915D01*
G01X1473438Y164000D02*
X1468819Y159381D01*
G01X1473915Y162850D02*
X1469296Y158231D01*
G01X1482703Y176251D02*
X1488364Y181912D01*
G01X1482226Y177401D02*
X1487887Y183062D01*
G01X1488364Y181912D02*
X1494865D01*
G01X1487887Y183062D02*
X1495342D01*
G01X1494865Y181912D02*
X1500977Y175800D01*
G01X1495342Y183062D02*
X1501454Y176950D01*
G01X1500977Y175800D02*
X1521539D01*
G01X1501454Y176950D02*
X1521062D01*
G01X1521539Y175800D02*
X1522540Y176801D01*
G01X1521062Y176950D02*
X1522063Y177951D01*
G01X1522540Y176801D02*
X1524102D01*
G01X1522063Y177951D02*
X1523625D01*
G01X1524102Y176801D02*
X1528451Y181150D01*
G01X1523625Y177951D02*
X1527974Y182300D01*
G01X1480702Y181013D02*
X1479739Y180050D01*
G01X1480216Y178900D02*
X1481852Y180536D01*
G01X1480702Y183315D02*
Y181013D01*
G01X1481852Y180536D02*
Y182838D01*
G01X1482961Y185574D02*
X1480702Y183315D01*
G01X1481852Y182838D02*
X1483438Y184424D01*
G01X1496449Y185575D02*
X1495497D01*
G01X1495496Y185574D02*
X1482961D01*
G01X1483438Y184424D02*
X1495973D01*
G01X1502574Y179450D02*
X1496449Y185575D01*
G01X1495973Y184424D02*
X1502097Y178300D01*
G01X1520025Y179450D02*
X1502574D01*
G01X1502097Y178300D02*
X1520502D01*
G01X1521026Y180451D02*
X1520025Y179450D01*
G01X1520502Y178300D02*
X1521503Y179301D01*
G01X1522588Y180451D02*
X1521026D01*
G01D02*
X1520025Y179450D01*
G01X1521503Y179301D02*
X1523065D01*
G01X1528237Y186100D02*
X1522588Y180451D01*
G01X1523065Y179301D02*
X1528714Y184950D01*
G01X1502009Y220731D02*
Y217013D01*
G01X1500859Y221208D02*
Y217490D01*
G01X1502009Y217013D02*
X1499302Y214306D01*
G01X1500859Y217490D02*
X1498825Y215456D01*
G01X1499302Y214306D02*
X1484645D01*
G01X1498825Y215456D02*
X1490940D01*
G01X1499302Y214306D02*
X1484645D01*
G01X1490939Y215457D02*
X1488900D01*
G01X1499302Y214306D02*
X1484645D01*
G01X1488899Y215456D02*
X1485122D01*
G01X1484645Y214306D02*
X1481301Y217650D01*
G01X1485122Y215456D02*
X1481778Y218800D01*
G01X1481301Y217650D02*
X1479850D01*
G01D02*
X1473900Y223600D01*
G01X1504906Y218939D02*
Y215638D01*
G01X1503756Y219416D02*
Y216115D01*
G01X1504906Y215638D02*
X1501074Y211806D01*
G01X1503756Y216115D02*
X1500597Y212956D01*
G01X1501074Y211806D02*
X1483608D01*
G01X1500597Y212956D02*
X1484085D01*
G01X1483608Y211806D02*
X1480372Y215042D01*
G01X1484085Y212956D02*
X1480849Y216192D01*
G01X1480372Y215042D02*
X1478258D01*
G01X1480849Y216192D02*
X1478735D01*
G01X1478258Y215042D02*
X1473180Y220120D01*
G01X1478735Y216192D02*
X1473657Y221270D01*
G01X1469720Y220120D02*
X1467400Y217800D01*
G01X1528753Y217450D02*
X1526256Y214953D01*
G01X1528276Y218600D02*
X1525779Y216103D01*
G01X1526256Y214953D02*
X1522046D01*
G01X1525779Y216103D02*
X1522523D01*
G01X1522046Y214953D02*
X1516649Y220350D01*
G01X1522523Y216103D02*
X1517126Y221500D01*
G01X1513539Y220350D02*
X1502495Y209306D01*
G01X1513062Y221500D02*
X1502018Y210456D01*
G01X1502495Y209306D02*
X1482571D01*
G01X1502018Y210456D02*
X1483048D01*
G01X1482571Y209306D02*
X1479335Y212542D01*
G01X1483048Y210456D02*
X1479812Y213692D01*
G01X1479335Y212542D02*
X1466058D01*
G01X1479812Y213692D02*
X1466535D01*
G01X1483676Y204250D02*
X1469817D01*
G01X1470294Y205400D02*
X1483199D01*
G01X1486232Y206806D02*
X1483676Y204250D01*
G01X1483199Y205400D02*
X1485755Y207956D01*
G01X1503716Y206806D02*
X1486232D01*
G01X1485755Y207956D02*
X1503239D01*
G01X1509849Y212939D02*
X1503716Y206806D01*
G01X1503239Y207956D02*
X1509372Y214089D01*
G01X1510420Y213457D02*
X1509902Y212939D01*
G01X1509425Y214089D02*
X1509943Y214607D01*
G01X1519692Y213457D02*
X1510420D01*
G01X1509943Y214607D02*
X1520169D01*
G01X1521084Y212065D02*
X1519692Y213457D01*
G01X1520169Y214607D02*
X1521561Y213215D01*
G01X1527688Y212065D02*
X1521084D01*
G01X1521561Y213215D02*
X1527211D01*
G01X1530069Y209550D02*
X1520023D01*
G01X1529592Y210700D02*
X1520500D01*
G01X1520023Y209550D02*
X1518616Y210957D01*
G01X1520500Y210700D02*
X1519093Y212107D01*
G01X1518616Y210957D02*
X1511457D01*
G01X1519093Y212107D02*
X1510980D01*
G01X1511457Y210957D02*
X1504806Y204306D01*
G01X1510980Y212107D02*
X1504329Y205456D01*
G01X1504806Y204306D02*
X1487269D01*
G01X1504329Y205456D02*
X1486792D01*
G01X1487269Y204306D02*
X1484713Y201750D01*
G01X1486792Y205456D02*
X1484236Y202900D01*
G01X1484713Y201750D02*
X1468780D01*
G01X1484236Y202900D02*
X1469257D01*
G01X1531106Y207050D02*
X1525277D01*
G01X1530629Y208200D02*
X1524800D01*
G01X1525277Y207050D02*
X1518177Y199950D01*
G01X1524800Y208200D02*
X1517700Y201100D01*
G01X1518177Y199950D02*
X1515050D01*
G01X1517700Y201100D02*
X1515527D01*
G01X1515050Y199950D02*
X1513194Y201806D01*
G01X1515527Y201100D02*
X1513671Y202956D01*
G01X1513194Y201806D02*
X1488306D01*
G01X1513671Y202956D02*
X1487829D01*
G01X1488306Y201806D02*
X1485750Y199250D01*
G01X1487829Y202956D02*
X1485273Y200400D01*
G01X1485750Y199250D02*
X1467743D01*
G01X1485273Y200400D02*
X1468220D01*
G01X1500859Y221208D02*
Y217490D01*
G01X1502009Y220731D02*
Y217013D01*
G01X1500859Y217490D02*
X1498825Y215456D01*
G01X1502009Y217013D02*
X1499302Y214306D01*
G01X1498825Y215456D02*
X1490940D01*
G01X1490939Y215457D02*
X1488900D01*
G01X1488899Y215456D02*
X1485122D01*
G01X1499302Y214306D02*
X1484645D01*
G01X1485122Y215456D02*
X1481778Y218800D01*
G01X1484645Y214306D02*
X1481301Y217650D01*
G01D02*
X1479850D01*
G01D02*
X1473900Y223600D01*
G01X1503756Y219416D02*
Y216115D01*
G01X1504906Y218939D02*
Y215638D01*
G01X1503756Y216115D02*
X1500597Y212956D01*
G01X1504906Y215638D02*
X1501074Y211806D01*
G01X1500597Y212956D02*
X1484085D01*
G01X1501074Y211806D02*
X1483608D01*
G01X1484085Y212956D02*
X1480849Y216192D01*
G01X1483608Y211806D02*
X1480372Y215042D01*
G01X1480849Y216192D02*
X1478735D01*
G01X1480372Y215042D02*
X1478258D01*
G01X1478735Y216192D02*
X1473657Y221270D01*
G01X1478258Y215042D02*
X1473180Y220120D01*
G01X1469720D02*
X1467400Y217800D01*
G01X1528276Y218600D02*
X1525779Y216103D01*
G01X1528753Y217450D02*
X1526256Y214953D01*
G01X1525779Y216103D02*
X1522523D01*
G01X1526256Y214953D02*
X1522046D01*
G01X1522523Y216103D02*
X1517126Y221500D01*
G01X1522046Y214953D02*
X1516649Y220350D01*
G01X1513062Y221500D02*
X1502018Y210456D01*
G01X1513539Y220350D02*
X1502495Y209306D01*
G01X1502018Y210456D02*
X1483048D01*
G01X1502495Y209306D02*
X1482571D01*
G01X1483048Y210456D02*
X1479812Y213692D01*
G01X1482571Y209306D02*
X1479335Y212542D01*
G01X1479812Y213692D02*
X1466535D01*
G01X1479335Y212542D02*
X1466058D01*
G01X1521561Y213215D02*
X1527211D01*
G01X1527688Y212065D02*
X1521084D01*
G01X1520169Y214607D02*
X1521561Y213215D01*
G01X1521084Y212065D02*
X1519692Y213457D01*
G01X1509943Y214607D02*
X1520169D01*
G01X1519692Y213457D02*
X1510420D01*
G01X1509425Y214089D02*
X1509943Y214607D01*
G01X1510420Y213457D02*
X1509902Y212939D01*
G01X1503239Y207956D02*
X1509372Y214089D01*
G01X1509849Y212939D02*
X1503716Y206806D01*
G01X1485755Y207956D02*
X1503239D01*
G01X1503716Y206806D02*
X1486232D01*
G01X1483199Y205400D02*
X1485755Y207956D01*
G01X1486232Y206806D02*
X1483676Y204250D01*
G01X1470294Y205400D02*
X1483199D01*
G01X1483676Y204250D02*
X1469817D01*
G01X1529592Y210700D02*
X1520500D01*
G01X1530069Y209550D02*
X1520023D01*
G01X1520500Y210700D02*
X1519093Y212107D01*
G01X1520023Y209550D02*
X1518616Y210957D01*
G01X1519093Y212107D02*
X1510980D01*
G01X1518616Y210957D02*
X1511457D01*
G01X1510980Y212107D02*
X1504329Y205456D01*
G01X1511457Y210957D02*
X1504806Y204306D01*
G01X1504329Y205456D02*
X1486792D01*
G01X1504806Y204306D02*
X1487269D01*
G01X1486792Y205456D02*
X1484236Y202900D01*
G01X1487269Y204306D02*
X1484713Y201750D01*
G01X1484236Y202900D02*
X1469257D01*
G01X1484713Y201750D02*
X1468780D01*
G01X1530629Y208200D02*
X1524800D01*
G01X1531106Y207050D02*
X1525277D01*
G01X1524800Y208200D02*
X1517700Y201100D01*
G01X1525277Y207050D02*
X1518177Y199950D01*
G01X1517700Y201100D02*
X1515527D01*
G01X1518177Y199950D02*
X1515050D01*
G01X1515527Y201100D02*
X1513671Y202956D01*
G01X1515050Y199950D02*
X1513194Y201806D01*
G01X1513671Y202956D02*
X1487829D01*
G01X1513194Y201806D02*
X1488306D01*
G01X1487829Y202956D02*
X1485273Y200400D01*
G01X1488306Y201806D02*
X1485750Y199250D01*
G01X1485273Y200400D02*
X1468220D01*
G01X1485750Y199250D02*
X1467743D01*
G01X1538035Y228766D02*
X1505975D01*
G01X1538512Y229916D02*
X1505498D01*
G01X1505975Y228766D02*
X1504134Y226925D01*
G01X1505498Y229916D02*
X1503657Y228075D01*
G01X1504134Y226925D02*
X1498320D01*
G01X1503657Y228075D02*
X1497843D01*
G01X1498320Y226925D02*
X1494807Y223412D01*
G01X1497843Y228075D02*
X1494330Y224562D01*
G01X1494807Y223412D02*
X1489927D01*
G01X1494330Y224562D02*
X1490404D01*
G01X1489927Y223412D02*
X1486713Y226626D01*
G01X1490404Y224562D02*
X1487190Y227776D01*
G01X1486713Y226626D02*
X1478943D01*
G01X1487190Y227776D02*
X1478466D01*
G01X1478943Y226626D02*
X1478417Y226100D01*
G01X1478466Y227776D02*
X1477940Y227250D01*
G01X1537036Y226228D02*
X1507506D01*
G01X1537513Y227378D02*
X1507029D01*
G01X1507506Y226228D02*
X1502009Y220731D01*
G01X1507029Y227378D02*
X1500859Y221208D01*
G01X1481778Y218800D02*
X1480327D01*
G01D02*
X1474377Y224750D01*
G01X1532915Y220359D02*
X1523672D01*
G01X1532438Y221509D02*
X1524149D01*
G01X1523672Y220359D02*
X1521006Y223025D01*
G01X1524149Y221509D02*
X1521483Y224175D01*
G01X1521006Y223025D02*
X1508992D01*
G01X1521483Y224175D02*
X1508515D01*
G01X1508992Y223025D02*
X1504906Y218939D01*
G01X1508515Y224175D02*
X1503756Y219416D01*
G01X1473180Y220120D02*
X1469720D01*
G01X1473657Y221270D02*
X1469243D01*
G01D02*
X1466923Y218950D01*
G01X1516649Y220350D02*
X1513539D01*
G01X1517126Y221500D02*
X1513062D01*
G01X1466623Y229750D02*
X1470547Y233674D01*
G01X1467100Y228600D02*
X1471024Y232524D01*
G01X1470547Y233674D02*
X1494240D01*
G01X1471024Y232524D02*
X1494717D01*
G01X1494240Y233674D02*
X1497715Y237149D01*
G01X1494717Y232524D02*
X1498192Y235999D01*
G01X1497715Y237149D02*
X1502519D01*
G01X1498192Y235999D02*
X1502042D01*
G01X1502519Y237149D02*
X1507252Y232416D01*
G01X1502042Y235999D02*
X1506775Y231266D01*
G01X1507252Y232416D02*
X1539561D01*
G01X1506775Y231266D02*
X1539084D01*
G01X1538512Y229916D02*
X1505498D01*
G01X1538035Y228766D02*
X1505975D01*
G01X1505498Y229916D02*
X1503657Y228075D01*
G01X1505975Y228766D02*
X1504134Y226925D01*
G01X1503657Y228075D02*
X1497843D01*
G01X1504134Y226925D02*
X1498320D01*
G01X1497843Y228075D02*
X1494330Y224562D01*
G01X1498320Y226925D02*
X1494807Y223412D01*
G01X1494330Y224562D02*
X1490404D01*
G01X1494807Y223412D02*
X1489927D01*
G01X1490404Y224562D02*
X1487190Y227776D01*
G01X1489927Y223412D02*
X1486713Y226626D01*
G01X1487190Y227776D02*
X1478466D01*
G01X1486713Y226626D02*
X1478943D01*
G01X1478466Y227776D02*
X1477940Y227250D01*
G01X1478943Y226626D02*
X1478417Y226100D01*
G01X1537513Y227378D02*
X1507029D01*
G01X1537036Y226228D02*
X1507506D01*
G01X1507029Y227378D02*
X1500859Y221208D01*
G01X1507506Y226228D02*
X1502009Y220731D01*
G01X1481778Y218800D02*
X1480327D01*
G01D02*
X1474377Y224750D01*
G01X1532438Y221509D02*
X1524149D01*
G01X1532915Y220359D02*
X1523672D01*
G01X1524149Y221509D02*
X1521483Y224175D01*
G01X1523672Y220359D02*
X1521006Y223025D01*
G01X1521483Y224175D02*
X1508515D01*
G01X1521006Y223025D02*
X1508992D01*
G01X1508515Y224175D02*
X1503756Y219416D01*
G01X1508992Y223025D02*
X1504906Y218939D01*
G01X1473657Y221270D02*
X1469243D01*
G01X1473180Y220120D02*
X1469720D01*
G01X1469243Y221270D02*
X1466923Y218950D01*
G01X1517126Y221500D02*
X1513062D01*
G01X1516649Y220350D02*
X1513539D01*
G01X1467100Y228600D02*
X1471024Y232524D01*
G01X1466623Y229750D02*
X1470547Y233674D01*
G01X1471024Y232524D02*
X1494717D01*
G01X1470547Y233674D02*
X1494240D01*
G01X1494717Y232524D02*
X1498192Y235999D01*
G01X1494240Y233674D02*
X1497715Y237149D01*
G01X1498192Y235999D02*
X1502042D01*
G01X1497715Y237149D02*
X1502519D01*
G01X1502042Y235999D02*
X1506775Y231266D01*
G01X1502519Y237149D02*
X1507252Y232416D01*
G01X1506775Y231266D02*
X1539084D01*
G01X1507252Y232416D02*
X1539561D01*
G01X1508460Y346441D02*
X1516668Y338233D01*
G01D02*
X1518586Y336316D01*
G01X1507984Y345291D02*
X1518109Y335166D01*
G01X1518586Y336316D02*
X1529537D01*
G01X1518109Y335166D02*
X1529060D01*
G01X1507984Y345291D02*
X1518109Y335166D01*
G01X1508460Y346441D02*
X1516668Y338233D01*
G01X1507984Y345291D02*
X1518109Y335166D01*
G01X1516668Y338233D02*
X1518586Y336316D01*
G01X1518109Y335166D02*
X1529060D01*
G01X1518586Y336316D02*
X1529537D01*
G01X1529988Y337775D02*
X1519121D01*
G01X1530465Y338925D02*
X1519598D01*
G01X1519121Y337775D02*
X1508983Y347913D01*
G01X1519598Y338925D02*
X1509796Y348726D01*
G01X1519121Y337775D02*
X1508983Y347913D01*
G01X1530465Y338925D02*
X1519598D01*
G01X1529988Y337775D02*
X1519121D01*
G01X1519598Y338925D02*
X1509796Y348726D01*
G01X1519121Y337775D02*
X1508983Y347913D01*
G01X1519598Y338925D02*
X1509796Y348726D01*
G01X1519598Y338925D02*
X1509796Y348726D01*
G01X1466505Y388421D02*
X1467656Y387270D01*
G01X1466028Y387271D02*
X1467179Y386120D01*
G01X1467656Y387270D02*
X1474557D01*
G01X1467179Y386120D02*
X1474080D01*
G01X1474557Y387270D02*
X1476450Y385377D01*
G01X1474080Y386120D02*
X1475300Y384900D01*
G01X1476450Y385377D02*
Y376600D01*
G01X1475300Y384900D02*
Y376123D01*
G01X1476450Y376600D02*
X1483381Y369669D01*
G01X1475300Y376123D02*
X1482904Y368519D01*
G01X1483381Y369669D02*
X1489637D01*
G01X1482904Y368519D02*
X1489160D01*
G01X1489637Y369669D02*
X1493851Y365455D01*
G01X1489160Y368519D02*
X1492701Y364978D01*
G01X1493851Y365455D02*
Y348849D01*
G01X1492701Y364978D02*
Y348372D01*
G01X1493851Y348849D02*
X1494631Y348069D01*
G01X1492701Y348372D02*
X1494154Y346919D01*
G01X1494631Y348069D02*
X1501720D01*
G01X1494154Y346919D02*
X1501243D01*
G01X1501720Y348069D02*
X1503348Y346441D01*
G01X1501243Y346919D02*
X1502871Y345291D01*
G01X1503348Y346441D02*
X1508460D01*
G01X1502871Y345291D02*
X1507984D01*
G01X1466028Y387271D02*
X1467179Y386120D01*
G01X1466505Y388421D02*
X1467656Y387270D01*
G01X1467179Y386120D02*
X1474080D01*
G01X1467656Y387270D02*
X1474557D01*
G01X1474080Y386120D02*
X1475300Y384900D01*
G01X1474557Y387270D02*
X1476450Y385377D01*
G01X1475300Y384900D02*
Y376123D01*
G01X1476450Y385377D02*
Y376600D01*
G01X1475300Y376123D02*
X1482904Y368519D01*
G01X1476450Y376600D02*
X1483381Y369669D01*
G01X1482904Y368519D02*
X1489160D01*
G01X1483381Y369669D02*
X1489637D01*
G01X1489160Y368519D02*
X1492701Y364978D01*
G01X1489637Y369669D02*
X1493851Y365455D01*
G01X1492701Y364978D02*
Y348372D01*
G01X1493851Y365455D02*
Y348849D01*
G01X1492701Y348372D02*
X1494154Y346919D01*
G01X1493851Y348849D02*
X1494631Y348069D01*
G01X1494154Y346919D02*
X1501243D01*
G01X1494631Y348069D02*
X1501720D01*
G01X1501243Y346919D02*
X1502871Y345291D01*
G01X1501720Y348069D02*
X1503348Y346441D01*
G01X1502871Y345291D02*
X1507984D01*
G01X1503348Y346441D02*
X1508460D01*
G01X1508983Y347912D02*
X1508982Y347913D01*
G01D02*
X1508370D01*
G01X1508983Y347912D02*
X1508982Y347913D01*
G01X1509796Y348726D02*
X1509459Y349063D01*
G01X1508982Y347913D02*
X1508370D01*
G01D02*
X1500550Y355733D01*
G01X1509459Y349063D02*
X1508847D01*
G01X1508370Y347913D02*
X1500550Y355733D01*
G01X1508847Y349063D02*
X1501700Y356210D01*
G01X1500550Y355733D02*
Y366823D01*
G01X1501700Y356210D02*
Y367300D01*
G01X1500550Y366823D02*
X1495823Y371550D01*
G01X1501700Y367300D02*
X1496300Y372700D01*
G01X1495823Y371550D02*
X1486273D01*
G01X1496300Y372700D02*
X1486750D01*
G01X1486273Y371550D02*
X1482500Y375323D01*
G01X1486750Y372700D02*
X1483650Y375800D01*
G01X1482500Y375323D02*
Y377123D01*
G01X1483650Y375800D02*
Y377600D01*
G01X1482500Y377123D02*
X1478000Y381623D01*
G01X1483650Y377600D02*
X1479150Y382100D01*
G01X1478000Y381623D02*
Y388200D01*
G01X1479150Y382100D02*
Y388677D01*
G01X1478000Y388200D02*
X1477100Y389100D01*
G01X1479150Y388677D02*
X1477577Y390250D01*
G01X1477100Y389100D02*
X1468900D01*
G01X1477577Y390250D02*
X1469377D01*
G01X1468900Y389100D02*
X1466900Y391100D01*
G01X1469377Y390250D02*
X1468050Y391577D01*
G01X1466900Y391100D02*
Y394500D01*
G01X1468050Y391577D02*
Y394023D01*
G01X1466900Y394500D02*
X1467798Y395398D01*
G01X1468050Y394023D02*
X1468948Y394921D01*
G01X1467798Y395398D02*
Y396723D01*
G01X1468948Y394921D02*
Y396723D01*
G01X1509796Y348726D02*
X1509459Y349063D01*
G01X1509796Y348726D02*
X1509459Y349063D01*
G01X1508983Y347912D02*
X1508982Y347913D01*
G01X1509459Y349063D02*
X1508847D01*
G01X1508982Y347913D02*
X1508370D01*
G01X1509459Y349063D02*
X1508847D01*
G01D02*
X1501700Y356210D01*
G01X1508370Y347913D02*
X1500550Y355733D01*
G01X1501700Y356210D02*
Y367300D01*
G01X1500550Y355733D02*
Y366823D01*
G01X1501700Y367300D02*
X1496300Y372700D01*
G01X1500550Y366823D02*
X1495823Y371550D01*
G01X1496300Y372700D02*
X1486750D01*
G01X1495823Y371550D02*
X1486273D01*
G01X1486750Y372700D02*
X1483650Y375800D01*
G01X1486273Y371550D02*
X1482500Y375323D01*
G01X1483650Y375800D02*
Y377600D01*
G01X1482500Y375323D02*
Y377123D01*
G01X1483650Y377600D02*
X1479150Y382100D01*
G01X1482500Y377123D02*
X1478000Y381623D01*
G01X1479150Y382100D02*
Y388677D01*
G01X1478000Y381623D02*
Y388200D01*
G01X1479150Y388677D02*
X1477577Y390250D01*
G01X1478000Y388200D02*
X1477100Y389100D01*
G01X1477577Y390250D02*
X1469377D01*
G01X1477100Y389100D02*
X1468900D01*
G01X1469377Y390250D02*
X1468050Y391577D01*
G01X1468900Y389100D02*
X1466900Y391100D01*
G01X1468050Y391577D02*
Y394023D01*
G01X1466900Y391100D02*
Y394500D01*
G01X1468050Y394023D02*
X1468948Y394921D01*
G01X1466900Y394500D02*
X1467798Y395398D01*
G01X1468948Y394921D02*
Y396723D01*
G01X1467798Y395398D02*
Y396723D01*
G01X1484200Y403750D02*
X1485900Y402050D01*
G01X1484677Y404900D02*
X1487050Y402527D01*
G01X1485900Y402050D02*
Y400426D01*
G01X1487050Y402527D02*
Y399949D01*
G01X1485900Y400426D02*
X1484756Y399282D01*
G01X1487050Y399949D02*
X1485906Y398805D01*
G01X1484756Y399282D02*
Y396646D01*
G01X1485906Y398805D02*
Y397123D01*
G01X1484756Y396646D02*
X1486706Y394696D01*
G01X1485906Y397123D02*
X1487856Y395173D01*
G01X1486706Y394696D02*
Y389206D01*
G01X1487856Y395173D02*
Y388729D01*
G01X1486706Y389206D02*
X1484700Y387200D01*
G01X1487856Y388729D02*
X1485850Y386723D01*
G01X1484700Y387200D02*
Y376324D01*
G01X1485850Y386723D02*
Y376801D01*
G01X1484700Y376324D02*
X1486824Y374200D01*
G01X1485850Y376801D02*
X1487301Y375350D01*
G01X1486824Y374200D02*
X1500417D01*
G01X1503067D02*
X1504573D01*
G01X1487301Y375350D02*
X1505050D01*
G01X1503067Y374200D02*
X1504573D01*
G01D02*
X1505528Y373245D01*
G01X1505050Y375350D02*
X1506678Y373722D01*
G01X1505528Y373245D02*
Y372326D01*
G01X1506678Y373722D02*
Y372803D01*
G01X1505528Y372326D02*
X1506482Y371372D01*
G01X1506678Y372803D02*
X1506959Y372522D01*
G01X1506482Y371372D02*
X1507401D01*
G01X1506959Y372522D02*
X1507878D01*
G01X1507401Y371372D02*
X1508356Y370417D01*
G01X1507878Y372522D02*
X1509506Y370894D01*
G01X1508356Y370417D02*
Y369498D01*
G01X1509506Y370894D02*
Y369975D01*
G01X1508356Y369498D02*
X1509310Y368544D01*
G01X1509506Y369975D02*
X1509787Y369694D01*
G01X1508356Y369498D02*
X1509310Y368544D01*
G01D02*
X1510229D01*
G01X1509787Y369694D02*
X1510706D01*
G01X1509310Y368544D02*
X1510229D01*
G01D02*
X1510860Y367913D01*
G01X1510706Y369694D02*
X1512020Y368380D01*
G01X1510860Y367913D02*
Y365993D01*
G01Y363343D02*
Y361993D01*
G01Y359343D02*
Y357993D01*
G01Y355343D02*
Y354313D01*
G01X1512020Y368380D02*
Y354780D01*
G01X1510860Y354313D02*
X1513763Y351410D01*
G01X1512020Y354780D02*
X1514913Y351887D01*
G01X1513763Y351410D02*
Y348909D01*
G01X1514913Y351887D02*
Y349386D01*
G01X1513763Y348909D02*
X1514909Y347763D01*
G01X1515864Y345889D02*
X1516783D01*
G01D02*
X1519672Y343000D01*
G01X1514913Y349386D02*
X1520149Y344150D01*
G01X1519672Y343000D02*
X1530900D01*
G01X1520149Y344150D02*
X1531377D01*
G01X1484677Y404900D02*
X1487050Y402527D01*
G01X1484200Y403750D02*
X1485900Y402050D01*
G01X1487050Y402527D02*
Y399949D01*
G01X1485900Y402050D02*
Y400426D01*
G01X1487050Y399949D02*
X1485906Y398805D01*
G01X1485900Y400426D02*
X1484756Y399282D01*
G01X1485906Y398805D02*
Y397123D01*
G01X1484756Y399282D02*
Y396646D01*
G01X1485906Y397123D02*
X1487856Y395173D01*
G01X1484756Y396646D02*
X1486706Y394696D01*
G01X1487856Y395173D02*
Y388729D01*
G01X1486706Y394696D02*
Y389206D01*
G01X1487856Y388729D02*
X1485850Y386723D01*
G01X1486706Y389206D02*
X1484700Y387200D01*
G01X1485850Y386723D02*
Y376801D01*
G01X1484700Y387200D02*
Y376324D01*
G01X1485850Y376801D02*
X1487301Y375350D01*
G01X1484700Y376324D02*
X1486824Y374200D01*
G01X1487301Y375350D02*
X1505050D01*
G01X1486824Y374200D02*
X1500417D01*
G01X1487301Y375350D02*
X1505050D01*
G01D02*
X1506678Y373722D01*
G01X1503067Y374200D02*
X1504573D01*
G01X1505050Y375350D02*
X1506678Y373722D01*
G01X1504573Y374200D02*
X1505528Y373245D01*
G01X1506678Y373722D02*
Y372803D01*
G01X1505528Y373245D02*
Y372326D01*
G01X1506678Y372803D02*
X1506959Y372522D01*
G01X1505528Y372326D02*
X1506482Y371372D01*
G01X1506959Y372522D02*
X1507878D01*
G01X1506482Y371372D02*
X1507401D01*
G01X1507878Y372522D02*
X1509506Y370894D01*
G01X1507401Y371372D02*
X1508356Y370417D01*
G01X1509506Y370894D02*
Y369975D01*
G01X1508356Y370417D02*
Y369498D01*
G01X1509506Y369975D02*
X1509787Y369694D01*
G01D02*
X1510706D01*
G01X1508356Y369498D02*
X1509310Y368544D01*
G01X1509787Y369694D02*
X1510706D01*
G01D02*
X1512020Y368380D01*
G01X1509310Y368544D02*
X1510229D01*
G01X1510706Y369694D02*
X1512020Y368380D01*
G01X1510229Y368544D02*
X1510860Y367913D01*
G01X1512020Y368380D02*
Y354780D01*
G01X1510860Y367913D02*
Y365993D01*
G01X1512020Y368380D02*
Y354780D01*
G01X1510860Y363343D02*
Y361993D01*
G01X1512020Y368380D02*
Y354780D01*
G01X1510860Y359343D02*
Y357993D01*
G01X1512020Y368380D02*
Y354780D01*
G01X1510860Y355343D02*
Y354313D01*
G01X1512020Y354780D02*
X1514913Y351887D01*
G01X1510860Y354313D02*
X1513763Y351410D01*
G01X1514913Y351887D02*
Y349386D01*
G01X1513763Y351410D02*
Y348909D01*
G01X1514913Y349386D02*
X1520149Y344150D01*
G01X1513763Y348909D02*
X1514909Y347763D01*
G01X1514913Y349386D02*
X1520149Y344150D01*
G01X1515864Y345889D02*
X1516783D01*
G01X1514913Y349386D02*
X1520149Y344150D01*
G01X1516783Y345889D02*
X1519672Y343000D01*
G01X1520149Y344150D02*
X1531377D01*
G01X1519672Y343000D02*
X1530900D01*
G01X1470125Y449272D02*
Y445798D01*
G01X1471275Y449272D02*
Y446275D01*
G01X1470125Y445798D02*
X1474977Y440945D01*
G01X1471275Y446275D02*
X1475925Y441625D01*
G01X1474977Y440945D02*
X1476763Y437332D01*
G01X1475925Y441625D02*
X1477990Y437445D01*
G01X1476763Y437332D02*
X1476236Y435463D01*
G01X1477990Y437445D02*
X1477439Y435490D01*
G01X1476236Y435463D02*
X1477252Y432390D01*
G01X1477439Y435490D02*
X1478448Y432436D01*
G01X1477252Y432390D02*
X1476828Y430671D01*
G01X1478449Y432436D02*
X1478028Y430727D01*
G01X1476828Y430671D02*
X1477316Y429264D01*
G01X1478026Y430727D02*
X1478506Y429344D01*
G01X1477316Y429264D02*
X1476081Y423175D01*
G01X1478506Y429344D02*
X1477180Y422808D01*
G01X1476081Y423175D02*
X1474194Y419213D01*
G01X1477180Y422808D02*
X1475018Y418266D01*
G01X1474194Y419213D02*
X1470587Y418072D01*
G01X1475018Y418266D02*
X1470655Y416887D01*
G01X1470587Y418072D02*
X1467849Y418604D01*
G01X1470655Y416887D02*
X1467947Y417413D01*
G01D02*
X1465991Y416686D01*
G01X1471275Y449272D02*
Y446275D01*
G01X1470125Y449272D02*
Y445798D01*
G01X1471275Y446275D02*
X1475925Y441625D01*
G01X1470125Y445798D02*
X1474977Y440945D01*
G01X1475925Y441625D02*
X1477990Y437445D01*
G01X1474977Y440945D02*
X1476763Y437332D01*
G01X1477990Y437445D02*
X1477439Y435490D01*
G01X1476763Y437332D02*
X1476236Y435463D01*
G01X1477439Y435490D02*
X1478448Y432436D01*
G01X1476236Y435463D02*
X1477252Y432390D01*
G01X1478449Y432436D02*
X1478028Y430727D01*
G01X1477252Y432390D02*
X1476828Y430671D01*
G01X1478026Y430727D02*
X1478506Y429344D01*
G01X1476828Y430671D02*
X1477316Y429264D01*
G01X1478506Y429344D02*
X1477180Y422808D01*
G01X1477316Y429264D02*
X1476081Y423175D01*
G01X1477180Y422808D02*
X1475018Y418266D01*
G01X1476081Y423175D02*
X1474194Y419213D01*
G01X1475018Y418266D02*
X1470655Y416887D01*
G01X1474194Y419213D02*
X1470587Y418072D01*
G01X1470655Y416887D02*
X1467947Y417413D01*
G01X1470587Y418072D02*
X1467849Y418604D01*
G01X1467947Y417413D02*
X1465991Y416686D01*
G01X1467967Y441706D02*
X1469184Y439164D01*
G01X1470328Y436774D02*
X1470911Y435556D01*
G01X1468920Y442380D02*
X1471784Y436396D01*
G01X1470911Y435556D02*
X1474071Y433890D01*
G01X1471784Y436396D02*
X1475018Y434691D01*
G01X1474071Y433890D02*
X1474600Y432288D01*
G01X1475018Y434691D02*
X1475796Y432334D01*
G01X1474600Y432288D02*
X1474170Y430549D01*
G01X1475796Y432334D02*
X1475369Y430604D01*
G01X1474170Y430549D02*
X1474678Y429087D01*
G01X1475369Y430604D02*
X1475868Y429167D01*
G01X1474678Y429087D02*
X1474385Y427643D01*
G01X1475868Y429167D02*
X1475660Y428137D01*
G01X1474678Y429087D02*
X1474385Y427643D01*
G01X1475659Y428136D02*
X1475455Y427129D01*
G01X1474385Y427643D02*
X1473342Y426391D01*
G01X1475455Y427129D02*
X1473981Y425361D01*
G01X1473342Y426391D02*
X1471496Y425950D01*
G01X1468792Y425304D02*
X1467430Y424979D01*
G01X1468920Y442380D02*
X1471784Y436396D01*
G01X1467967Y441706D02*
X1469184Y439164D01*
G01X1468920Y442380D02*
X1471784Y436396D01*
G01X1470328Y436774D02*
X1470911Y435556D01*
G01X1471784Y436396D02*
X1475018Y434691D01*
G01X1470911Y435556D02*
X1474071Y433890D01*
G01X1475018Y434691D02*
X1475796Y432334D01*
G01X1474071Y433890D02*
X1474600Y432288D01*
G01X1475796Y432334D02*
X1475369Y430604D01*
G01X1474600Y432288D02*
X1474170Y430549D01*
G01X1475369Y430604D02*
X1475868Y429167D01*
G01X1474170Y430549D02*
X1474678Y429087D01*
G01X1475868Y429167D02*
X1475660Y428137D01*
G01X1475659Y428136D02*
X1475455Y427129D01*
G01X1474678Y429087D02*
X1474385Y427643D01*
G01X1475455Y427129D02*
X1473981Y425361D01*
G01X1474385Y427643D02*
X1473342Y426391D01*
G01D02*
X1471496Y425950D01*
G01X1468792Y425304D02*
X1467430Y424979D01*
G01X1468457Y407698D02*
Y408335D01*
G01X1467307Y407698D02*
Y408812D01*
G01X1468457Y408335D02*
X1469122Y409000D01*
G01X1467307Y408812D02*
X1468645Y410150D01*
G01X1469122Y409000D02*
X1474000D01*
G01X1468645Y410150D02*
X1474477D01*
G01X1474000Y409000D02*
X1474955Y408045D01*
G01X1476828Y406172D02*
X1479250Y403750D01*
G01X1474477Y410150D02*
X1479727Y404900D01*
G01X1479250Y403750D02*
X1484200D01*
G01X1479727Y404900D02*
X1484677D01*
G01X1467307Y407698D02*
Y408812D01*
G01X1468457Y407698D02*
Y408335D01*
G01X1467307Y408812D02*
X1468645Y410150D01*
G01X1468457Y408335D02*
X1469122Y409000D01*
G01X1468645Y410150D02*
X1474477D01*
G01X1469122Y409000D02*
X1474000D01*
G01X1474477Y410150D02*
X1479727Y404900D01*
G01X1474000Y409000D02*
X1474955Y408045D01*
G01X1474477Y410150D02*
X1479727Y404900D01*
G01X1476828Y406172D02*
X1479250Y403750D01*
G01X1479727Y404900D02*
X1484677D01*
G01X1479250Y403750D02*
X1484200D01*
G01X1596088Y543454D02*
X1508969Y526131D01*
G01D02*
X1503691Y527409D01*
G01D02*
X1499745Y526291D01*
G01D02*
X1495437Y527623D01*
G01D02*
X1490690Y526253D01*
G01D02*
X1484994Y527317D01*
G01D02*
X1480896Y526175D01*
G01D02*
X1477199Y523254D01*
G01X1480364Y527222D02*
X1476706Y524331D01*
G01X1477199Y523254D02*
X1474423Y522717D01*
G01X1476706Y524331D02*
X1474110Y523828D01*
G01X1474423Y522717D02*
X1465587Y519681D01*
G01X1474110Y523828D02*
X1465520Y520875D01*
G01X1596088Y543454D02*
X1508969Y526131D01*
G01D02*
X1503691Y527409D01*
G01D02*
X1499745Y526291D01*
G01D02*
X1495437Y527623D01*
G01D02*
X1490690Y526253D01*
G01D02*
X1484994Y527317D01*
G01D02*
X1480896Y526175D01*
G01X1480364Y527222D02*
X1476706Y524331D01*
G01X1480896Y526175D02*
X1477199Y523254D01*
G01X1476706Y524331D02*
X1474110Y523828D01*
G01X1477199Y523254D02*
X1474423Y522717D01*
G01X1474110Y523828D02*
X1465520Y520875D01*
G01X1474423Y522717D02*
X1465587Y519681D01*
G01X1471959Y529559D02*
X1467094Y525797D01*
G01X1471959Y529559D02*
X1467094Y525797D01*
G01X1537671Y527338D02*
X1504244Y520374D01*
G01X1537667Y528512D02*
X1504322Y521565D01*
G01X1504244Y520374D02*
X1499347Y522084D01*
G01X1504322Y521565D02*
X1499898Y523110D01*
G01X1499347Y522084D02*
X1496493Y524252D01*
G01X1499898Y523110D02*
X1497027Y525291D01*
G01X1496493Y524252D02*
X1494715Y524802D01*
G01X1497027Y525291D02*
X1494726Y526003D01*
G01X1494715Y524802D02*
X1491694Y523929D01*
G01X1494726Y526003D02*
X1491179Y524978D01*
G01X1491694Y523929D02*
X1484789Y518890D01*
G01X1491179Y524978D02*
X1484318Y519971D01*
G01X1484789Y518890D02*
X1481628Y518279D01*
G01X1484318Y519971D02*
X1481650Y519455D01*
G01X1481628Y518279D02*
X1474307Y519981D01*
G01X1481650Y519455D02*
X1474246Y521177D01*
G01X1474307Y519981D02*
X1465735Y517036D01*
G01X1474246Y521177D02*
X1465668Y518230D01*
G01X1467319Y512032D02*
X1474148Y513187D01*
G01X1466994Y513144D02*
X1474218Y514366D01*
G01X1474148Y513187D02*
X1481066Y511154D01*
G01X1474218Y514366D02*
X1481113Y512339D01*
G01X1481066Y511154D02*
X1488260Y512659D01*
G01X1481113Y512339D02*
X1488276Y513838D01*
G01X1488260Y512659D02*
X1498478Y510220D01*
G01X1488276Y513838D02*
X1498614Y511370D01*
G01X1498478Y510220D02*
X1502744D01*
G01X1498614Y511370D02*
X1502413D01*
G01X1502744Y510220D02*
X1508273Y513680D01*
G01X1502413Y511370D02*
X1507809Y514747D01*
G01X1508273Y513680D02*
X1516973Y516002D01*
G01X1507809Y514747D02*
X1516524Y517073D01*
G01X1516973Y516002D02*
X1518683Y517010D01*
G01X1516524Y517073D02*
X1517687Y517759D01*
G01X1518684Y517012D02*
X1528543Y522831D01*
G01X1519969Y519106D02*
X1521131Y519792D01*
G01X1518684Y517012D02*
X1528543Y522831D01*
G01X1523413Y521139D02*
X1528122Y523918D01*
G01X1529698Y520467D02*
X1525246Y517839D01*
G01X1529277Y521554D02*
X1524396Y518673D01*
G01X1525246Y517839D02*
X1520308Y509093D01*
G01X1524396Y518673D02*
X1519456Y509925D01*
G01X1520308Y509093D02*
X1513242Y504874D01*
G01X1519456Y509925D02*
X1512924Y506024D01*
G01X1513242Y504874D02*
X1508207D01*
G01X1512924Y506024D02*
X1507919D01*
G01X1508207Y504874D02*
X1502481Y501820D01*
G01X1507919Y506024D02*
X1502053Y502896D01*
G01X1502481Y501820D02*
X1499107Y500876D01*
G01X1502053Y502896D02*
X1499091Y502066D01*
G01X1499107Y500876D02*
X1484897Y504455D01*
G01X1499091Y502066D02*
X1484918Y505636D01*
G01X1484897Y504455D02*
X1480869Y503597D01*
G01X1484918Y505636D02*
X1480874Y504774D01*
G01X1480869Y503597D02*
X1477926Y504249D01*
G01X1480874Y504774D02*
X1477945Y505423D01*
G01X1477926Y504249D02*
X1465894Y501985D01*
G01X1477945Y505423D02*
X1465997Y503175D01*
G01X1465666Y499347D02*
X1477884Y501646D01*
G01X1465769Y500537D02*
X1477903Y502820D01*
G01X1477884Y501646D02*
X1480858Y500986D01*
G01X1477903Y502820D02*
X1480863Y502164D01*
G01X1480858Y500986D02*
X1484847Y501837D01*
G01X1480863Y502164D02*
X1484869Y503018D01*
G01X1484847Y501837D02*
X1511813Y495045D01*
G01X1484869Y503018D02*
X1511840Y496225D01*
G01X1511813Y495046D02*
X1515656Y495827D01*
G01X1511840Y496225D02*
X1515208Y496910D01*
G01X1515656Y495827D02*
X1519006Y498044D01*
G01X1515208Y496910D02*
X1518176Y498874D01*
G01X1519006Y498044D02*
X1523164Y504325D01*
G01X1518176Y498874D02*
X1522081Y504774D01*
G01X1523164Y504325D02*
X1524585Y511312D01*
G01X1522081Y504774D02*
X1523494Y511719D01*
G01X1524585Y511312D02*
X1527277Y516075D01*
G01X1523494Y511719D02*
X1526425Y516909D01*
G01D02*
X1530210Y519144D01*
G01X1537667Y528512D02*
X1504322Y521565D01*
G01X1537671Y527338D02*
X1504244Y520374D01*
G01X1504322Y521565D02*
X1499898Y523110D01*
G01X1504244Y520374D02*
X1499347Y522084D01*
G01X1499898Y523110D02*
X1497027Y525291D01*
G01X1499347Y522084D02*
X1496493Y524252D01*
G01X1497027Y525291D02*
X1494726Y526003D01*
G01X1496493Y524252D02*
X1494715Y524802D01*
G01X1494726Y526003D02*
X1491179Y524978D01*
G01X1494715Y524802D02*
X1491694Y523929D01*
G01X1491179Y524978D02*
X1484318Y519971D01*
G01X1491694Y523929D02*
X1484789Y518890D01*
G01X1484318Y519971D02*
X1481650Y519455D01*
G01X1484789Y518890D02*
X1481628Y518279D01*
G01X1481650Y519455D02*
X1474246Y521177D01*
G01X1481628Y518279D02*
X1474307Y519981D01*
G01X1474246Y521177D02*
X1465668Y518230D01*
G01X1474307Y519981D02*
X1465735Y517036D01*
G01X1466994Y513144D02*
X1474218Y514366D01*
G01X1467319Y512032D02*
X1474148Y513187D01*
G01X1474218Y514366D02*
X1481113Y512339D01*
G01X1474148Y513187D02*
X1481066Y511154D01*
G01X1481113Y512339D02*
X1488276Y513838D01*
G01X1481066Y511154D02*
X1488260Y512659D01*
G01X1488276Y513838D02*
X1498614Y511370D01*
G01X1488260Y512659D02*
X1498478Y510220D01*
G01X1498614Y511370D02*
X1502413D01*
G01X1498478Y510220D02*
X1502744D01*
G01X1502413Y511370D02*
X1507809Y514747D01*
G01X1502744Y510220D02*
X1508273Y513680D01*
G01X1507809Y514747D02*
X1516524Y517073D01*
G01X1508273Y513680D02*
X1516973Y516002D01*
G01X1516524Y517073D02*
X1517687Y517759D01*
G01X1516973Y516002D02*
X1518683Y517010D01*
G01X1519969Y519106D02*
X1521131Y519792D01*
G01X1523413Y521139D02*
X1528122Y523918D01*
G01X1518684Y517012D02*
X1528543Y522831D01*
G01X1529277Y521554D02*
X1524396Y518673D01*
G01X1529698Y520467D02*
X1525246Y517839D01*
G01X1524396Y518673D02*
X1519456Y509925D01*
G01X1525246Y517839D02*
X1520308Y509093D01*
G01X1519456Y509925D02*
X1512924Y506024D01*
G01X1520308Y509093D02*
X1513242Y504874D01*
G01X1512924Y506024D02*
X1507919D01*
G01X1513242Y504874D02*
X1508207D01*
G01X1507919Y506024D02*
X1502053Y502896D01*
G01X1508207Y504874D02*
X1502481Y501820D01*
G01X1502053Y502896D02*
X1499091Y502066D01*
G01X1502481Y501820D02*
X1499107Y500876D01*
G01X1499091Y502066D02*
X1484918Y505636D01*
G01X1499107Y500876D02*
X1484897Y504455D01*
G01X1484918Y505636D02*
X1480874Y504774D01*
G01X1484897Y504455D02*
X1480869Y503597D01*
G01X1480874Y504774D02*
X1477945Y505423D01*
G01X1480869Y503597D02*
X1477926Y504249D01*
G01X1477945Y505423D02*
X1465997Y503175D01*
G01X1477926Y504249D02*
X1465894Y501985D01*
G01X1465769Y500537D02*
X1477903Y502820D01*
G01X1465666Y499347D02*
X1477884Y501646D01*
G01X1477903Y502820D02*
X1480863Y502164D01*
G01X1477884Y501646D02*
X1480858Y500986D01*
G01X1480863Y502164D02*
X1484869Y503018D01*
G01X1480858Y500986D02*
X1484847Y501837D01*
G01X1484869Y503018D02*
X1511840Y496225D01*
G01X1484847Y501837D02*
X1511813Y495045D01*
G01X1511840Y496225D02*
X1515208Y496910D01*
G01X1511813Y495046D02*
X1515656Y495827D01*
G01X1515208Y496910D02*
X1518176Y498874D01*
G01X1515656Y495827D02*
X1519006Y498044D01*
G01X1518176Y498874D02*
X1522081Y504774D01*
G01X1519006Y498044D02*
X1523164Y504325D01*
G01X1522081Y504774D02*
X1523494Y511719D01*
G01X1523164Y504325D02*
X1524585Y511312D01*
G01X1523494Y511719D02*
X1526425Y516909D01*
G01X1524585Y511312D02*
X1527277Y516075D01*
G01X1526425Y516909D02*
X1530210Y519144D01*
G01X1513660Y549505D02*
X1515151Y548014D01*
G01X1514137Y550655D02*
X1515628Y549164D01*
G01X1515151Y548014D02*
X1545826D01*
G01X1515628Y549164D02*
X1545349D01*
G01X1514137Y550655D02*
X1515628Y549164D01*
G01X1513660Y549505D02*
X1515151Y548014D01*
G01X1515628Y549164D02*
X1545349D01*
G01X1515151Y548014D02*
X1545826D01*
G01X1596089Y544627D02*
X1508992Y527309D01*
G01D02*
X1503666Y528599D01*
G01D02*
X1499759Y527491D01*
G01D02*
X1495448Y528824D01*
G01D02*
X1490633Y527434D01*
G01D02*
X1484943Y528497D01*
G01D02*
X1480364Y527222D01*
G01X1467195Y539263D02*
X1475537Y544004D01*
G01X1467607Y538174D02*
X1475970Y542927D01*
G01X1475537Y544004D02*
X1482579Y545785D01*
G01X1475970Y542927D02*
X1482563Y544594D01*
G01X1482579Y545785D02*
X1486106Y544793D01*
G01X1482563Y544594D02*
X1485594Y543742D01*
G01X1486106Y544793D02*
X1490788Y541354D01*
G01X1485594Y543742D02*
X1490299Y540286D01*
G01X1490788Y541354D02*
X1495846Y540198D01*
G01X1490299Y540286D02*
X1495842Y539019D01*
G01X1495846Y540198D02*
X1500735Y541281D01*
G01X1495842Y539019D02*
X1500683Y540091D01*
G01X1500735Y541281D02*
X1505976Y539632D01*
G01X1500683Y540091D02*
X1505912Y538446D01*
G01X1505976Y539632D02*
X1511740Y540778D01*
G01X1505912Y538446D02*
X1511691Y539595D01*
G01X1511740Y540778D02*
X1520390Y538305D01*
G01X1511691Y539595D02*
X1520341Y537122D01*
G01X1520390Y538305D02*
X1594128Y552970D01*
G01X1520341Y537122D02*
X1529997Y539042D01*
G01X1520390Y538305D02*
X1594128Y552970D01*
G01X1520390Y538305D02*
X1594128Y552970D01*
G01X1520390Y538305D02*
X1594128Y552970D01*
G01X1520390Y538305D02*
X1594128Y552970D01*
G01X1596010Y548819D02*
X1521797Y534053D01*
G01X1596011Y549992D02*
X1521845Y535236D01*
G01X1521797Y534053D02*
X1511611Y536964D01*
G01X1521845Y535236D02*
X1511660Y538147D01*
G01X1511611Y536964D02*
X1505841Y535816D01*
G01X1511660Y538147D02*
X1505906Y537002D01*
G01X1505841Y535816D02*
X1500610Y537463D01*
G01X1505906Y537002D02*
X1500662Y538653D01*
G01X1500610Y537463D02*
X1495704Y536376D01*
G01X1500662Y538653D02*
X1495708Y537555D01*
G01X1495704Y536376D02*
X1489330Y537833D01*
G01X1495708Y537555D02*
X1489820Y538901D01*
G01X1489330Y537833D02*
X1484458Y541412D01*
G01X1489820Y538901D02*
X1484969Y542464D01*
G01X1484458Y541412D02*
X1482456Y541975D01*
G01X1484969Y542464D02*
X1482471Y543166D01*
G01X1482456Y541975D02*
X1477047Y540605D01*
G01X1482471Y543166D02*
X1476614Y541682D01*
G01X1477047Y540605D02*
X1468521Y535761D01*
G01X1476614Y541682D02*
X1468109Y536850D01*
G01X1596089Y544627D02*
X1508992Y527309D01*
G01D02*
X1503666Y528599D01*
G01D02*
X1499759Y527491D01*
G01D02*
X1495448Y528824D01*
G01D02*
X1490633Y527434D01*
G01D02*
X1484943Y528497D01*
G01D02*
X1480364Y527222D01*
G01X1467607Y538174D02*
X1475970Y542927D01*
G01X1467195Y539263D02*
X1475537Y544004D01*
G01X1475970Y542927D02*
X1482563Y544594D01*
G01X1475537Y544004D02*
X1482579Y545785D01*
G01X1482563Y544594D02*
X1485594Y543742D01*
G01X1482579Y545785D02*
X1486106Y544793D01*
G01X1485594Y543742D02*
X1490299Y540286D01*
G01X1486106Y544793D02*
X1490788Y541354D01*
G01X1490299Y540286D02*
X1495842Y539019D01*
G01X1490788Y541354D02*
X1495846Y540198D01*
G01X1495842Y539019D02*
X1500683Y540091D01*
G01X1495846Y540198D02*
X1500735Y541281D01*
G01X1500683Y540091D02*
X1505912Y538446D01*
G01X1500735Y541281D02*
X1505976Y539632D01*
G01X1505912Y538446D02*
X1511691Y539595D01*
G01X1505976Y539632D02*
X1511740Y540778D01*
G01X1511691Y539595D02*
X1520341Y537122D01*
G01X1511740Y540778D02*
X1520390Y538305D01*
G01X1520341Y537122D02*
X1529997Y539042D01*
G01X1520390Y538305D02*
X1594128Y552970D01*
G01X1596011Y549992D02*
X1521845Y535236D01*
G01X1596010Y548819D02*
X1521797Y534053D01*
G01X1521845Y535236D02*
X1511660Y538147D01*
G01X1521797Y534053D02*
X1511611Y536964D01*
G01X1511660Y538147D02*
X1505906Y537002D01*
G01X1511611Y536964D02*
X1505841Y535816D01*
G01X1505906Y537002D02*
X1500662Y538653D01*
G01X1505841Y535816D02*
X1500610Y537463D01*
G01X1500662Y538653D02*
X1495708Y537555D01*
G01X1500610Y537463D02*
X1495704Y536376D01*
G01X1495708Y537555D02*
X1489820Y538901D01*
G01X1495704Y536376D02*
X1489330Y537833D01*
G01X1489820Y538901D02*
X1484969Y542464D01*
G01X1489330Y537833D02*
X1484458Y541412D01*
G01X1484969Y542464D02*
X1482471Y543166D01*
G01X1484458Y541412D02*
X1482456Y541975D01*
G01X1482471Y543166D02*
X1476614Y541682D01*
G01X1482456Y541975D02*
X1477047Y540605D01*
G01X1476614Y541682D02*
X1468109Y536850D01*
G01X1477047Y540605D02*
X1468521Y535761D01*
G01X1596121Y546178D02*
X1521809Y531397D01*
G01X1596122Y547351D02*
X1521858Y532580D01*
G01X1521809Y531397D02*
X1519194Y532145D01*
G01X1516646Y532873D02*
X1515348Y533244D01*
G01X1512800Y533973D02*
X1511502Y534344D01*
G01X1521858Y532580D02*
X1511550Y535527D01*
G01X1511502Y534344D02*
X1505582Y533165D01*
G01X1511550Y535527D02*
X1505646Y534351D01*
G01X1505582Y533165D02*
X1500382Y534800D01*
G01X1505646Y534351D02*
X1500434Y535990D01*
G01X1500382Y534800D02*
X1493984Y533383D01*
G01X1500434Y535990D02*
X1493979Y534560D01*
G01Y533383D02*
X1492659Y533665D01*
G01X1490067Y534218D02*
X1488747Y534500D01*
G01X1486155Y535053D02*
X1479179Y536542D01*
G01X1493979Y534560D02*
X1479151Y537724D01*
G01X1479179Y536542D02*
X1476952Y535957D01*
G01X1479151Y537724D02*
X1476465Y537019D01*
G01X1476952Y535957D02*
X1475469Y534935D01*
G01X1476465Y537019D02*
X1474629Y535754D01*
G01X1475469Y534935D02*
X1471959Y529559D01*
G01X1474629Y535754D02*
X1471101Y530351D01*
G01D02*
X1466581Y526855D01*
G01X1596122Y547351D02*
X1521858Y532580D01*
G01X1596121Y546178D02*
X1521809Y531397D01*
G01X1521858Y532580D02*
X1511550Y535527D01*
G01X1521809Y531397D02*
X1519194Y532145D01*
G01X1521858Y532580D02*
X1511550Y535527D01*
G01X1516646Y532873D02*
X1515348Y533244D01*
G01X1521858Y532580D02*
X1511550Y535527D01*
G01X1512800Y533973D02*
X1511502Y534344D01*
G01X1511550Y535527D02*
X1505646Y534351D01*
G01X1511502Y534344D02*
X1505582Y533165D01*
G01X1505646Y534351D02*
X1500434Y535990D01*
G01X1505582Y533165D02*
X1500382Y534800D01*
G01X1500434Y535990D02*
X1493979Y534560D01*
G01X1500382Y534800D02*
X1493984Y533383D01*
G01X1493979Y534560D02*
X1479151Y537724D01*
G01X1493979Y533383D02*
X1492659Y533665D01*
G01X1493979Y534560D02*
X1479151Y537724D01*
G01X1490067Y534218D02*
X1488747Y534500D01*
G01X1493979Y534560D02*
X1479151Y537724D01*
G01X1486155Y535053D02*
X1479179Y536542D01*
G01X1479151Y537724D02*
X1476465Y537019D01*
G01X1479179Y536542D02*
X1476952Y535957D01*
G01X1476465Y537019D02*
X1474629Y535754D01*
G01X1476952Y535957D02*
X1475469Y534935D01*
G01X1474629Y535754D02*
X1471101Y530351D01*
G01X1475469Y534935D02*
X1471959Y529559D01*
G01X1471101Y530351D02*
X1466581Y526855D01*
G01X1517183Y648661D02*
X1515395D01*
G01X1515442Y649811D02*
X1510987Y650168D01*
G01X1515395Y648661D02*
X1511120Y649003D01*
G01X1510987Y650168D02*
X1507316Y649001D01*
G01X1511120Y649003D02*
X1508016Y648016D01*
G01X1507316Y649001D02*
X1506335Y647693D01*
G01X1508016Y648016D02*
X1507394Y647186D01*
G01X1506335Y647693D02*
X1506091Y646732D01*
G01X1507394Y647186D02*
X1507217Y646490D01*
G01X1506091Y646732D02*
X1505755Y644822D01*
G01X1507217Y646490D02*
X1506806Y644153D01*
G01X1505755Y644822D02*
X1505234Y644457D01*
G01D02*
X1504200Y644639D01*
G01X1506806Y644153D02*
X1505504Y643241D01*
G01X1505234Y644457D02*
X1504200Y644639D01*
G01X1505504Y643241D02*
X1503530Y643588D01*
G01X1504200Y644639D02*
X1503835Y645161D01*
G01X1503530Y643588D02*
X1502619Y644892D01*
G01X1503835Y645161D02*
X1505319Y653568D01*
G01X1502619Y644892D02*
X1504103Y653298D01*
G01X1501133Y654311D02*
X1499448Y644761D01*
G01X1502183Y653642D02*
X1500499Y644092D01*
G01X1499448Y644761D02*
X1498925Y644394D01*
G01D02*
X1497892Y644576D01*
G01X1500499Y644092D02*
X1499195Y643178D01*
G01X1498925Y644394D02*
X1497892Y644576D01*
G01X1499195Y643178D02*
X1497221Y643526D01*
G01X1497892Y644576D02*
X1497528Y645099D01*
G01X1497221Y643526D02*
X1496312Y644831D01*
G01X1497528Y645099D02*
X1499020Y653553D01*
G01X1496312Y644831D02*
X1497804Y653284D01*
G01X1494832Y654292D02*
X1493153Y644758D01*
G01X1495882Y653622D02*
X1494204Y644088D01*
G01X1493153Y644758D02*
X1492631Y644393D01*
G01D02*
X1491598Y644574D01*
G01X1494204Y644088D02*
X1492901Y643178D01*
G01X1492631Y644393D02*
X1491598Y644574D01*
G01X1492901Y643178D02*
X1490929Y643523D01*
G01X1491598Y644574D02*
X1491233Y645096D01*
G01X1490929Y643523D02*
X1490017Y644827D01*
G01X1491233Y645096D02*
X1492724Y653552D01*
G01X1490017Y644827D02*
X1491508Y653283D01*
G01X1488536Y654291D02*
X1486854Y644739D01*
G01X1489587Y653621D02*
X1487904Y644069D01*
G01X1486854Y644739D02*
X1486332Y644375D01*
G01D02*
X1485299Y644556D01*
G01X1487904Y644069D02*
X1486601Y643160D01*
G01X1486332Y644375D02*
X1485299Y644556D01*
G01X1486601Y643160D02*
X1484632Y643505D01*
G01X1485299Y644556D02*
X1484933Y645076D01*
G01X1484632Y643505D02*
X1483717Y644805D01*
G01X1484933Y645076D02*
X1486433Y653585D01*
G01X1483717Y644805D02*
X1485217Y653316D01*
G01X1482249Y654324D02*
X1480558Y644742D01*
G01X1483299Y653655D02*
X1481609Y644074D01*
G01X1480558Y644742D02*
X1480035Y644374D01*
G01D02*
X1479001Y644557D01*
G01X1481609Y644074D02*
X1480306Y643158D01*
G01X1480035Y644374D02*
X1479001Y644557D01*
G01X1480306Y643158D02*
X1478332Y643507D01*
G01X1479001Y644557D02*
X1478636Y645078D01*
G01X1478332Y643507D02*
X1477420Y644808D01*
G01X1478636Y645078D02*
X1480136Y653586D01*
G01X1477420Y644808D02*
X1478920Y653315D01*
G01X1475951Y654325D02*
X1474282Y644855D01*
G01X1477001Y653655D02*
X1475333Y644186D01*
G01X1474282Y644855D02*
X1473759Y644488D01*
G01D02*
X1472726Y644669D01*
G01X1475333Y644186D02*
X1474030Y643272D01*
G01X1473759Y644488D02*
X1472726Y644669D01*
G01X1474030Y643272D02*
X1472056Y643618D01*
G01X1472726Y644669D02*
X1472362Y645191D01*
G01X1472056Y643618D02*
X1471146Y644923D01*
G01X1472362Y645191D02*
X1473839Y653568D01*
G01X1471146Y644923D02*
X1472623Y653299D01*
G01X1469653Y654307D02*
X1467984Y644851D01*
G01X1470703Y653637D02*
X1469034Y644181D01*
G01X1467984Y644851D02*
X1467463Y644487D01*
G01D02*
X1466431Y644669D01*
G01X1469034Y644181D02*
X1467732Y643271D01*
G01X1467463Y644487D02*
X1466431Y644669D01*
G01X1467732Y643271D02*
X1465761Y643618D01*
G01X1466431Y644669D02*
X1466066Y645191D01*
G01D02*
X1467544Y653566D01*
G01X1517183Y648661D02*
X1515395D01*
G01D02*
X1511120Y649003D01*
G01X1515442Y649811D02*
X1510987Y650168D01*
G01X1511120Y649003D02*
X1508016Y648016D01*
G01X1510987Y650168D02*
X1507316Y649001D01*
G01X1508016Y648016D02*
X1507394Y647186D01*
G01X1507316Y649001D02*
X1506335Y647693D01*
G01X1507394Y647186D02*
X1507217Y646490D01*
G01X1506335Y647693D02*
X1506091Y646732D01*
G01X1507217Y646490D02*
X1506806Y644153D01*
G01X1506091Y646732D02*
X1505755Y644822D01*
G01X1506806Y644153D02*
X1505504Y643241D01*
G01X1505755Y644822D02*
X1505234Y644457D01*
G01X1506806Y644153D02*
X1505504Y643241D01*
G01D02*
X1503530Y643588D01*
G01X1505234Y644457D02*
X1504200Y644639D01*
G01X1503530Y643588D02*
X1502619Y644892D01*
G01X1504200Y644639D02*
X1503835Y645161D01*
G01X1502619Y644892D02*
X1504103Y653298D01*
G01X1503835Y645161D02*
X1505319Y653568D01*
G01X1502183Y653642D02*
X1500499Y644092D01*
G01X1501133Y654311D02*
X1499448Y644761D01*
G01X1500499Y644092D02*
X1499195Y643178D01*
G01X1499448Y644761D02*
X1498925Y644394D01*
G01X1500499Y644092D02*
X1499195Y643178D01*
G01D02*
X1497221Y643526D01*
G01X1498925Y644394D02*
X1497892Y644576D01*
G01X1497221Y643526D02*
X1496312Y644831D01*
G01X1497892Y644576D02*
X1497528Y645099D01*
G01X1496312Y644831D02*
X1497804Y653284D01*
G01X1497528Y645099D02*
X1499020Y653553D01*
G01X1495882Y653622D02*
X1494204Y644088D01*
G01X1494832Y654292D02*
X1493153Y644758D01*
G01X1494204Y644088D02*
X1492901Y643178D01*
G01X1493153Y644758D02*
X1492631Y644393D01*
G01X1494204Y644088D02*
X1492901Y643178D01*
G01D02*
X1490929Y643523D01*
G01X1492631Y644393D02*
X1491598Y644574D01*
G01X1490929Y643523D02*
X1490017Y644827D01*
G01X1491598Y644574D02*
X1491233Y645096D01*
G01X1490017Y644827D02*
X1491508Y653283D01*
G01X1491233Y645096D02*
X1492724Y653552D01*
G01X1489587Y653621D02*
X1487904Y644069D01*
G01X1488536Y654291D02*
X1486854Y644739D01*
G01X1487904Y644069D02*
X1486601Y643160D01*
G01X1486854Y644739D02*
X1486332Y644375D01*
G01X1487904Y644069D02*
X1486601Y643160D01*
G01D02*
X1484632Y643505D01*
G01X1486332Y644375D02*
X1485299Y644556D01*
G01X1484632Y643505D02*
X1483717Y644805D01*
G01X1485299Y644556D02*
X1484933Y645076D01*
G01X1483717Y644805D02*
X1485217Y653316D01*
G01X1484933Y645076D02*
X1486433Y653585D01*
G01X1483299Y653655D02*
X1481609Y644074D01*
G01X1482249Y654324D02*
X1480558Y644742D01*
G01X1481609Y644074D02*
X1480306Y643158D01*
G01X1480558Y644742D02*
X1480035Y644374D01*
G01X1481609Y644074D02*
X1480306Y643158D01*
G01D02*
X1478332Y643507D01*
G01X1480035Y644374D02*
X1479001Y644557D01*
G01X1478332Y643507D02*
X1477420Y644808D01*
G01X1479001Y644557D02*
X1478636Y645078D01*
G01X1477420Y644808D02*
X1478920Y653315D01*
G01X1478636Y645078D02*
X1480136Y653586D01*
G01X1477001Y653655D02*
X1475333Y644186D01*
G01X1475951Y654325D02*
X1474282Y644855D01*
G01X1475333Y644186D02*
X1474030Y643272D01*
G01X1474282Y644855D02*
X1473759Y644488D01*
G01X1475333Y644186D02*
X1474030Y643272D01*
G01D02*
X1472056Y643618D01*
G01X1473759Y644488D02*
X1472726Y644669D01*
G01X1472056Y643618D02*
X1471146Y644923D01*
G01X1472726Y644669D02*
X1472362Y645191D01*
G01X1471146Y644923D02*
X1472623Y653299D01*
G01X1472362Y645191D02*
X1473839Y653568D01*
G01X1470703Y653637D02*
X1469034Y644181D01*
G01X1469653Y654307D02*
X1467984Y644851D01*
G01X1469034Y644181D02*
X1467732Y643271D01*
G01X1467984Y644851D02*
X1467463Y644487D01*
G01X1469034Y644181D02*
X1467732Y643271D01*
G01D02*
X1465761Y643618D01*
G01X1467463Y644487D02*
X1466431Y644669D01*
G01D02*
X1466066Y645191D01*
G01D02*
X1467544Y653566D01*
G01X1517183Y649811D02*
X1515442D01*
G01X1505319Y653568D02*
X1504406Y654872D01*
G01X1504103Y653298D02*
X1503736Y653822D01*
G01X1504406Y654872D02*
X1502433Y655221D01*
G01D02*
X1501133Y654311D01*
G01X1503736Y653822D02*
X1502702Y654005D01*
G01X1502433Y655221D02*
X1501133Y654311D01*
G01X1502702Y654005D02*
X1502183Y653642D01*
G01X1499020Y653553D02*
X1498110Y654856D01*
G01X1497804Y653284D02*
X1497440Y653805D01*
G01X1498110Y654856D02*
X1496136Y655202D01*
G01D02*
X1494832Y654292D01*
G01X1497440Y653805D02*
X1496405Y653987D01*
G01X1496136Y655202D02*
X1494832Y654292D01*
G01X1496405Y653987D02*
X1495882Y653622D01*
G01X1492724Y653552D02*
X1491814Y654855D01*
G01X1491508Y653283D02*
X1491144Y653804D01*
G01X1491814Y654855D02*
X1489840Y655201D01*
G01D02*
X1488536Y654291D01*
G01X1491144Y653804D02*
X1490110Y653986D01*
G01X1489840Y655201D02*
X1488536Y654291D01*
G01X1490110Y653986D02*
X1489587Y653621D01*
G01X1486433Y653585D02*
X1485523Y654888D01*
G01X1485217Y653316D02*
X1484853Y653837D01*
G01X1485523Y654888D02*
X1483549Y655235D01*
G01D02*
X1482249Y654324D01*
G01X1484853Y653837D02*
X1483819Y654019D01*
G01X1483549Y655235D02*
X1482249Y654324D01*
G01X1483819Y654019D02*
X1483299Y653655D01*
G01X1480136Y653586D02*
X1479227Y654887D01*
G01X1478920Y653315D02*
X1478557Y653837D01*
G01X1479227Y654887D02*
X1477254Y655235D01*
G01D02*
X1475951Y654325D01*
G01X1478557Y653837D02*
X1477523Y654020D01*
G01X1477254Y655235D02*
X1475951Y654325D01*
G01X1477523Y654020D02*
X1477001Y653655D01*
G01X1473839Y653568D02*
X1472929Y654871D01*
G01X1472623Y653299D02*
X1472259Y653820D01*
G01X1472929Y654871D02*
X1470956Y655216D01*
G01D02*
X1469653Y654307D01*
G01X1472259Y653820D02*
X1471225Y654001D01*
G01X1470956Y655216D02*
X1469653Y654307D01*
G01X1471225Y654001D02*
X1470703Y653637D01*
G01X1467544Y653566D02*
X1466633Y654870D01*
G01X1466328Y653297D02*
X1465963Y653819D01*
G01X1517183Y649811D02*
X1515442D01*
G01X1504103Y653298D02*
X1503736Y653822D01*
G01X1505319Y653568D02*
X1504406Y654872D01*
G01X1503736Y653822D02*
X1502702Y654005D01*
G01X1504406Y654872D02*
X1502433Y655221D01*
G01X1503736Y653822D02*
X1502702Y654005D01*
G01D02*
X1502183Y653642D01*
G01X1502433Y655221D02*
X1501133Y654311D01*
G01X1497804Y653284D02*
X1497440Y653805D01*
G01X1499020Y653553D02*
X1498110Y654856D01*
G01X1497440Y653805D02*
X1496405Y653987D01*
G01X1498110Y654856D02*
X1496136Y655202D01*
G01X1497440Y653805D02*
X1496405Y653987D01*
G01D02*
X1495882Y653622D01*
G01X1496136Y655202D02*
X1494832Y654292D01*
G01X1491508Y653283D02*
X1491144Y653804D01*
G01X1492724Y653552D02*
X1491814Y654855D01*
G01X1491144Y653804D02*
X1490110Y653986D01*
G01X1491814Y654855D02*
X1489840Y655201D01*
G01X1491144Y653804D02*
X1490110Y653986D01*
G01D02*
X1489587Y653621D01*
G01X1489840Y655201D02*
X1488536Y654291D01*
G01X1485217Y653316D02*
X1484853Y653837D01*
G01X1486433Y653585D02*
X1485523Y654888D01*
G01X1484853Y653837D02*
X1483819Y654019D01*
G01X1485523Y654888D02*
X1483549Y655235D01*
G01X1484853Y653837D02*
X1483819Y654019D01*
G01D02*
X1483299Y653655D01*
G01X1483549Y655235D02*
X1482249Y654324D01*
G01X1478920Y653315D02*
X1478557Y653837D01*
G01X1480136Y653586D02*
X1479227Y654887D01*
G01X1478557Y653837D02*
X1477523Y654020D01*
G01X1479227Y654887D02*
X1477254Y655235D01*
G01X1478557Y653837D02*
X1477523Y654020D01*
G01D02*
X1477001Y653655D01*
G01X1477254Y655235D02*
X1475951Y654325D01*
G01X1472623Y653299D02*
X1472259Y653820D01*
G01X1473839Y653568D02*
X1472929Y654871D01*
G01X1472259Y653820D02*
X1471225Y654001D01*
G01X1472929Y654871D02*
X1470956Y655216D01*
G01X1472259Y653820D02*
X1471225Y654001D01*
G01D02*
X1470703Y653637D01*
G01X1470956Y655216D02*
X1469653Y654307D01*
G01X1466328Y653297D02*
X1465963Y653819D01*
G01X1467544Y653566D02*
X1466633Y654870D01*
G01X1568992Y34573D02*
X1578925Y27951D01*
G01X1569630Y35530D02*
X1579745Y28787D01*
G01X1578925Y27951D02*
X1584754Y19564D01*
G01X1579745Y28787D02*
X1585484Y20531D01*
G01X1584754Y19564D02*
X1602228Y13589D01*
G01X1585484Y20531D02*
X1602949Y14558D01*
G01X1557619Y36521D02*
X1563801Y32399D01*
G01Y32398D02*
X1566729Y31813D01*
G01D02*
X1572140Y28207D01*
G01X1567178Y32897D02*
X1572873Y29101D01*
G01X1572140Y28207D02*
X1586272Y14071D01*
G01X1572873Y29101D02*
X1586749Y15221D01*
G01X1586272Y14071D02*
X1592336D01*
G01X1586749Y15221D02*
X1592813D01*
G01X1533491Y38828D02*
X1570258Y26258D01*
G01X1533563Y40019D02*
X1570883Y27260D01*
G01X1570258Y26258D02*
X1575338Y21178D01*
G01X1576292Y19305D02*
X1577211D01*
G01D02*
X1578166Y18350D01*
G01X1570883Y27260D02*
X1578979Y19164D01*
G01X1579121Y16476D02*
X1580040D01*
G01D02*
X1583922Y12594D01*
G01D02*
X1583923D01*
G01X1578980Y19164D02*
X1585073Y13071D01*
G01X1583923Y12594D02*
Y11805D01*
G01X1585073Y13071D02*
Y11805D01*
G01X1534439Y35854D02*
X1566122Y25023D01*
G01X1534511Y37045D02*
X1566747Y26026D01*
G01X1566122Y25023D02*
X1570247Y20898D01*
G01D02*
X1570248D01*
G01D02*
X1574373Y16773D01*
G01X1566747Y26026D02*
X1575523Y17250D01*
G01X1574373Y16773D02*
Y12956D01*
G01X1575523Y17250D02*
Y13176D01*
G01X1534763Y33038D02*
X1555842Y25831D01*
G01X1534835Y34229D02*
X1556467Y26833D01*
G01X1555842Y25831D02*
X1564979Y16694D01*
G01X1556467Y26833D02*
X1566129Y17171D01*
G01X1564979Y16694D02*
Y13056D01*
G01X1566129Y17171D02*
Y13306D01*
G01X1556816Y16323D02*
Y12972D01*
G01X1555666Y12908D02*
Y15846D01*
G01X1553336Y19804D02*
X1556816Y16323D01*
G01X1555666Y15846D02*
X1552763Y18749D01*
G01X1548189Y20897D02*
X1550715Y20361D01*
G01Y20360D02*
X1553336Y19804D01*
G01X1552763Y18749D02*
X1548189Y19721D01*
G01X1543367Y19873D02*
X1548189Y20897D01*
G01Y19721D02*
X1543367Y18697D01*
G01X1540537Y20474D02*
X1543367Y19873D01*
G01Y18697D02*
X1540537Y19298D01*
G01X1529145Y18054D02*
X1540537Y20474D01*
G01Y19298D02*
X1529145Y16878D01*
G01X1546050Y13210D02*
Y14820D01*
G01X1547200Y13240D02*
Y15297D01*
G01X1546050Y14820D02*
X1545291Y15577D01*
G01X1547200Y15297D02*
X1545864Y16632D01*
G01X1545291Y15577D02*
X1540537Y16589D01*
G01X1545864Y16632D02*
X1540537Y17765D01*
G01Y16589D02*
X1533056Y15000D01*
G01X1530464Y14449D02*
X1529143Y14169D01*
G01X1540537Y17765D02*
X1529143Y15345D01*
G01X1576930Y39230D02*
X1588096Y22479D01*
G01X1576930Y39230D02*
X1588096Y22479D01*
G01X1578319Y35072D02*
X1587366Y21500D01*
G01X1588096Y22479D02*
X1611028Y15434D01*
G01X1587366Y21500D02*
X1610416Y14418D01*
G01X1569630Y35530D02*
X1579745Y28787D01*
G01X1569630Y35530D02*
X1579745Y28787D01*
G01X1568992Y34573D02*
X1578925Y27951D01*
G01X1579745Y28787D02*
X1585484Y20531D01*
G01X1578925Y27951D02*
X1584754Y19564D01*
G01X1585484Y20531D02*
X1602949Y14558D01*
G01X1584754Y19564D02*
X1602228Y13589D01*
G01X1557619Y36521D02*
X1563801Y32399D01*
G01Y32398D02*
X1566729Y31813D01*
G01X1567178Y32897D02*
X1572873Y29101D01*
G01X1566729Y31813D02*
X1572140Y28207D01*
G01X1572873Y29101D02*
X1586749Y15221D01*
G01X1572140Y28207D02*
X1586272Y14071D01*
G01X1586749Y15221D02*
X1592813D01*
G01X1586272Y14071D02*
X1592336D01*
G01X1533563Y40019D02*
X1570883Y27260D01*
G01X1533491Y38828D02*
X1570258Y26258D01*
G01X1570883Y27260D02*
X1578979Y19164D01*
G01X1570258Y26258D02*
X1575338Y21178D01*
G01X1570883Y27260D02*
X1578979Y19164D01*
G01X1576292Y19305D02*
X1577211D01*
G01X1570883Y27260D02*
X1578979Y19164D01*
G01X1577211Y19305D02*
X1578166Y18350D01*
G01X1578980Y19164D02*
X1585073Y13071D01*
G01X1579121Y16476D02*
X1580040D01*
G01X1578980Y19164D02*
X1585073Y13071D01*
G01X1580040Y16476D02*
X1583922Y12594D01*
G01X1578980Y19164D02*
X1585073Y13071D01*
G01X1583922Y12594D02*
X1583923D01*
G01X1585073Y13071D02*
Y11805D01*
G01X1583923Y12594D02*
Y11805D01*
G01X1534511Y37045D02*
X1566747Y26026D01*
G01X1534439Y35854D02*
X1566122Y25023D01*
G01X1566747Y26026D02*
X1575523Y17250D01*
G01X1566122Y25023D02*
X1570247Y20898D01*
G01X1566747Y26026D02*
X1575523Y17250D01*
G01X1570247Y20898D02*
X1570248D01*
G01X1566747Y26026D02*
X1575523Y17250D01*
G01X1570248Y20898D02*
X1574373Y16773D01*
G01X1575523Y17250D02*
Y13176D01*
G01X1574373Y16773D02*
Y12956D01*
G01X1534835Y34229D02*
X1556467Y26833D01*
G01X1534763Y33038D02*
X1555842Y25831D01*
G01X1556467Y26833D02*
X1566129Y17171D01*
G01X1555842Y25831D02*
X1564979Y16694D01*
G01X1566129Y17171D02*
Y13306D01*
G01X1564979Y16694D02*
Y13056D01*
G01X1540537Y19298D02*
X1529145Y16878D01*
G01Y18054D02*
X1540537Y20474D01*
G01X1543367Y18697D02*
X1540537Y19298D01*
G01Y20474D02*
X1543367Y19873D01*
G01X1548189Y19721D02*
X1543367Y18697D01*
G01Y19873D02*
X1548189Y20897D01*
G01X1552763Y18749D02*
X1548189Y19721D01*
G01Y20897D02*
X1550715Y20361D01*
G01X1552763Y18749D02*
X1548189Y19721D01*
G01X1550715Y20360D02*
X1553336Y19804D01*
G01X1555666Y15846D02*
X1552763Y18749D01*
G01X1553336Y19804D02*
X1556816Y16323D01*
G01X1555666Y12908D02*
Y15846D01*
G01X1556816Y16323D02*
Y12972D01*
G01X1547200Y13240D02*
Y15297D01*
G01X1546050Y13210D02*
Y14820D01*
G01X1547200Y15297D02*
X1545864Y16632D01*
G01X1546050Y14820D02*
X1545291Y15577D01*
G01X1545864Y16632D02*
X1540537Y17765D01*
G01X1545291Y15577D02*
X1540537Y16589D01*
G01Y17765D02*
X1529143Y15345D01*
G01X1540537Y16589D02*
X1533056Y15000D01*
G01X1540537Y17765D02*
X1529143Y15345D01*
G01X1530464Y14449D02*
X1529143Y14169D01*
G01X1578319Y35072D02*
X1587366Y21500D01*
G01X1576930Y39230D02*
X1588096Y22479D01*
G01X1587366Y21500D02*
X1610416Y14418D01*
G01X1588096Y22479D02*
X1611028Y15434D01*
G01X1536486Y46490D02*
X1558195Y42252D01*
G01X1560796Y41745D02*
X1562121Y41486D01*
G01X1536478Y47664D02*
X1562567Y42571D01*
G01X1562121Y41486D02*
X1565192Y39439D01*
G01X1562567Y42571D02*
X1565192Y40822D01*
G01X1562121Y41486D02*
X1565192Y39439D01*
G01D02*
X1566000Y38900D01*
G01X1565192Y40822D02*
X1566830Y39730D01*
G01X1566000Y38900D02*
X1568800Y34700D01*
G01X1566830Y39730D02*
X1569630Y35530D01*
G01X1568800Y34700D02*
X1568991Y34572D01*
G01X1528822Y41140D02*
X1532142Y41804D01*
G01D02*
X1532141D01*
G01D02*
X1539387Y43253D01*
G01D02*
X1554077Y40314D01*
G01X1539387Y44426D02*
X1554526Y41398D01*
G01X1554077Y40314D02*
X1555900Y39100D01*
G01X1554526Y41398D02*
X1556730Y39930D01*
G01X1555900Y39100D02*
X1557619Y36521D01*
G01X1556730Y39930D02*
X1558449Y37351D01*
G01D02*
X1564250Y33482D01*
G01D02*
X1567178Y32897D01*
G01X1534299Y50873D02*
X1570249Y43683D01*
G01X1534304Y49699D02*
X1569800Y42600D01*
G01X1570249Y43683D02*
X1576930Y39230D01*
G01X1569800Y42600D02*
X1576100Y38400D01*
G01D02*
X1576849Y37277D01*
G01X1536478Y47664D02*
X1562567Y42571D01*
G01X1536486Y46490D02*
X1558195Y42252D01*
G01X1536478Y47664D02*
X1562567Y42571D01*
G01X1560796Y41745D02*
X1562121Y41486D01*
G01X1562567Y42571D02*
X1565192Y40822D01*
G01D02*
X1566830Y39730D01*
G01X1562121Y41486D02*
X1565192Y39439D01*
G01Y40822D02*
X1566830Y39730D01*
G01X1565192Y39439D02*
X1566000Y38900D01*
G01X1566830Y39730D02*
X1569630Y35530D01*
G01X1566000Y38900D02*
X1568800Y34700D01*
G01D02*
X1568991Y34572D01*
G01X1528822Y41140D02*
X1532142Y41804D01*
G01D02*
X1532141D01*
G01D02*
X1539387Y43253D01*
G01Y44426D02*
X1554526Y41398D01*
G01X1539387Y43253D02*
X1554077Y40314D01*
G01X1554526Y41398D02*
X1556730Y39930D01*
G01X1554077Y40314D02*
X1555900Y39100D01*
G01X1556730Y39930D02*
X1558449Y37351D01*
G01X1555900Y39100D02*
X1557619Y36521D01*
G01X1558449Y37351D02*
X1564250Y33482D01*
G01D02*
X1567178Y32897D01*
G01X1534304Y49699D02*
X1569800Y42600D01*
G01X1534299Y50873D02*
X1570249Y43683D01*
G01X1569800Y42600D02*
X1576100Y38400D01*
G01X1570249Y43683D02*
X1576930Y39230D01*
G01X1576100Y38400D02*
X1576849Y37277D01*
G01X1594677Y207220D02*
X1587693D01*
G01X1594200Y208370D02*
X1588170D01*
G01X1587693Y207220D02*
X1585462Y209451D01*
G01X1588170Y208370D02*
X1585939Y210601D01*
G01X1585462Y209451D02*
X1544867D01*
G01X1585939Y210601D02*
X1544390D01*
G01X1544867Y209451D02*
X1538898Y203482D01*
G01X1544390Y210601D02*
X1538421Y204632D01*
G01X1527140Y197813D02*
X1537413D01*
G01D02*
X1546551Y206951D01*
G01X1536936Y198963D02*
X1546074Y208101D01*
G01X1546551Y206951D02*
X1576829D01*
G01X1546074Y208101D02*
X1577306D01*
G01X1576829Y206951D02*
X1579083Y204697D01*
G01X1577306Y208101D02*
X1579560Y205847D01*
G01X1579083Y204697D02*
X1596024D01*
G01X1579560Y205847D02*
X1595547D01*
G01X1533040Y192813D02*
X1539487D01*
G01X1532563Y193963D02*
X1539010D01*
G01X1539487Y192813D02*
X1539924Y193250D01*
G01X1539010Y193963D02*
X1539447Y194400D01*
G01X1539924Y193250D02*
X1554082D01*
G01X1539447Y194400D02*
X1553605D01*
G01X1554082Y193250D02*
X1555849Y195017D01*
G01X1553605Y194400D02*
X1555372Y196167D01*
G01X1555849Y195017D02*
X1574310D01*
G01X1555372Y196167D02*
X1573833D01*
G01X1574310Y195017D02*
X1578968Y199675D01*
G01X1573833Y196167D02*
X1578491Y200825D01*
G01X1578968Y199675D02*
X1598253D01*
G01X1578491Y200825D02*
X1597776D01*
G01X1594200Y208370D02*
X1588170D01*
G01X1594677Y207220D02*
X1587693D01*
G01X1588170Y208370D02*
X1585939Y210601D01*
G01X1587693Y207220D02*
X1585462Y209451D01*
G01X1585939Y210601D02*
X1544390D01*
G01X1585462Y209451D02*
X1544867D01*
G01X1544390Y210601D02*
X1538421Y204632D01*
G01X1544867Y209451D02*
X1538898Y203482D01*
G01X1527140Y197813D02*
X1537413D01*
G01X1536936Y198963D02*
X1546074Y208101D01*
G01X1537413Y197813D02*
X1546551Y206951D01*
G01X1546074Y208101D02*
X1577306D01*
G01X1546551Y206951D02*
X1576829D01*
G01X1577306Y208101D02*
X1579560Y205847D01*
G01X1576829Y206951D02*
X1579083Y204697D01*
G01X1579560Y205847D02*
X1595547D01*
G01X1579083Y204697D02*
X1596024D01*
G01X1532563Y193963D02*
X1539010D01*
G01X1533040Y192813D02*
X1539487D01*
G01X1539010Y193963D02*
X1539447Y194400D01*
G01X1539487Y192813D02*
X1539924Y193250D01*
G01X1539447Y194400D02*
X1553605D01*
G01X1539924Y193250D02*
X1554082D01*
G01X1553605Y194400D02*
X1555372Y196167D01*
G01X1554082Y193250D02*
X1555849Y195017D01*
G01X1555372Y196167D02*
X1573833D01*
G01X1555849Y195017D02*
X1574310D01*
G01X1573833Y196167D02*
X1578491Y200825D01*
G01X1574310Y195017D02*
X1578968Y199675D01*
G01X1578491Y200825D02*
X1597776D01*
G01X1578968Y199675D02*
X1598253D01*
G01X1528177Y195313D02*
X1538450D01*
G01X1527700Y196463D02*
X1537973D01*
G01X1538450Y195313D02*
X1547587Y204450D01*
G01X1537973Y196463D02*
X1547110Y205600D01*
G01X1547587Y204450D02*
X1554231D01*
G01X1547110Y205600D02*
X1554708D01*
G01X1554231Y204450D02*
X1557829Y200852D01*
G01X1554708Y205600D02*
X1558305Y202003D01*
G01X1557829Y200852D02*
X1558781D01*
G01X1558782Y200853D02*
X1576609D01*
G01X1558305Y202003D02*
X1576132D01*
G01X1576609Y200853D02*
X1577931Y202175D01*
G01X1576132Y202003D02*
X1577454Y203325D01*
G01X1577931Y202175D02*
X1597216D01*
G01X1577454Y203325D02*
X1596739D01*
G01X1599375Y186623D02*
X1582696D01*
G01X1599852Y185473D02*
X1583173D01*
G01X1582696Y186623D02*
X1574093Y178020D01*
G01X1583173Y185473D02*
X1574570Y176870D01*
G01X1574093Y178020D02*
X1569131D01*
G01X1574570Y176870D02*
X1568654D01*
G01X1569131Y178020D02*
X1568428Y178723D01*
G01X1568654Y176870D02*
X1567951Y177573D01*
G01X1568428Y178723D02*
X1555824D01*
G01X1567951Y177573D02*
X1556301D01*
G01X1555824Y178723D02*
X1553182Y176081D01*
G01X1556301Y177573D02*
X1553659Y174931D01*
G01X1553182Y176081D02*
X1550782D01*
G01X1553659Y174931D02*
X1551259D01*
G01X1550782Y176081D02*
X1549211Y174510D01*
G01X1551259Y174931D02*
X1549688Y173360D01*
G01X1549211Y174510D02*
X1527647D01*
G01X1549688Y173360D02*
X1528124D01*
G01X1598776Y188018D02*
X1581579D01*
G01X1598299Y189168D02*
X1581102D01*
G01X1581579Y188018D02*
X1577420Y183859D01*
G01X1581102Y189168D02*
X1576943Y185009D01*
G01X1577420Y183859D02*
X1565691D01*
G01X1576943Y185009D02*
X1565214D01*
G01X1565691Y183859D02*
X1562182Y180350D01*
G01X1565214Y185009D02*
X1561705Y181500D01*
G01X1562182Y180350D02*
X1555541D01*
G01X1561705Y181500D02*
X1555064D01*
G01X1555541Y180350D02*
X1552622Y177431D01*
G01X1555064Y181500D02*
X1552145Y178581D01*
G01X1552622Y177431D02*
X1550222D01*
G01X1552145Y178581D02*
X1549745D01*
G01X1550222Y177431D02*
X1548651Y175860D01*
G01X1549745Y178581D02*
X1548174Y177010D01*
G01X1548651Y175860D02*
X1538913D01*
G01X1548174Y177010D02*
X1539390D01*
G01X1538913Y175860D02*
X1536323Y178450D01*
G01X1539390Y177010D02*
X1536800Y179600D01*
G01X1536323Y178450D02*
X1529677D01*
G01X1536800Y179600D02*
X1529200D01*
G01X1527974Y182300D02*
X1539300D01*
G01X1528451Y181150D02*
X1538823D01*
G01X1539300Y182300D02*
X1542049Y179551D01*
G01X1538823Y181150D02*
X1541572Y178401D01*
G01X1542049Y179551D02*
X1547178D01*
G01X1541572Y178401D02*
X1547655D01*
G01X1547178Y179551D02*
X1548708Y181081D01*
G01X1547655Y178401D02*
X1549185Y179931D01*
G01X1548708Y181081D02*
X1551005D01*
G01X1549185Y179931D02*
X1551482D01*
G01X1551005Y181081D02*
X1554074Y184150D01*
G01X1551482Y179931D02*
X1554551Y183000D01*
G01X1554074Y184150D02*
X1560244D01*
G01X1554551Y183000D02*
X1560721D01*
G01X1560244Y184150D02*
X1563707Y187613D01*
G01X1560721Y183000D02*
X1564184Y186463D01*
G01X1563707Y187613D02*
X1572946D01*
G01X1564184Y186463D02*
X1573423D01*
G01X1572946Y187613D02*
X1580963Y195630D01*
G01X1573423Y186463D02*
X1581440Y194480D01*
G01X1580963Y195630D02*
X1599680D01*
G01X1581440Y194480D02*
X1600157D01*
G01X1580005Y197175D02*
X1599302D01*
G01X1598826Y198325D02*
X1579528D01*
G01X1572161Y189331D02*
X1580005Y197175D01*
G01X1579528Y198325D02*
X1571684Y190481D01*
G01X1563431Y189331D02*
X1572161D01*
G01X1571684Y190481D02*
X1562954D01*
G01X1559869Y185769D02*
X1563431Y189331D01*
G01X1562954Y190481D02*
X1559392Y186919D01*
G01X1549004Y185769D02*
X1559869D01*
G01X1559392Y186919D02*
X1549481D01*
G01X1545223Y189550D02*
X1549004Y185769D01*
G01X1549481Y186919D02*
X1545700Y190700D01*
G01X1541477Y189550D02*
X1545223D01*
G01X1545700Y190700D02*
X1541000D01*
G01X1536877Y184950D02*
X1541477Y189550D01*
G01X1541000Y190700D02*
X1536400Y186100D01*
G01X1528714Y184950D02*
X1536877D01*
G01X1536400Y186100D02*
X1528237D01*
G01X1527700Y196463D02*
X1537973D01*
G01X1528177Y195313D02*
X1538450D01*
G01X1537973Y196463D02*
X1547110Y205600D01*
G01X1538450Y195313D02*
X1547587Y204450D01*
G01X1547110Y205600D02*
X1554708D01*
G01X1547587Y204450D02*
X1554231D01*
G01X1554708Y205600D02*
X1558305Y202003D01*
G01X1554231Y204450D02*
X1557829Y200852D01*
G01X1558305Y202003D02*
X1576132D01*
G01X1557829Y200852D02*
X1558781D01*
G01X1558305Y202003D02*
X1576132D01*
G01X1558782Y200853D02*
X1576609D01*
G01X1576132Y202003D02*
X1577454Y203325D01*
G01X1576609Y200853D02*
X1577931Y202175D01*
G01X1577454Y203325D02*
X1596739D01*
G01X1577931Y202175D02*
X1597216D01*
G01X1599852Y185473D02*
X1583173D01*
G01X1599375Y186623D02*
X1582696D01*
G01X1583173Y185473D02*
X1574570Y176870D01*
G01X1582696Y186623D02*
X1574093Y178020D01*
G01X1574570Y176870D02*
X1568654D01*
G01X1574093Y178020D02*
X1569131D01*
G01X1568654Y176870D02*
X1567951Y177573D01*
G01X1569131Y178020D02*
X1568428Y178723D01*
G01X1567951Y177573D02*
X1556301D01*
G01X1568428Y178723D02*
X1555824D01*
G01X1556301Y177573D02*
X1553659Y174931D01*
G01X1555824Y178723D02*
X1553182Y176081D01*
G01X1553659Y174931D02*
X1551259D01*
G01X1553182Y176081D02*
X1550782D01*
G01X1551259Y174931D02*
X1549688Y173360D01*
G01X1550782Y176081D02*
X1549211Y174510D01*
G01X1549688Y173360D02*
X1528124D01*
G01X1549211Y174510D02*
X1527647D01*
G01X1598299Y189168D02*
X1581102D01*
G01X1598776Y188018D02*
X1581579D01*
G01X1581102Y189168D02*
X1576943Y185009D01*
G01X1581579Y188018D02*
X1577420Y183859D01*
G01X1576943Y185009D02*
X1565214D01*
G01X1577420Y183859D02*
X1565691D01*
G01X1565214Y185009D02*
X1561705Y181500D01*
G01X1565691Y183859D02*
X1562182Y180350D01*
G01X1561705Y181500D02*
X1555064D01*
G01X1562182Y180350D02*
X1555541D01*
G01X1555064Y181500D02*
X1552145Y178581D01*
G01X1555541Y180350D02*
X1552622Y177431D01*
G01X1552145Y178581D02*
X1549745D01*
G01X1552622Y177431D02*
X1550222D01*
G01X1549745Y178581D02*
X1548174Y177010D01*
G01X1550222Y177431D02*
X1548651Y175860D01*
G01X1548174Y177010D02*
X1539390D01*
G01X1548651Y175860D02*
X1538913D01*
G01X1539390Y177010D02*
X1536800Y179600D01*
G01X1538913Y175860D02*
X1536323Y178450D01*
G01X1536800Y179600D02*
X1529200D01*
G01X1536323Y178450D02*
X1529677D01*
G01X1528451Y181150D02*
X1538823D01*
G01X1527974Y182300D02*
X1539300D01*
G01X1538823Y181150D02*
X1541572Y178401D01*
G01X1539300Y182300D02*
X1542049Y179551D01*
G01X1541572Y178401D02*
X1547655D01*
G01X1542049Y179551D02*
X1547178D01*
G01X1547655Y178401D02*
X1549185Y179931D01*
G01X1547178Y179551D02*
X1548708Y181081D01*
G01X1549185Y179931D02*
X1551482D01*
G01X1548708Y181081D02*
X1551005D01*
G01X1551482Y179931D02*
X1554551Y183000D01*
G01X1551005Y181081D02*
X1554074Y184150D01*
G01X1554551Y183000D02*
X1560721D01*
G01X1554074Y184150D02*
X1560244D01*
G01X1560721Y183000D02*
X1564184Y186463D01*
G01X1560244Y184150D02*
X1563707Y187613D01*
G01X1564184Y186463D02*
X1573423D01*
G01X1563707Y187613D02*
X1572946D01*
G01X1573423Y186463D02*
X1581440Y194480D01*
G01X1572946Y187613D02*
X1580963Y195630D01*
G01X1581440Y194480D02*
X1600157D01*
G01X1580963Y195630D02*
X1599680D01*
G01X1536400Y186100D02*
X1528237D01*
G01X1528714Y184950D02*
X1536877D01*
G01X1541000Y190700D02*
X1536400Y186100D01*
G01X1536877Y184950D02*
X1541477Y189550D01*
G01X1545700Y190700D02*
X1541000D01*
G01X1541477Y189550D02*
X1545223D01*
G01X1549481Y186919D02*
X1545700Y190700D01*
G01X1545223Y189550D02*
X1549004Y185769D01*
G01X1559392Y186919D02*
X1549481D01*
G01X1549004Y185769D02*
X1559869D01*
G01X1562954Y190481D02*
X1559392Y186919D01*
G01X1559869Y185769D02*
X1563431Y189331D01*
G01X1571684Y190481D02*
X1562954D01*
G01X1563431Y189331D02*
X1572161D01*
G01X1579528Y198325D02*
X1571684Y190481D01*
G01X1572161Y189331D02*
X1580005Y197175D01*
G01X1598826Y198325D02*
X1579528D01*
G01X1580005Y197175D02*
X1599302D01*
G01X1537569Y220350D02*
X1534669Y217450D01*
G01D02*
X1528753D01*
G01X1530573Y214950D02*
X1527688Y212065D01*
G01X1527211Y213215D02*
X1530096Y216100D01*
G01X1536125Y214950D02*
X1530573D01*
G01X1530096Y216100D02*
X1535648D01*
G01X1538973Y217798D02*
X1536125Y214950D01*
G01X1535648Y216100D02*
X1538496Y218948D01*
G01X1576818Y217798D02*
X1538973D01*
G01X1582275Y223255D02*
X1576818Y217798D01*
G01X1582828Y220271D02*
X1577855Y215298D01*
G01X1582351Y221421D02*
X1577378Y216448D01*
G01X1577855Y215298D02*
X1541085D01*
G01X1577378Y216448D02*
X1540608D01*
G01X1541085Y215298D02*
X1537486Y211699D01*
G01X1540608Y216448D02*
X1537009Y212849D01*
G01X1537486Y211699D02*
X1532218D01*
G01X1537009Y212849D02*
X1531741D01*
G01X1532218Y211699D02*
X1530069Y209550D01*
G01X1531741Y212849D02*
X1529592Y210700D01*
G01X1588944Y210850D02*
X1587094Y212700D01*
G01X1589421Y212000D02*
X1587571Y213850D01*
G01X1587094Y212700D02*
X1542653D01*
G01X1587571Y213850D02*
X1542176D01*
G01X1542653Y212700D02*
X1539152Y209199D01*
G01X1542176Y213850D02*
X1538675Y210349D01*
G01X1539152Y209199D02*
X1533255D01*
G01X1538675Y210349D02*
X1532778D01*
G01X1533255Y209199D02*
X1531106Y207050D01*
G01X1532778Y210349D02*
X1530629Y208200D01*
G01X1537569Y220350D02*
X1534669Y217450D01*
G01D02*
X1528753D01*
G01X1582275Y223255D02*
X1576818Y217798D01*
G01D02*
X1538973D01*
G01X1535648Y216100D02*
X1538496Y218948D01*
G01X1538973Y217798D02*
X1536125Y214950D01*
G01X1530096Y216100D02*
X1535648D01*
G01X1536125Y214950D02*
X1530573D01*
G01X1527211Y213215D02*
X1530096Y216100D01*
G01X1530573Y214950D02*
X1527688Y212065D01*
G01X1582351Y221421D02*
X1577378Y216448D01*
G01X1582828Y220271D02*
X1577855Y215298D01*
G01X1577378Y216448D02*
X1540608D01*
G01X1577855Y215298D02*
X1541085D01*
G01X1540608Y216448D02*
X1537009Y212849D01*
G01X1541085Y215298D02*
X1537486Y211699D01*
G01X1537009Y212849D02*
X1531741D01*
G01X1537486Y211699D02*
X1532218D01*
G01X1531741Y212849D02*
X1529592Y210700D01*
G01X1532218Y211699D02*
X1530069Y209550D01*
G01X1589421Y212000D02*
X1587571Y213850D01*
G01X1588944Y210850D02*
X1587094Y212700D01*
G01X1587571Y213850D02*
X1542176D01*
G01X1587094Y212700D02*
X1542653D01*
G01X1542176Y213850D02*
X1538675Y210349D01*
G01X1542653Y212700D02*
X1539152Y209199D01*
G01X1538675Y210349D02*
X1532778D01*
G01X1539152Y209199D02*
X1533255D01*
G01X1532778Y210349D02*
X1530629Y208200D01*
G01X1533255Y209199D02*
X1531106Y207050D01*
G01X1595098Y234208D02*
X1578934D01*
G01X1594621Y235358D02*
X1578457D01*
G01X1578934Y234208D02*
X1572776Y228050D01*
G01X1578457Y235358D02*
X1572299Y229200D01*
G01X1572776Y228050D02*
X1538751D01*
G01X1572299Y229200D02*
X1539228D01*
G01X1538751Y228050D02*
X1538035Y228766D01*
G01X1539228Y229200D02*
X1538512Y229916D01*
G01X1596355Y231708D02*
X1579971D01*
G01X1595878Y232858D02*
X1579494D01*
G01X1579971Y231708D02*
X1573813Y225550D01*
G01X1579494Y232858D02*
X1573336Y226700D01*
G01X1573813Y225550D02*
X1537714D01*
G01X1573336Y226700D02*
X1538191D01*
G01X1537714Y225550D02*
X1537036Y226228D01*
G01X1538191Y226700D02*
X1537513Y227378D01*
G01X1597408Y229208D02*
X1581008D01*
G01X1596931Y230358D02*
X1580531D01*
G01X1581008Y229208D02*
X1574650Y222850D01*
G01X1580531Y230358D02*
X1574173Y224000D01*
G01X1574650Y222850D02*
X1535406D01*
G01X1574173Y224000D02*
X1534929D01*
G01X1535406Y222850D02*
X1532915Y220359D01*
G01X1534929Y224000D02*
X1532438Y221509D01*
G01X1598521Y226656D02*
X1582056D01*
G01X1598044Y227806D02*
X1581579D01*
G01X1582056Y226656D02*
X1575750Y220350D01*
G01X1581579Y227806D02*
X1575273Y221500D01*
G01X1575750Y220350D02*
X1537569D01*
G01X1575273Y221500D02*
X1537092D01*
G01D02*
X1534192Y218600D01*
G01D02*
X1528276D01*
G01X1538496Y218948D02*
X1576341D01*
G01D02*
X1581798Y224405D01*
G01X1588904Y223255D02*
X1582275D01*
G01X1581798Y224405D02*
X1589381D01*
G01X1598979Y219725D02*
X1588148D01*
G01X1598502Y220875D02*
X1588625D01*
G01X1588148Y219725D02*
X1587602Y220271D01*
G01X1588625Y220875D02*
X1588079Y221421D01*
G01X1587602Y220271D02*
X1582828D01*
G01X1588079Y221421D02*
X1582351D01*
G01X1539561Y232416D02*
X1540277Y231700D01*
G01X1539084Y231266D02*
X1539800Y230550D01*
G01X1540277Y231700D02*
X1571182D01*
G01X1539800Y230550D02*
X1571659D01*
G01X1571182Y231700D02*
X1581371Y241889D01*
G01X1571659Y230550D02*
X1581848Y240739D01*
G01X1581371Y241889D02*
X1601578D01*
G01X1581848Y240739D02*
X1602055D01*
G01X1594621Y235358D02*
X1578457D01*
G01X1595098Y234208D02*
X1578934D01*
G01X1578457Y235358D02*
X1572299Y229200D01*
G01X1578934Y234208D02*
X1572776Y228050D01*
G01X1572299Y229200D02*
X1539228D01*
G01X1572776Y228050D02*
X1538751D01*
G01X1539228Y229200D02*
X1538512Y229916D01*
G01X1538751Y228050D02*
X1538035Y228766D01*
G01X1595878Y232858D02*
X1579494D01*
G01X1596355Y231708D02*
X1579971D01*
G01X1579494Y232858D02*
X1573336Y226700D01*
G01X1579971Y231708D02*
X1573813Y225550D01*
G01X1573336Y226700D02*
X1538191D01*
G01X1573813Y225550D02*
X1537714D01*
G01X1538191Y226700D02*
X1537513Y227378D01*
G01X1537714Y225550D02*
X1537036Y226228D01*
G01X1596931Y230358D02*
X1580531D01*
G01X1597408Y229208D02*
X1581008D01*
G01X1580531Y230358D02*
X1574173Y224000D01*
G01X1581008Y229208D02*
X1574650Y222850D01*
G01X1574173Y224000D02*
X1534929D01*
G01X1574650Y222850D02*
X1535406D01*
G01X1534929Y224000D02*
X1532438Y221509D01*
G01X1535406Y222850D02*
X1532915Y220359D01*
G01X1598044Y227806D02*
X1581579D01*
G01X1598521Y226656D02*
X1582056D01*
G01X1581579Y227806D02*
X1575273Y221500D01*
G01X1582056Y226656D02*
X1575750Y220350D01*
G01X1575273Y221500D02*
X1537092D01*
G01X1575750Y220350D02*
X1537569D01*
G01X1537092Y221500D02*
X1534192Y218600D01*
G01D02*
X1528276D01*
G01X1581798Y224405D02*
X1589381D01*
G01X1588904Y223255D02*
X1582275D01*
G01X1576341Y218948D02*
X1581798Y224405D01*
G01X1538496Y218948D02*
X1576341D01*
G01X1598502Y220875D02*
X1588625D01*
G01X1598979Y219725D02*
X1588148D01*
G01X1588625Y220875D02*
X1588079Y221421D01*
G01X1588148Y219725D02*
X1587602Y220271D01*
G01X1588079Y221421D02*
X1582351D01*
G01X1587602Y220271D02*
X1582828D01*
G01X1539084Y231266D02*
X1539800Y230550D01*
G01X1539561Y232416D02*
X1540277Y231700D01*
G01X1539800Y230550D02*
X1571659D01*
G01X1540277Y231700D02*
X1571182D01*
G01X1571659Y230550D02*
X1581848Y240739D01*
G01X1571182Y231700D02*
X1581371Y241889D01*
G01X1581848Y240739D02*
X1602055D01*
G01X1581371Y241889D02*
X1601578D01*
G01X1529537Y336316D02*
X1530953Y334900D01*
G01X1529060Y335166D02*
X1530476Y333750D01*
G01X1530953Y334900D02*
X1540092D01*
G01X1530476Y333750D02*
X1539615D01*
G01X1540092Y334900D02*
X1545256Y329736D01*
G01X1539615Y333750D02*
X1544779Y328586D01*
G01X1545256Y329736D02*
X1550163D01*
G01X1544779Y328586D02*
X1549686D01*
G01X1550163Y329736D02*
X1555270Y324629D01*
G01X1549686Y328586D02*
X1554793Y323479D01*
G01X1555270Y324629D02*
X1583230D01*
G01X1554793Y323479D02*
X1582753D01*
G01X1583230Y324629D02*
X1587789Y320070D01*
G01X1582753Y323479D02*
X1587312Y318920D01*
G01X1587789Y320070D02*
X1596112D01*
G01X1587312Y318920D02*
X1596589D01*
G01X1529060Y335166D02*
X1530476Y333750D01*
G01X1529537Y336316D02*
X1530953Y334900D01*
G01X1530476Y333750D02*
X1539615D01*
G01X1530953Y334900D02*
X1540092D01*
G01X1539615Y333750D02*
X1544779Y328586D01*
G01X1540092Y334900D02*
X1545256Y329736D01*
G01X1544779Y328586D02*
X1549686D01*
G01X1545256Y329736D02*
X1550163D01*
G01X1549686Y328586D02*
X1554793Y323479D01*
G01X1550163Y329736D02*
X1555270Y324629D01*
G01X1554793Y323479D02*
X1582753D01*
G01X1555270Y324629D02*
X1583230D01*
G01X1582753Y323479D02*
X1587312Y318920D01*
G01X1583230Y324629D02*
X1587789Y320070D01*
G01X1587312Y318920D02*
X1596589D01*
G01X1587789Y320070D02*
X1596112D01*
G01X1597444Y326067D02*
X1556894D01*
G01X1596967Y327217D02*
X1557371D01*
G01X1556894Y326067D02*
X1551602Y331359D01*
G01X1557371Y327217D02*
X1552752Y331836D01*
G01X1551602Y331359D02*
Y333479D01*
G01X1552752Y331836D02*
Y333956D01*
G01X1551602Y333479D02*
X1548681Y336400D01*
G01X1552752Y333956D02*
X1549158Y337550D01*
G01X1548681Y336400D02*
X1531363D01*
G01X1549158Y337550D02*
X1531840D01*
G01X1531363Y336400D02*
X1529988Y337775D01*
G01X1531840Y337550D02*
X1530465Y338925D01*
G01X1596967Y327217D02*
X1557371D01*
G01X1597444Y326067D02*
X1556894D01*
G01X1557371Y327217D02*
X1552752Y331836D01*
G01X1556894Y326067D02*
X1551602Y331359D01*
G01X1552752Y331836D02*
Y333956D01*
G01X1551602Y331359D02*
Y333479D01*
G01X1552752Y333956D02*
X1549158Y337550D01*
G01X1551602Y333479D02*
X1548681Y336400D01*
G01X1549158Y337550D02*
X1531840D01*
G01X1548681Y336400D02*
X1531363D01*
G01X1531840Y337550D02*
X1530465Y338925D01*
G01X1531363Y336400D02*
X1529988Y337775D01*
G01X1530900Y343000D02*
X1534900Y339000D01*
G01X1531377Y344150D02*
X1535377Y340150D01*
G01X1534900Y339000D02*
X1550486D01*
G01X1535377Y340150D02*
X1550963D01*
G01X1550486Y339000D02*
X1553803Y335683D01*
G01X1550963Y340150D02*
X1554280Y336833D01*
G01X1553803Y335683D02*
X1558617D01*
G01X1554280Y336833D02*
X1559094D01*
G01X1558617Y335683D02*
X1565733Y328567D01*
G01X1559094Y336833D02*
X1566210Y329717D01*
G01X1565733Y328567D02*
X1576348D01*
G01X1566210Y329717D02*
X1575871D01*
G01X1576348Y328567D02*
X1578959Y331178D01*
G01X1575871Y329717D02*
X1578482Y332328D01*
G01X1578959Y331178D02*
X1582863D01*
G01X1578482Y332328D02*
X1583340D01*
G01X1582863Y331178D02*
X1585238Y328803D01*
G01X1583340Y332328D02*
X1585715Y329953D01*
G01X1585238Y328803D02*
X1595919D01*
G01X1585715Y329953D02*
X1595442D01*
G01X1531377Y344150D02*
X1535377Y340150D01*
G01X1530900Y343000D02*
X1534900Y339000D01*
G01X1535377Y340150D02*
X1550963D01*
G01X1534900Y339000D02*
X1550486D01*
G01X1550963Y340150D02*
X1554280Y336833D01*
G01X1550486Y339000D02*
X1553803Y335683D01*
G01X1554280Y336833D02*
X1559094D01*
G01X1553803Y335683D02*
X1558617D01*
G01X1559094Y336833D02*
X1566210Y329717D01*
G01X1558617Y335683D02*
X1565733Y328567D01*
G01X1566210Y329717D02*
X1575871D01*
G01X1565733Y328567D02*
X1576348D01*
G01X1575871Y329717D02*
X1578482Y332328D01*
G01X1576348Y328567D02*
X1578959Y331178D01*
G01X1578482Y332328D02*
X1583340D01*
G01X1578959Y331178D02*
X1582863D01*
G01X1583340Y332328D02*
X1585715Y329953D01*
G01X1582863Y331178D02*
X1585238Y328803D01*
G01X1585715Y329953D02*
X1595442D01*
G01X1585238Y328803D02*
X1595919D01*
G01X1605348Y511545D02*
X1566611Y527585D01*
G01X1605465Y512742D02*
X1566699Y528794D01*
G01X1566611Y527585D02*
X1559062Y525674D01*
G01D02*
X1552591Y527040D01*
G01D02*
X1546269Y525605D01*
G01D02*
X1537671Y527338D01*
G01X1528543Y522831D02*
X1537680Y524735D01*
G01X1528122Y523918D02*
X1537676Y525909D01*
G01X1537680Y524735D02*
X1546301Y522996D01*
G01X1537676Y525909D02*
X1546287Y524173D01*
G01X1546301Y522996D02*
X1552611Y524431D01*
G01X1546287Y524173D02*
X1552602Y525609D01*
G01X1552611Y524431D02*
X1559115Y523059D01*
G01X1552602Y525609D02*
X1559091Y524240D01*
G01X1559115Y523059D02*
X1565873Y524768D01*
G01X1559091Y524240D02*
X1565192Y525783D01*
G01X1559115Y523059D02*
X1565873Y524768D01*
G01X1565192Y525783D02*
X1565961Y525977D01*
G01X1565873Y524768D02*
X1609570Y506664D01*
G01X1565961Y525977D02*
X1609905Y507771D01*
G01X1608800Y504217D02*
X1565664Y522084D01*
G01X1609135Y505324D02*
X1565752Y523293D01*
G01X1565664Y522084D02*
X1559167Y520441D01*
G01X1565752Y523293D02*
X1559144Y521622D01*
G01X1559167Y520441D02*
X1552581Y521832D01*
G01X1559144Y521622D02*
X1552572Y523010D01*
G01X1552581Y521832D02*
X1546282Y520399D01*
G01X1552572Y523010D02*
X1546267Y521576D01*
G01X1546282Y520399D02*
X1537687Y522132D01*
G01X1546267Y521576D02*
X1537683Y523306D01*
G01X1537687Y522132D02*
X1529698Y520467D01*
G01X1537683Y523306D02*
X1529277Y521554D01*
G01X1527277Y516075D02*
X1530631Y518057D01*
G01D02*
X1537696Y519529D01*
G01X1530210Y519144D02*
X1537692Y520703D01*
G01X1537696Y519529D02*
X1546365Y517780D01*
G01X1537692Y520703D02*
X1546351Y518957D01*
G01X1546365Y517780D02*
X1552651Y519210D01*
G01X1546351Y518957D02*
X1552642Y520388D01*
G01X1552651Y519210D02*
X1559219Y517824D01*
G01X1552642Y520388D02*
X1559196Y519005D01*
G01X1559219Y517824D02*
X1565365Y519379D01*
G01X1559196Y519005D02*
X1565453Y520588D01*
G01X1565365Y519379D02*
X1608040Y501705D01*
G01X1565453Y520588D02*
X1608375Y502812D01*
G01X1605465Y512742D02*
X1566699Y528794D01*
G01X1605348Y511545D02*
X1566611Y527585D01*
G01D02*
X1559062Y525674D01*
G01D02*
X1552591Y527040D01*
G01D02*
X1546269Y525605D01*
G01D02*
X1537671Y527338D01*
G01X1528122Y523918D02*
X1537676Y525909D01*
G01X1528543Y522831D02*
X1537680Y524735D01*
G01X1537676Y525909D02*
X1546287Y524173D01*
G01X1537680Y524735D02*
X1546301Y522996D01*
G01X1546287Y524173D02*
X1552602Y525609D01*
G01X1546301Y522996D02*
X1552611Y524431D01*
G01X1552602Y525609D02*
X1559091Y524240D01*
G01X1552611Y524431D02*
X1559115Y523059D01*
G01X1559091Y524240D02*
X1565192Y525783D01*
G01D02*
X1565961Y525977D01*
G01X1559115Y523059D02*
X1565873Y524768D01*
G01X1565961Y525977D02*
X1609905Y507771D01*
G01X1565873Y524768D02*
X1609570Y506664D01*
G01X1609135Y505324D02*
X1565752Y523293D01*
G01X1608800Y504217D02*
X1565664Y522084D01*
G01X1565752Y523293D02*
X1559144Y521622D01*
G01X1565664Y522084D02*
X1559167Y520441D01*
G01X1559144Y521622D02*
X1552572Y523010D01*
G01X1559167Y520441D02*
X1552581Y521832D01*
G01X1552572Y523010D02*
X1546267Y521576D01*
G01X1552581Y521832D02*
X1546282Y520399D01*
G01X1546267Y521576D02*
X1537683Y523306D01*
G01X1546282Y520399D02*
X1537687Y522132D01*
G01X1537683Y523306D02*
X1529277Y521554D01*
G01X1537687Y522132D02*
X1529698Y520467D01*
G01X1527277Y516075D02*
X1530631Y518057D01*
G01X1530210Y519144D02*
X1537692Y520703D01*
G01X1530631Y518057D02*
X1537696Y519529D01*
G01X1537692Y520703D02*
X1546351Y518957D01*
G01X1537696Y519529D02*
X1546365Y517780D01*
G01X1546351Y518957D02*
X1552642Y520388D01*
G01X1546365Y517780D02*
X1552651Y519210D01*
G01X1552642Y520388D02*
X1559196Y519005D01*
G01X1552651Y519210D02*
X1559219Y517824D01*
G01X1559196Y519005D02*
X1565453Y520588D01*
G01X1559219Y517824D02*
X1565365Y519379D01*
G01X1565453Y520588D02*
X1608375Y502812D01*
G01X1565365Y519379D02*
X1608040Y501705D01*
G01X1600924Y499782D02*
X1581204D01*
G01X1600681Y498632D02*
X1581681D01*
G01X1581204Y499782D02*
X1578803Y497381D01*
G01X1581681Y498632D02*
X1579280Y496231D01*
G01X1578803Y497381D02*
X1540028D01*
G01X1579280Y496231D02*
X1560641D01*
G01X1578803Y497381D02*
X1540028D01*
G01X1557991Y496231D02*
X1556641D01*
G01X1578803Y497381D02*
X1540028D01*
G01X1553991Y496231D02*
X1552641D01*
G01X1578803Y497381D02*
X1540028D01*
G01X1549991Y496231D02*
X1548641D01*
G01X1578803Y497381D02*
X1540028D01*
G01X1545991Y496231D02*
X1539551D01*
G01X1540028Y497381D02*
X1538028Y499381D01*
G01X1539551Y496231D02*
X1536878Y498904D01*
G01X1538028Y499381D02*
Y506307D01*
G01X1536878Y498904D02*
Y505830D01*
G01X1538028Y506307D02*
X1536574Y507761D01*
G01X1536878Y505830D02*
X1536097Y506611D01*
G01X1538028Y506307D02*
X1536574Y507761D01*
G01D02*
X1534864D01*
G01X1536097Y506611D02*
X1534676D01*
G01X1600681Y498632D02*
X1581681D01*
G01X1600924Y499782D02*
X1581204D01*
G01X1581681Y498632D02*
X1579280Y496231D01*
G01X1581204Y499782D02*
X1578803Y497381D01*
G01X1579280Y496231D02*
X1560641D01*
G01X1557991D02*
X1556641D01*
G01X1553991D02*
X1552641D01*
G01X1549991D02*
X1548641D01*
G01X1545991D02*
X1539551D01*
G01X1578803Y497381D02*
X1540028D01*
G01X1539551Y496231D02*
X1536878Y498904D01*
G01X1540028Y497381D02*
X1538028Y499381D01*
G01X1536878Y498904D02*
Y505830D01*
G01X1538028Y499381D02*
Y506307D01*
G01X1536878Y505830D02*
X1536097Y506611D01*
G01D02*
X1534676D01*
G01X1538028Y506307D02*
X1536574Y507761D01*
G01X1536097Y506611D02*
X1534676D01*
G01X1536574Y507761D02*
X1534864D01*
G01X1545826Y548014D02*
X1549606Y551794D01*
G01X1545349Y549164D02*
X1549129Y552944D01*
G01X1549606Y551794D02*
X1565681D01*
G01X1549129Y552944D02*
X1565204D01*
G01X1565681Y551794D02*
X1569820Y555933D01*
G01X1565204Y552944D02*
X1569343Y557083D01*
G01X1569820Y555933D02*
X1582906D01*
G01X1569343Y557083D02*
X1582429D01*
G01X1582906Y555933D02*
X1584967Y557994D01*
G01X1582429Y557083D02*
X1584490Y559144D01*
G01X1584967Y557994D02*
X1598875D01*
G01X1584490Y559144D02*
X1599104D01*
G01X1545349Y549164D02*
X1549129Y552944D01*
G01X1545826Y548014D02*
X1549606Y551794D01*
G01X1549129Y552944D02*
X1565204D01*
G01X1549606Y551794D02*
X1565681D01*
G01X1565204Y552944D02*
X1569343Y557083D01*
G01X1565681Y551794D02*
X1569820Y555933D01*
G01X1569343Y557083D02*
X1582429D01*
G01X1569820Y555933D02*
X1582906D01*
G01X1582429Y557083D02*
X1584490Y559144D01*
G01X1582906Y555933D02*
X1584967Y557994D01*
G01X1584490Y559144D02*
X1599104D01*
G01X1584967Y557994D02*
X1598875D01*
G01X1532596Y539559D02*
X1533920Y539822D01*
G01X1536519Y540339D02*
X1537843Y540602D01*
G01X1540442Y541119D02*
X1541766Y541382D01*
G01X1544365Y541899D02*
X1594127Y551797D01*
G01X1532596Y539559D02*
X1533920Y539822D01*
G01X1536519Y540339D02*
X1537843Y540602D01*
G01X1540442Y541119D02*
X1541766Y541382D01*
G01X1544365Y541899D02*
X1594127Y551797D01*
G01X1566699Y528794D02*
X1559038Y526855D01*
G01D02*
X1552582Y528218D01*
G01D02*
X1546255Y526782D01*
G01D02*
X1537667Y528512D01*
G01X1566699Y528794D02*
X1559038Y526855D01*
G01D02*
X1552582Y528218D01*
G01D02*
X1546255Y526782D01*
G01D02*
X1537667Y528512D01*
G01X1602228Y13589D02*
X1602723Y12896D01*
G01X1602949Y14558D02*
X1603873Y13265D01*
G01X1602723Y12896D02*
Y11805D01*
G01X1603873Y13265D02*
Y11886D01*
G01X1592336Y14071D02*
X1593223Y13184D01*
G01X1592813Y15221D02*
X1594373Y13661D01*
G01X1593223Y13184D02*
Y11856D01*
G01X1594373Y13661D02*
Y11856D01*
G01X1611028Y15434D02*
X1612746Y13715D01*
G01X1610416Y14418D02*
X1611596Y13238D01*
G01X1612746Y13715D02*
Y6404D01*
G01X1611596Y13238D02*
Y6404D01*
G01X1602949Y14558D02*
X1603873Y13265D01*
G01X1602228Y13589D02*
X1602723Y12896D01*
G01X1603873Y13265D02*
Y11886D01*
G01X1602723Y12896D02*
Y11805D01*
G01X1592813Y15221D02*
X1594373Y13661D01*
G01X1592336Y14071D02*
X1593223Y13184D01*
G01X1594373Y13661D02*
Y11856D01*
G01X1593223Y13184D02*
Y11856D01*
G01X1610416Y14418D02*
X1611596Y13238D01*
G01X1611028Y15434D02*
X1612746Y13715D01*
G01X1611596Y13238D02*
Y6404D01*
G01X1612746Y13715D02*
Y6404D01*
G01X1651411Y214189D02*
X1649000Y216600D01*
G01X1651888Y215339D02*
X1649477Y217750D01*
G01X1649000Y216600D02*
X1633095D01*
G01X1649477Y217750D02*
X1632618D01*
G01X1633095Y216600D02*
X1631195Y214700D01*
G01X1632618Y217750D02*
X1630718Y215850D01*
G01X1631195Y214700D02*
X1618301D01*
G01X1630718Y215850D02*
X1618778D01*
G01X1618301Y214700D02*
X1613701Y219300D01*
G01X1618778Y215850D02*
X1614178Y220450D01*
G01X1610601Y219300D02*
X1607860Y216559D01*
G01X1610124Y220450D02*
X1607383Y217709D01*
G01X1607860Y216559D02*
X1604016D01*
G01X1607383Y217709D02*
X1603539D01*
G01X1604016Y216559D02*
X1594677Y207220D01*
G01X1603539Y217709D02*
X1594200Y208370D01*
G01X1596024Y204697D02*
X1601727Y210400D01*
G01X1595547Y205847D02*
X1601250Y211550D01*
G01X1601727Y210400D02*
X1630644D01*
G01X1601250Y211550D02*
X1630167D01*
G01X1630644Y210400D02*
X1634031Y213787D01*
G01X1630167Y211550D02*
X1633554Y214937D01*
G01X1634031Y213787D02*
X1640186D01*
G01X1633554Y214937D02*
X1640663D01*
G01X1640186Y213787D02*
X1643621Y210352D01*
G01X1640663Y214937D02*
X1644098Y211502D01*
G01X1643621Y210352D02*
X1657139D01*
G01X1644098Y211502D02*
X1657616D01*
G01X1598253Y199675D02*
X1603774Y205196D01*
G01X1597776Y200825D02*
X1603297Y206346D01*
G01X1603774Y205196D02*
X1649816D01*
G01X1603297Y206346D02*
X1650293D01*
G01X1649816Y205196D02*
X1653476Y201536D01*
G01X1650293Y206346D02*
X1653953Y202686D01*
G01X1651888Y215339D02*
X1649477Y217750D01*
G01X1651411Y214189D02*
X1649000Y216600D01*
G01X1649477Y217750D02*
X1632618D01*
G01X1649000Y216600D02*
X1633095D01*
G01X1632618Y217750D02*
X1630718Y215850D01*
G01X1633095Y216600D02*
X1631195Y214700D01*
G01X1630718Y215850D02*
X1618778D01*
G01X1631195Y214700D02*
X1618301D01*
G01X1618778Y215850D02*
X1614178Y220450D01*
G01X1618301Y214700D02*
X1613701Y219300D01*
G01X1610124Y220450D02*
X1607383Y217709D01*
G01X1610601Y219300D02*
X1607860Y216559D01*
G01X1607383Y217709D02*
X1603539D01*
G01X1607860Y216559D02*
X1604016D01*
G01X1603539Y217709D02*
X1594200Y208370D01*
G01X1604016Y216559D02*
X1594677Y207220D01*
G01X1595547Y205847D02*
X1601250Y211550D01*
G01X1596024Y204697D02*
X1601727Y210400D01*
G01X1601250Y211550D02*
X1630167D01*
G01X1601727Y210400D02*
X1630644D01*
G01X1630167Y211550D02*
X1633554Y214937D01*
G01X1630644Y210400D02*
X1634031Y213787D01*
G01X1633554Y214937D02*
X1640663D01*
G01X1634031Y213787D02*
X1640186D01*
G01X1640663Y214937D02*
X1644098Y211502D01*
G01X1640186Y213787D02*
X1643621Y210352D01*
G01X1644098Y211502D02*
X1657616D01*
G01X1643621Y210352D02*
X1657139D01*
G01X1597776Y200825D02*
X1603297Y206346D01*
G01X1598253Y199675D02*
X1603774Y205196D01*
G01X1603297Y206346D02*
X1650293D01*
G01X1603774Y205196D02*
X1649816D01*
G01X1650293Y206346D02*
X1653953Y202686D01*
G01X1649816Y205196D02*
X1653476Y201536D01*
G01X1597216Y202175D02*
X1602941Y207900D01*
G01X1596739Y203325D02*
X1602464Y209050D01*
G01X1602941Y207900D02*
X1631900D01*
G01X1602464Y209050D02*
X1631423D01*
G01X1631900Y207900D02*
X1634688Y210688D01*
G01X1631423Y209050D02*
X1634211Y211838D01*
G01X1634688Y210688D02*
X1638888D01*
G01X1634211Y211838D02*
X1639365D01*
G01X1638888Y210688D02*
X1641880Y207696D01*
G01X1639365Y211838D02*
X1642357Y208846D01*
G01X1641880Y207696D02*
X1650851D01*
G01X1642357Y208846D02*
X1651330D01*
G01X1651618Y190480D02*
X1627536D01*
G01X1651141Y189330D02*
X1635059D01*
G01X1651618Y190480D02*
X1627536D01*
G01X1632409Y189330D02*
X1631059D01*
G01X1651618Y190480D02*
X1627536D01*
G01X1628409Y189330D02*
X1627059D01*
G01X1627536Y190480D02*
X1626116Y191900D01*
G01X1627059Y189330D02*
X1625639Y190750D01*
G01X1626116Y191900D02*
X1604652D01*
G01X1625639Y190750D02*
X1605129D01*
G01X1604652Y191900D02*
X1599375Y186623D01*
G01X1605129Y190750D02*
X1599852Y185473D01*
G01X1652393Y191830D02*
X1628096D01*
G01X1652870Y192980D02*
X1628573D01*
G01X1628096Y191830D02*
X1626676Y193250D01*
G01X1628573Y192980D02*
X1627153Y194400D01*
G01X1626676Y193250D02*
X1604008D01*
G01X1627153Y194400D02*
X1603531D01*
G01X1604008Y193250D02*
X1598776Y188018D01*
G01X1603531Y194400D02*
X1598299Y189168D01*
G01X1599680Y195630D02*
X1605396Y201346D01*
G01X1600157Y194480D02*
X1605873Y200196D01*
G01X1605396Y201346D02*
X1648208D01*
G01X1605873Y200196D02*
X1620266D01*
G01X1605396Y201346D02*
X1648208D01*
G01X1622916Y200196D02*
X1624266D01*
G01X1605396Y201346D02*
X1648208D01*
G01X1626916Y200196D02*
X1647731D01*
G01X1648208Y201346D02*
X1656958Y192596D01*
G01X1647731Y200196D02*
X1656481Y191446D01*
G01X1648779Y202696D02*
X1653233Y198242D01*
G01X1653710Y199392D02*
X1649256Y203846D01*
G01X1604836Y202696D02*
X1648779D01*
G01X1649256Y203846D02*
X1604360D01*
G01X1599302Y197175D02*
X1604836Y202696D01*
G01X1604360Y203846D02*
X1598826Y198325D01*
G01X1596739Y203325D02*
X1602464Y209050D01*
G01X1597216Y202175D02*
X1602941Y207900D01*
G01X1602464Y209050D02*
X1631423D01*
G01X1602941Y207900D02*
X1631900D01*
G01X1631423Y209050D02*
X1634211Y211838D01*
G01X1631900Y207900D02*
X1634688Y210688D01*
G01X1634211Y211838D02*
X1639365D01*
G01X1634688Y210688D02*
X1638888D01*
G01X1639365Y211838D02*
X1642357Y208846D01*
G01X1638888Y210688D02*
X1641880Y207696D01*
G01X1642357Y208846D02*
X1651330D01*
G01X1641880Y207696D02*
X1650851D01*
G01X1651141Y189330D02*
X1635059D01*
G01X1632409D02*
X1631059D01*
G01X1628409D02*
X1627059D01*
G01X1651618Y190480D02*
X1627536D01*
G01X1627059Y189330D02*
X1625639Y190750D01*
G01X1627536Y190480D02*
X1626116Y191900D01*
G01X1625639Y190750D02*
X1605129D01*
G01X1626116Y191900D02*
X1604652D01*
G01X1605129Y190750D02*
X1599852Y185473D01*
G01X1604652Y191900D02*
X1599375Y186623D01*
G01X1652870Y192980D02*
X1628573D01*
G01X1652393Y191830D02*
X1628096D01*
G01X1628573Y192980D02*
X1627153Y194400D01*
G01X1628096Y191830D02*
X1626676Y193250D01*
G01X1627153Y194400D02*
X1603531D01*
G01X1626676Y193250D02*
X1604008D01*
G01X1603531Y194400D02*
X1598299Y189168D01*
G01X1604008Y193250D02*
X1598776Y188018D01*
G01X1600157Y194480D02*
X1605873Y200196D01*
G01X1599680Y195630D02*
X1605396Y201346D01*
G01X1605873Y200196D02*
X1620266D01*
G01X1622916D02*
X1624266D01*
G01X1626916D02*
X1647731D01*
G01X1605396Y201346D02*
X1648208D01*
G01X1647731Y200196D02*
X1656481Y191446D01*
G01X1648208Y201346D02*
X1656958Y192596D01*
G01X1604360Y203846D02*
X1598826Y198325D01*
G01X1599302Y197175D02*
X1604836Y202696D01*
G01X1649256Y203846D02*
X1604360D01*
G01X1604836Y202696D02*
X1648779D01*
G01X1653710Y199392D02*
X1649256Y203846D01*
G01X1648779Y202696D02*
X1653233Y198242D01*
G01X1602930Y219979D02*
X1593801Y210850D01*
G01X1602453Y221129D02*
X1593324Y212000D01*
G01X1593801Y210850D02*
X1588944D01*
G01X1593324Y212000D02*
X1589421D01*
G01X1602453Y221129D02*
X1593324Y212000D01*
G01X1602930Y219979D02*
X1593801Y210850D01*
G01X1593324Y212000D02*
X1589421D01*
G01X1593801Y210850D02*
X1588944D01*
G01X1613701Y219300D02*
X1610601D01*
G01X1614178Y220450D02*
X1610124D01*
G01X1614178D02*
X1610124D01*
G01X1613701Y219300D02*
X1610601D01*
G01X1654229Y234805D02*
X1648934Y240100D01*
G01X1654706Y235955D02*
X1649411Y241250D01*
G01X1648934Y240100D02*
X1638241D01*
G01X1649411Y241250D02*
X1638718D01*
G01X1638241Y240100D02*
X1630431Y247910D01*
G01X1638718Y241250D02*
X1630908Y249060D01*
G01X1630431Y247910D02*
X1624591D01*
G01X1630908Y249060D02*
X1624114D01*
G01X1624591Y247910D02*
X1619300Y242619D01*
G01X1624114Y249060D02*
X1618823Y243769D01*
G01X1619300Y242619D02*
X1614078D01*
G01X1618823Y243769D02*
X1613601D01*
G01X1614078Y242619D02*
X1608984Y237525D01*
G01X1613601Y243769D02*
X1608507Y238675D01*
G01X1608984Y237525D02*
X1601517D01*
G01X1608507Y238675D02*
X1601040D01*
G01X1601517Y237525D02*
X1599205Y235213D01*
G01X1601040Y238675D02*
X1598728Y236363D01*
G01X1599205Y235213D02*
X1596103D01*
G01X1598728Y236363D02*
X1595626D01*
G01X1596103Y235213D02*
X1595098Y234208D01*
G01X1595626Y236363D02*
X1594621Y235358D01*
G01X1653192Y232305D02*
X1647897Y237600D01*
G01X1653669Y233455D02*
X1648374Y238750D01*
G01X1647897Y237600D02*
X1637204D01*
G01X1648374Y238750D02*
X1637681D01*
G01X1637204Y237600D02*
X1629424Y245380D01*
G01X1637681Y238750D02*
X1629901Y246530D01*
G01X1629424Y245380D02*
X1625620D01*
G01X1629901Y246530D02*
X1625143D01*
G01X1625620Y245380D02*
X1620308Y240068D01*
G01X1625143Y246530D02*
X1619831Y241218D01*
G01X1620308Y240068D02*
X1615064D01*
G01X1619831Y241218D02*
X1614587D01*
G01X1615064Y240068D02*
X1610021Y235025D01*
G01X1614587Y241218D02*
X1609544Y236175D01*
G01X1610021Y235025D02*
X1602554D01*
G01X1609544Y236175D02*
X1602077D01*
G01X1602554Y235025D02*
X1600239Y232710D01*
G01X1602077Y236175D02*
X1599762Y233860D01*
G01X1600239Y232710D02*
X1597357D01*
G01X1599762Y233860D02*
X1596880D01*
G01X1597357Y232710D02*
X1596355Y231708D01*
G01X1596880Y233860D02*
X1595878Y232858D01*
G01X1656208Y229805D02*
X1640988D01*
G01X1656685Y230955D02*
X1641465D01*
G01X1640988Y229805D02*
X1635273Y235520D01*
G01X1641465Y230955D02*
X1635750Y236670D01*
G01X1635273Y235520D02*
X1614053D01*
G01X1635750Y236670D02*
X1613576D01*
G01X1614053Y235520D02*
X1611058Y232525D01*
G01X1613576Y236670D02*
X1610581Y233675D01*
G01X1611058Y232525D02*
X1603591D01*
G01X1610581Y233675D02*
X1603114D01*
G01X1603591Y232525D02*
X1601266Y230200D01*
G01X1603114Y233675D02*
X1600789Y231350D01*
G01X1601266Y230200D02*
X1598400D01*
G01X1600789Y231350D02*
X1597923D01*
G01X1598400Y230200D02*
X1597408Y229208D01*
G01X1597923Y231350D02*
X1596931Y230358D01*
G01X1655171Y227305D02*
X1639951D01*
G01X1655648Y228455D02*
X1640428D01*
G01X1639951Y227305D02*
X1634236Y233020D01*
G01X1640428Y228455D02*
X1634713Y234170D01*
G01X1634236Y233020D02*
X1615090D01*
G01X1634713Y234170D02*
X1614613D01*
G01X1615090Y233020D02*
X1612095Y230025D01*
G01X1614613Y234170D02*
X1611618Y231175D01*
G01X1612095Y230025D02*
X1604628D01*
G01X1611618Y231175D02*
X1604151D01*
G01X1604628Y230025D02*
X1602296Y227693D01*
G01X1604151Y231175D02*
X1601819Y228843D01*
G01X1602296Y227693D02*
X1599558D01*
G01X1601819Y228843D02*
X1599081D01*
G01X1599558Y227693D02*
X1598521Y226656D01*
G01X1599081Y228843D02*
X1598044Y227806D01*
G01X1589934Y222225D02*
X1588904Y223255D01*
G01X1589381Y224405D02*
X1590411Y223375D01*
G01X1597894Y222225D02*
X1589934D01*
G01X1590411Y223375D02*
X1597417D01*
G01X1600807Y225138D02*
X1597894Y222225D01*
G01X1597417Y223375D02*
X1600330Y226288D01*
G01X1603340Y225138D02*
X1600807D01*
G01X1600330Y226288D02*
X1602863D01*
G01X1605652Y227450D02*
X1603340Y225138D01*
G01X1602863Y226288D02*
X1605175Y228600D01*
G01X1613177Y227450D02*
X1605652D01*
G01X1605175Y228600D02*
X1612700D01*
G01X1616247Y230520D02*
X1613177Y227450D01*
G01X1612700Y228600D02*
X1615770Y231670D01*
G01X1633199Y230520D02*
X1616247D01*
G01X1615770Y231670D02*
X1633676D01*
G01X1638914Y224805D02*
X1633199Y230520D01*
G01X1633676Y231670D02*
X1639391Y225955D01*
G01X1654134Y224805D02*
X1638914D01*
G01X1639391Y225955D02*
X1654611D01*
G01X1653097Y222305D02*
X1637877D01*
G01X1653574Y223455D02*
X1638354D01*
G01X1637877Y222305D02*
X1632162Y228020D01*
G01X1638354Y223455D02*
X1632639Y229170D01*
G01X1632162Y228020D02*
X1617284D01*
G01X1632639Y229170D02*
X1616807D01*
G01X1617284Y228020D02*
X1614214Y224950D01*
G01X1616807Y229170D02*
X1613737Y226100D01*
G01X1614214Y224950D02*
X1606689D01*
G01X1613737Y226100D02*
X1606212D01*
G01X1606689Y224950D02*
X1604218Y222479D01*
G01X1606212Y226100D02*
X1603741Y223629D01*
G01X1604218Y222479D02*
X1601733D01*
G01X1603741Y223629D02*
X1601256D01*
G01X1601733Y222479D02*
X1598979Y219725D01*
G01X1601256Y223629D02*
X1598502Y220875D01*
G01X1652060Y219805D02*
X1623247D01*
G01X1620597D02*
X1618095D01*
G01X1652537Y220955D02*
X1618572D01*
G01X1618095Y219805D02*
X1615499Y222401D01*
G01X1618572Y220955D02*
X1615976Y223551D01*
G01X1615499Y222401D02*
X1607677D01*
G01X1615976Y223551D02*
X1607200D01*
G01X1607677Y222401D02*
X1605255Y219979D01*
G01X1607200Y223551D02*
X1604778Y221129D01*
G01X1605255Y219979D02*
X1602930D01*
G01X1604778Y221129D02*
X1602453D01*
G01X1601578Y241889D02*
X1606079Y246390D01*
G01X1602055Y240739D02*
X1606556Y245240D01*
G01X1606079Y246390D02*
X1617883D01*
G01X1606556Y245240D02*
X1618360D01*
G01X1617883Y246390D02*
X1623053Y251560D01*
G01X1618360Y245240D02*
X1623530Y250410D01*
G01X1623053Y251560D02*
X1631967D01*
G01X1623530Y250410D02*
X1631490D01*
G01X1631967Y251560D02*
X1634377Y249150D01*
G01X1631490Y250410D02*
X1633900Y248000D01*
G01X1634377Y249150D02*
X1639369D01*
G01X1633900Y248000D02*
X1638892D01*
G01X1639369Y249150D02*
X1641297Y247222D01*
G01X1638892Y248000D02*
X1640147Y246745D01*
G01X1641297Y247222D02*
Y245668D01*
G01X1640147Y246745D02*
Y245191D01*
G01X1641297Y245668D02*
X1642730Y244235D01*
G01X1640147Y245191D02*
X1642253Y243085D01*
G01X1642730Y244235D02*
X1649963D01*
G01X1642253Y243085D02*
X1649486D01*
G01X1649963Y244235D02*
X1655743Y238455D01*
G01X1649486Y243085D02*
X1655266Y237305D01*
G01X1654706Y235955D02*
X1649411Y241250D01*
G01X1654229Y234805D02*
X1648934Y240100D01*
G01X1649411Y241250D02*
X1638718D01*
G01X1648934Y240100D02*
X1638241D01*
G01X1638718Y241250D02*
X1630908Y249060D01*
G01X1638241Y240100D02*
X1630431Y247910D01*
G01X1630908Y249060D02*
X1624114D01*
G01X1630431Y247910D02*
X1624591D01*
G01X1624114Y249060D02*
X1618823Y243769D01*
G01X1624591Y247910D02*
X1619300Y242619D01*
G01X1618823Y243769D02*
X1613601D01*
G01X1619300Y242619D02*
X1614078D01*
G01X1613601Y243769D02*
X1608507Y238675D01*
G01X1614078Y242619D02*
X1608984Y237525D01*
G01X1608507Y238675D02*
X1601040D01*
G01X1608984Y237525D02*
X1601517D01*
G01X1601040Y238675D02*
X1598728Y236363D01*
G01X1601517Y237525D02*
X1599205Y235213D01*
G01X1598728Y236363D02*
X1595626D01*
G01X1599205Y235213D02*
X1596103D01*
G01X1595626Y236363D02*
X1594621Y235358D01*
G01X1596103Y235213D02*
X1595098Y234208D01*
G01X1653669Y233455D02*
X1648374Y238750D01*
G01X1653192Y232305D02*
X1647897Y237600D01*
G01X1648374Y238750D02*
X1637681D01*
G01X1647897Y237600D02*
X1637204D01*
G01X1637681Y238750D02*
X1629901Y246530D01*
G01X1637204Y237600D02*
X1629424Y245380D01*
G01X1629901Y246530D02*
X1625143D01*
G01X1629424Y245380D02*
X1625620D01*
G01X1625143Y246530D02*
X1619831Y241218D01*
G01X1625620Y245380D02*
X1620308Y240068D01*
G01X1619831Y241218D02*
X1614587D01*
G01X1620308Y240068D02*
X1615064D01*
G01X1614587Y241218D02*
X1609544Y236175D01*
G01X1615064Y240068D02*
X1610021Y235025D01*
G01X1609544Y236175D02*
X1602077D01*
G01X1610021Y235025D02*
X1602554D01*
G01X1602077Y236175D02*
X1599762Y233860D01*
G01X1602554Y235025D02*
X1600239Y232710D01*
G01X1599762Y233860D02*
X1596880D01*
G01X1600239Y232710D02*
X1597357D01*
G01X1596880Y233860D02*
X1595878Y232858D01*
G01X1597357Y232710D02*
X1596355Y231708D01*
G01X1656685Y230955D02*
X1641465D01*
G01X1656208Y229805D02*
X1640988D01*
G01X1641465Y230955D02*
X1635750Y236670D01*
G01X1640988Y229805D02*
X1635273Y235520D01*
G01X1635750Y236670D02*
X1613576D01*
G01X1635273Y235520D02*
X1614053D01*
G01X1613576Y236670D02*
X1610581Y233675D01*
G01X1614053Y235520D02*
X1611058Y232525D01*
G01X1610581Y233675D02*
X1603114D01*
G01X1611058Y232525D02*
X1603591D01*
G01X1603114Y233675D02*
X1600789Y231350D01*
G01X1603591Y232525D02*
X1601266Y230200D01*
G01X1600789Y231350D02*
X1597923D01*
G01X1601266Y230200D02*
X1598400D01*
G01X1597923Y231350D02*
X1596931Y230358D01*
G01X1598400Y230200D02*
X1597408Y229208D01*
G01X1655648Y228455D02*
X1640428D01*
G01X1655171Y227305D02*
X1639951D01*
G01X1640428Y228455D02*
X1634713Y234170D01*
G01X1639951Y227305D02*
X1634236Y233020D01*
G01X1634713Y234170D02*
X1614613D01*
G01X1634236Y233020D02*
X1615090D01*
G01X1614613Y234170D02*
X1611618Y231175D01*
G01X1615090Y233020D02*
X1612095Y230025D01*
G01X1611618Y231175D02*
X1604151D01*
G01X1612095Y230025D02*
X1604628D01*
G01X1604151Y231175D02*
X1601819Y228843D01*
G01X1604628Y230025D02*
X1602296Y227693D01*
G01X1601819Y228843D02*
X1599081D01*
G01X1602296Y227693D02*
X1599558D01*
G01X1599081Y228843D02*
X1598044Y227806D01*
G01X1599558Y227693D02*
X1598521Y226656D01*
G01X1639391Y225955D02*
X1654611D01*
G01X1654134Y224805D02*
X1638914D01*
G01X1633676Y231670D02*
X1639391Y225955D01*
G01X1638914Y224805D02*
X1633199Y230520D01*
G01X1615770Y231670D02*
X1633676D01*
G01X1633199Y230520D02*
X1616247D01*
G01X1612700Y228600D02*
X1615770Y231670D01*
G01X1616247Y230520D02*
X1613177Y227450D01*
G01X1605175Y228600D02*
X1612700D01*
G01X1613177Y227450D02*
X1605652D01*
G01X1602863Y226288D02*
X1605175Y228600D01*
G01X1605652Y227450D02*
X1603340Y225138D01*
G01X1600330Y226288D02*
X1602863D01*
G01X1603340Y225138D02*
X1600807D01*
G01X1597417Y223375D02*
X1600330Y226288D01*
G01X1600807Y225138D02*
X1597894Y222225D01*
G01X1590411Y223375D02*
X1597417D01*
G01X1597894Y222225D02*
X1589934D01*
G01X1589381Y224405D02*
X1590411Y223375D01*
G01X1589934Y222225D02*
X1588904Y223255D01*
G01X1653574Y223455D02*
X1638354D01*
G01X1653097Y222305D02*
X1637877D01*
G01X1638354Y223455D02*
X1632639Y229170D01*
G01X1637877Y222305D02*
X1632162Y228020D01*
G01X1632639Y229170D02*
X1616807D01*
G01X1632162Y228020D02*
X1617284D01*
G01X1616807Y229170D02*
X1613737Y226100D01*
G01X1617284Y228020D02*
X1614214Y224950D01*
G01X1613737Y226100D02*
X1606212D01*
G01X1614214Y224950D02*
X1606689D01*
G01X1606212Y226100D02*
X1603741Y223629D01*
G01X1606689Y224950D02*
X1604218Y222479D01*
G01X1603741Y223629D02*
X1601256D01*
G01X1604218Y222479D02*
X1601733D01*
G01X1601256Y223629D02*
X1598502Y220875D01*
G01X1601733Y222479D02*
X1598979Y219725D01*
G01X1652537Y220955D02*
X1618572D01*
G01X1652060Y219805D02*
X1623247D01*
G01X1652537Y220955D02*
X1618572D01*
G01X1620597Y219805D02*
X1618095D01*
G01X1618572Y220955D02*
X1615976Y223551D01*
G01X1618095Y219805D02*
X1615499Y222401D01*
G01X1615976Y223551D02*
X1607200D01*
G01X1615499Y222401D02*
X1607677D01*
G01X1607200Y223551D02*
X1604778Y221129D01*
G01X1607677Y222401D02*
X1605255Y219979D01*
G01X1604778Y221129D02*
X1602453D01*
G01X1605255Y219979D02*
X1602930D01*
G01X1602055Y240739D02*
X1606556Y245240D01*
G01X1601578Y241889D02*
X1606079Y246390D01*
G01X1606556Y245240D02*
X1618360D01*
G01X1606079Y246390D02*
X1617883D01*
G01X1618360Y245240D02*
X1623530Y250410D01*
G01X1617883Y246390D02*
X1623053Y251560D01*
G01X1623530Y250410D02*
X1631490D01*
G01X1623053Y251560D02*
X1631967D01*
G01X1631490Y250410D02*
X1633900Y248000D01*
G01X1631967Y251560D02*
X1634377Y249150D01*
G01X1633900Y248000D02*
X1638892D01*
G01X1634377Y249150D02*
X1639369D01*
G01X1638892Y248000D02*
X1640147Y246745D01*
G01X1639369Y249150D02*
X1641297Y247222D01*
G01X1640147Y246745D02*
Y245191D01*
G01X1641297Y247222D02*
Y245668D01*
G01X1640147Y245191D02*
X1642253Y243085D01*
G01X1641297Y245668D02*
X1642730Y244235D01*
G01X1642253Y243085D02*
X1649486D01*
G01X1642730Y244235D02*
X1649963D01*
G01X1649486Y243085D02*
X1655266Y237305D01*
G01X1649963Y244235D02*
X1655743Y238455D01*
G01X1643375Y318814D02*
Y279398D01*
G01X1644525Y279875D02*
X1651550Y272850D01*
G01X1643375Y279398D02*
X1651073Y271700D01*
G01X1643375Y318814D02*
Y279398D01*
G01D02*
X1651073Y271700D01*
G01X1644525Y279875D02*
X1651550Y272850D01*
G01X1596112Y320070D02*
X1601234Y325192D01*
G01X1596589Y318920D02*
X1601711Y324042D01*
G01X1601234Y325192D02*
X1607590D01*
G01X1601711Y324042D02*
X1608067D01*
G01X1607613Y325215D02*
X1609915D01*
G01X1608090Y324065D02*
X1609438D01*
G01X1609938Y325192D02*
X1620294D01*
G01X1609461Y324042D02*
X1619817D01*
G01X1620294Y325192D02*
X1622948Y322538D01*
G01X1619817Y324042D02*
X1622471Y321388D01*
G01X1622948Y322538D02*
X1641278D01*
G01X1622471Y321388D02*
X1640801D01*
G01X1641278Y322538D02*
X1644525Y319291D01*
G01X1640801Y321388D02*
X1643375Y318814D01*
G01X1644525Y319291D02*
Y279875D01*
G01X1596589Y318920D02*
X1601711Y324042D01*
G01X1596112Y320070D02*
X1601234Y325192D01*
G01X1601711Y324042D02*
X1608067D01*
G01X1601234Y325192D02*
X1607590D01*
G01X1608090Y324065D02*
X1609438D01*
G01X1607613Y325215D02*
X1609915D01*
G01X1609461Y324042D02*
X1619817D01*
G01X1609938Y325192D02*
X1620294D01*
G01X1619817Y324042D02*
X1622471Y321388D01*
G01X1620294Y325192D02*
X1622948Y322538D01*
G01X1622471Y321388D02*
X1640801D01*
G01X1622948Y322538D02*
X1641278D01*
G01X1640801Y321388D02*
X1643375Y318814D01*
G01X1641278Y322538D02*
X1644525Y319291D01*
G01D02*
Y279875D01*
G01X1653044Y281585D02*
X1646522Y288107D01*
G01X1653521Y282735D02*
X1647672Y288584D01*
G01X1646522Y288107D02*
Y321701D01*
G01X1647672Y288584D02*
Y322178D01*
G01X1646522Y321701D02*
X1640058Y328165D01*
G01X1647672Y322178D02*
X1640535Y329315D01*
G01X1640058Y328165D02*
X1634810D01*
G01X1640535Y329315D02*
X1634333D01*
G01X1634810Y328165D02*
X1631501Y324856D01*
G01X1634333Y329315D02*
X1631024Y326006D01*
G01X1631501Y324856D02*
X1624021D01*
G01X1631024Y326006D02*
X1624498D01*
G01X1624021Y324856D02*
X1622195Y326682D01*
G01X1624498Y326006D02*
X1622672Y327832D01*
G01X1622195Y326682D02*
X1598059D01*
G01X1622672Y327832D02*
X1597582D01*
G01X1598059Y326682D02*
X1597444Y326067D01*
G01X1597582Y327832D02*
X1596967Y327217D01*
G01X1653521Y282735D02*
X1647672Y288584D01*
G01X1653044Y281585D02*
X1646522Y288107D01*
G01X1647672Y288584D02*
Y322178D01*
G01X1646522Y288107D02*
Y321701D01*
G01X1647672Y322178D02*
X1640535Y329315D01*
G01X1646522Y321701D02*
X1640058Y328165D01*
G01X1640535Y329315D02*
X1634333D01*
G01X1640058Y328165D02*
X1634810D01*
G01X1634333Y329315D02*
X1631024Y326006D01*
G01X1634810Y328165D02*
X1631501Y324856D01*
G01X1631024Y326006D02*
X1624498D01*
G01X1631501Y324856D02*
X1624021D01*
G01X1624498Y326006D02*
X1622672Y327832D01*
G01X1624021Y324856D02*
X1622195Y326682D01*
G01X1622672Y327832D02*
X1597582D01*
G01X1622195Y326682D02*
X1598059D01*
G01X1597582Y327832D02*
X1596967Y327217D01*
G01X1598059Y326682D02*
X1597444Y326067D01*
G01X1595919Y328803D02*
X1600045Y332929D01*
G01X1595442Y329953D02*
X1599568Y334079D01*
G01X1600045Y332929D02*
X1603991D01*
G01X1599568Y334079D02*
X1604468D01*
G01X1603991Y332929D02*
X1607691Y329229D01*
G01X1604468Y334079D02*
X1608168Y330379D01*
G01X1607691Y329229D02*
X1621456D01*
G01X1608168Y330379D02*
X1620979D01*
G01X1621456Y329229D02*
X1622892Y330665D01*
G01X1620979Y330379D02*
X1622415Y331815D01*
G01X1622892Y330665D02*
X1641407D01*
G01X1622415Y331815D02*
X1641884D01*
G01X1641407Y330665D02*
X1649200Y322872D01*
G01X1641884Y331815D02*
X1650350Y323349D01*
G01X1649200Y322872D02*
Y294965D01*
G01X1650350Y323349D02*
Y295442D01*
G01X1649200Y294965D02*
X1654478Y289687D01*
G01X1650350Y295442D02*
X1654955Y290837D01*
G01X1595442Y329953D02*
X1599568Y334079D01*
G01X1595919Y328803D02*
X1600045Y332929D01*
G01X1599568Y334079D02*
X1604468D01*
G01X1600045Y332929D02*
X1603991D01*
G01X1604468Y334079D02*
X1608168Y330379D01*
G01X1603991Y332929D02*
X1607691Y329229D01*
G01X1608168Y330379D02*
X1620979D01*
G01X1607691Y329229D02*
X1621456D01*
G01X1620979Y330379D02*
X1622415Y331815D01*
G01X1621456Y329229D02*
X1622892Y330665D01*
G01X1622415Y331815D02*
X1641884D01*
G01X1622892Y330665D02*
X1641407D01*
G01X1641884Y331815D02*
X1650350Y323349D01*
G01X1641407Y330665D02*
X1649200Y322872D01*
G01X1650350Y323349D02*
Y295442D01*
G01X1649200Y322872D02*
Y294965D01*
G01X1650350Y295442D02*
X1654955Y290837D01*
G01X1649200Y294965D02*
X1654478Y289687D01*
G01X1667236Y409464D02*
X1648074Y428626D01*
G01X1666759Y408314D02*
X1647598Y427475D01*
G01X1647957Y428625D02*
X1646443D01*
G01X1647598Y427475D02*
X1645966D01*
G01X1646443Y428625D02*
X1644156Y430912D01*
G01X1645966Y427475D02*
X1643006Y430435D01*
G01X1644156Y430912D02*
Y460957D01*
G01X1643006Y430435D02*
Y461434D01*
G01X1644156Y460957D02*
X1646150Y462951D01*
G01X1643006Y461434D02*
X1645000Y463428D01*
G01X1646150Y462951D02*
Y478150D01*
G01X1645000Y463428D02*
Y477673D01*
G01X1666759Y408314D02*
X1647598Y427475D01*
G01X1666759Y408314D02*
X1647598Y427475D01*
G01X1667236Y409464D02*
X1648074Y428626D01*
G01X1647598Y427475D02*
X1645966D01*
G01X1647957Y428625D02*
X1646443D01*
G01X1645966Y427475D02*
X1643006Y430435D01*
G01X1646443Y428625D02*
X1644156Y430912D01*
G01X1643006Y430435D02*
Y461434D01*
G01X1644156Y430912D02*
Y460957D01*
G01X1643006Y461434D02*
X1645000Y463428D01*
G01X1644156Y460957D02*
X1646150Y462951D01*
G01X1645000Y463428D02*
Y477673D01*
G01X1646150Y462951D02*
Y478150D01*
G01X1665951Y406364D02*
X1646790Y425525D01*
G01X1664801Y405887D02*
X1646313Y424375D01*
G01X1646790Y425525D02*
X1641547D01*
G01X1646313Y424375D02*
X1641070D01*
G01X1641547Y425525D02*
X1636851Y430221D01*
G01X1641070Y424375D02*
X1635701Y429744D01*
G01X1636851Y430221D02*
Y460551D01*
G01X1635701Y429744D02*
Y461028D01*
G01X1636851Y460551D02*
X1642000Y465700D01*
G01X1635701Y461028D02*
X1640850Y466177D01*
G01X1664801Y405887D02*
X1646313Y424375D01*
G01X1665951Y406364D02*
X1646790Y425525D01*
G01X1646313Y424375D02*
X1641070D01*
G01X1646790Y425525D02*
X1641547D01*
G01X1641070Y424375D02*
X1635701Y429744D01*
G01X1641547Y425525D02*
X1636851Y430221D01*
G01X1635701Y429744D02*
Y461028D01*
G01X1636851Y430221D02*
Y460551D01*
G01X1635701Y461028D02*
X1640850Y466177D01*
G01X1636851Y460551D02*
X1642000Y465700D01*
G01X1661040Y507150D02*
X1645698D01*
G01X1660871Y508300D02*
X1645931D01*
G01X1645698Y507150D02*
X1625935Y515490D01*
G01X1645931Y508300D02*
X1625981Y516719D01*
G01X1625935Y515490D02*
X1617007Y512484D01*
G01X1625981Y516719D02*
X1616980Y513689D01*
G01X1617007Y512484D02*
X1614152Y513306D01*
G01X1616980Y513689D02*
X1614201Y514489D01*
G01X1614152Y513306D02*
X1605348Y511545D01*
G01X1614201Y514489D02*
X1609834Y513616D01*
G01X1614152Y513306D02*
X1605348Y511545D01*
G01X1609834Y513616D02*
X1609833D01*
G01X1614152Y513306D02*
X1605348Y511545D01*
G01X1609833Y513616D02*
X1605465Y512742D01*
G01X1609570Y506664D02*
X1612187Y506147D01*
G01X1609905Y507771D02*
X1612187Y507320D01*
G01Y506147D02*
X1614375Y506580D01*
G01X1612187Y507320D02*
X1614375Y507753D01*
G01Y506580D02*
X1616309Y506197D01*
G01X1614375Y507753D02*
X1616309Y507370D01*
G01Y506197D02*
X1618274Y506586D01*
G01X1616309Y507370D02*
X1618274Y507759D01*
G01Y506586D02*
X1625210Y505211D01*
G01X1618274Y507759D02*
X1625541Y506318D01*
G01X1625210Y505211D02*
X1629963Y503283D01*
G01X1625541Y506318D02*
X1630077Y504478D01*
G01X1629963Y503283D02*
X1632280Y503741D01*
G01X1630077Y504478D02*
X1632280Y504914D01*
G01Y503741D02*
X1634207Y503360D01*
G01X1632280Y504914D02*
X1634201Y504534D01*
G01X1634207Y503360D02*
X1638124Y504179D01*
G01X1634201Y504534D02*
X1638158Y505362D01*
G01X1638124Y504179D02*
X1648601Y501351D01*
G01X1638158Y505362D02*
X1648622Y502537D01*
G01X1648601Y501351D02*
X1660222Y504045D01*
G01X1648622Y502537D02*
X1659927Y505158D01*
G01X1656345Y500224D02*
X1648582Y498674D01*
G01X1656067Y501342D02*
X1648621Y499855D01*
G01X1648582Y498674D02*
X1637964Y501540D01*
G01X1648621Y499855D02*
X1637998Y502722D01*
G01X1637964Y501540D02*
X1634222Y500758D01*
G01X1637998Y502722D02*
X1634216Y501932D01*
G01X1634222Y500758D02*
X1632235Y501151D01*
G01X1634216Y501932D02*
X1632235Y502324D01*
G01Y501151D02*
X1629683Y500645D01*
G01X1632235Y502324D02*
X1629797Y501840D01*
G01X1629683Y500645D02*
X1624428Y502776D01*
G01X1629797Y501840D02*
X1624759Y503883D01*
G01X1624428Y502776D02*
X1618297Y503992D01*
G01X1624759Y503883D02*
X1618297Y505165D01*
G01Y503992D02*
X1616309Y503598D01*
G01X1618297Y505165D02*
X1616311Y504771D01*
G01X1616309Y503598D02*
X1614344Y503987D01*
G01X1616311Y504771D02*
X1614344Y505160D01*
G01Y503987D02*
X1612157Y503554D01*
G01X1614344Y505160D02*
X1612157Y504727D01*
G01Y503554D02*
X1608800Y504217D01*
G01X1612157Y504727D02*
X1609135Y505324D01*
G01X1608040Y501705D02*
X1611998Y500922D01*
G01X1608375Y502812D02*
X1611998Y502095D01*
G01Y500922D02*
X1614347Y501387D01*
G01X1611998Y502095D02*
X1614347Y502560D01*
G01Y501387D02*
X1616309Y500999D01*
G01X1614347Y502560D02*
X1616309Y502172D01*
G01Y500999D02*
X1618365Y501407D01*
G01X1616309Y502172D02*
X1618365Y502580D01*
G01Y501407D02*
X1623546Y500382D01*
G01X1618365Y502580D02*
X1623877Y501489D01*
G01X1623546Y500382D02*
X1629431Y497996D01*
G01X1623877Y501489D02*
X1629545Y499191D01*
G01X1629431Y497996D02*
X1632239Y498551D01*
G01X1629545Y499191D02*
X1632239Y499724D01*
G01Y498551D02*
X1634237Y498156D01*
G01X1632239Y499724D02*
X1634231Y499330D01*
G01X1634237Y498156D02*
X1637964Y498935D01*
G01X1634231Y499330D02*
X1637998Y500117D01*
G01X1637964Y498935D02*
X1648621Y496058D01*
G01X1637998Y500117D02*
X1648660Y497239D01*
G01X1648621Y496058D02*
X1656729Y497678D01*
G01X1648660Y497239D02*
X1656451Y498796D01*
G01X1660871Y508300D02*
X1645931D01*
G01X1661040Y507150D02*
X1645698D01*
G01X1645931Y508300D02*
X1625981Y516719D01*
G01X1645698Y507150D02*
X1625935Y515490D01*
G01X1625981Y516719D02*
X1616980Y513689D01*
G01X1625935Y515490D02*
X1617007Y512484D01*
G01X1616980Y513689D02*
X1614201Y514489D01*
G01X1617007Y512484D02*
X1614152Y513306D01*
G01X1614201Y514489D02*
X1609834Y513616D01*
G01D02*
X1609833D01*
G01D02*
X1605465Y512742D01*
G01X1614152Y513306D02*
X1605348Y511545D01*
G01X1609905Y507771D02*
X1612187Y507320D01*
G01X1609570Y506664D02*
X1612187Y506147D01*
G01Y507320D02*
X1614375Y507753D01*
G01X1612187Y506147D02*
X1614375Y506580D01*
G01Y507753D02*
X1616309Y507370D01*
G01X1614375Y506580D02*
X1616309Y506197D01*
G01Y507370D02*
X1618274Y507759D01*
G01X1616309Y506197D02*
X1618274Y506586D01*
G01Y507759D02*
X1625541Y506318D01*
G01X1618274Y506586D02*
X1625210Y505211D01*
G01X1625541Y506318D02*
X1630077Y504478D01*
G01X1625210Y505211D02*
X1629963Y503283D01*
G01X1630077Y504478D02*
X1632280Y504914D01*
G01X1629963Y503283D02*
X1632280Y503741D01*
G01Y504914D02*
X1634201Y504534D01*
G01X1632280Y503741D02*
X1634207Y503360D01*
G01X1634201Y504534D02*
X1638158Y505362D01*
G01X1634207Y503360D02*
X1638124Y504179D01*
G01X1638158Y505362D02*
X1648622Y502537D01*
G01X1638124Y504179D02*
X1648601Y501351D01*
G01X1648622Y502537D02*
X1659927Y505158D01*
G01X1648601Y501351D02*
X1660222Y504045D01*
G01X1656067Y501342D02*
X1648621Y499855D01*
G01X1656345Y500224D02*
X1648582Y498674D01*
G01X1648621Y499855D02*
X1637998Y502722D01*
G01X1648582Y498674D02*
X1637964Y501540D01*
G01X1637998Y502722D02*
X1634216Y501932D01*
G01X1637964Y501540D02*
X1634222Y500758D01*
G01X1634216Y501932D02*
X1632235Y502324D01*
G01X1634222Y500758D02*
X1632235Y501151D01*
G01Y502324D02*
X1629797Y501840D01*
G01X1632235Y501151D02*
X1629683Y500645D01*
G01X1629797Y501840D02*
X1624759Y503883D01*
G01X1629683Y500645D02*
X1624428Y502776D01*
G01X1624759Y503883D02*
X1618297Y505165D01*
G01X1624428Y502776D02*
X1618297Y503992D01*
G01Y505165D02*
X1616311Y504771D01*
G01X1618297Y503992D02*
X1616309Y503598D01*
G01X1616311Y504771D02*
X1614344Y505160D01*
G01X1616309Y503598D02*
X1614344Y503987D01*
G01Y505160D02*
X1612157Y504727D01*
G01X1614344Y503987D02*
X1612157Y503554D01*
G01Y504727D02*
X1609135Y505324D01*
G01X1612157Y503554D02*
X1608800Y504217D01*
G01X1608375Y502812D02*
X1611998Y502095D01*
G01X1608040Y501705D02*
X1611998Y500922D01*
G01Y502095D02*
X1614347Y502560D01*
G01X1611998Y500922D02*
X1614347Y501387D01*
G01Y502560D02*
X1616309Y502172D01*
G01X1614347Y501387D02*
X1616309Y500999D01*
G01Y502172D02*
X1618365Y502580D01*
G01X1616309Y500999D02*
X1618365Y501407D01*
G01Y502580D02*
X1623877Y501489D01*
G01X1618365Y501407D02*
X1623546Y500382D01*
G01X1623877Y501489D02*
X1629545Y499191D01*
G01X1623546Y500382D02*
X1629431Y497996D01*
G01X1629545Y499191D02*
X1632239Y499724D01*
G01X1629431Y497996D02*
X1632239Y498551D01*
G01Y499724D02*
X1634231Y499330D01*
G01X1632239Y498551D02*
X1634237Y498156D01*
G01X1634231Y499330D02*
X1637998Y500117D01*
G01X1634237Y498156D02*
X1637964Y498935D01*
G01X1637998Y500117D02*
X1648660Y497239D01*
G01X1637964Y498935D02*
X1648621Y496058D01*
G01X1648660Y497239D02*
X1656451Y498796D01*
G01X1648621Y496058D02*
X1656729Y497678D01*
G01X1646150Y478150D02*
X1640377Y483923D01*
G01X1645000Y477673D02*
X1639900Y482773D01*
G01X1640377Y483923D02*
X1639659D01*
G01X1639900Y482773D02*
X1639182D01*
G01X1639659Y483923D02*
X1636082Y487500D01*
G01X1639182Y482773D02*
X1635605Y486350D01*
G01X1636082Y487500D02*
X1614244D01*
G01X1635605Y486350D02*
X1613767D01*
G01X1614244Y487500D02*
X1613625Y488120D01*
G01X1613767Y486350D02*
X1612679Y487438D01*
G01X1613625Y488120D02*
X1612006Y491354D01*
G01X1612679Y487438D02*
X1611060Y490672D01*
G01X1612006Y491354D02*
X1605671Y497689D01*
G01X1611060Y490672D02*
X1605009Y496723D01*
G01X1605671Y497689D02*
X1600924Y499782D01*
G01X1605009Y496723D02*
X1600681Y498632D01*
G01X1645000Y477673D02*
X1639900Y482773D01*
G01X1646150Y478150D02*
X1640377Y483923D01*
G01X1639900Y482773D02*
X1639182D01*
G01X1640377Y483923D02*
X1639659D01*
G01X1639182Y482773D02*
X1635605Y486350D01*
G01X1639659Y483923D02*
X1636082Y487500D01*
G01X1635605Y486350D02*
X1613767D01*
G01X1636082Y487500D02*
X1614244D01*
G01X1613767Y486350D02*
X1612679Y487438D01*
G01X1614244Y487500D02*
X1613625Y488120D01*
G01X1612679Y487438D02*
X1611060Y490672D01*
G01X1613625Y488120D02*
X1612006Y491354D01*
G01X1611060Y490672D02*
X1605009Y496723D01*
G01X1612006Y491354D02*
X1605671Y497689D01*
G01X1605009Y496723D02*
X1600681Y498632D01*
G01X1605671Y497689D02*
X1600924Y499782D01*
G01X1642000Y465700D02*
Y477870D01*
G01X1640850Y466177D02*
Y477393D01*
G01X1642000Y477870D02*
X1639636Y480234D01*
G01X1640850Y477393D02*
X1639159Y479084D01*
G01X1639636Y480234D02*
X1637215D01*
G01X1639159Y479084D02*
X1636738D01*
G01X1637215Y480234D02*
X1633049Y484400D01*
G01X1636738Y479084D02*
X1632572Y483250D01*
G01X1633049Y484400D02*
X1611900D01*
G01X1632572Y483250D02*
X1611423D01*
G01X1611900Y484400D02*
X1610017Y486283D01*
G01X1611423Y483250D02*
X1608867Y485806D01*
G01X1610017Y486283D02*
Y488203D01*
G01X1608867Y485806D02*
Y487726D01*
G01X1610017Y488203D02*
X1606213Y492007D01*
G01X1608867Y487726D02*
X1605736Y490857D01*
G01X1606213Y492007D02*
X1600516D01*
G01X1605736Y490857D02*
X1600039D01*
G01X1600516Y492007D02*
X1599627Y492896D01*
G01X1600039Y490857D02*
X1598477Y492419D01*
G01X1599627Y492896D02*
Y494263D01*
G01X1598477Y492419D02*
Y494319D01*
G01X1640850Y466177D02*
Y477393D01*
G01X1642000Y465700D02*
Y477870D01*
G01X1640850Y477393D02*
X1639159Y479084D01*
G01X1642000Y477870D02*
X1639636Y480234D01*
G01X1639159Y479084D02*
X1636738D01*
G01X1639636Y480234D02*
X1637215D01*
G01X1636738Y479084D02*
X1632572Y483250D01*
G01X1637215Y480234D02*
X1633049Y484400D01*
G01X1632572Y483250D02*
X1611423D01*
G01X1633049Y484400D02*
X1611900D01*
G01X1611423Y483250D02*
X1608867Y485806D01*
G01X1611900Y484400D02*
X1610017Y486283D01*
G01X1608867Y485806D02*
Y487726D01*
G01X1610017Y486283D02*
Y488203D01*
G01X1608867Y487726D02*
X1605736Y490857D01*
G01X1610017Y488203D02*
X1606213Y492007D01*
G01X1605736Y490857D02*
X1600039D01*
G01X1606213Y492007D02*
X1600516D01*
G01X1600039Y490857D02*
X1598477Y492419D01*
G01X1600516Y492007D02*
X1599627Y492896D01*
G01X1598477Y492419D02*
Y494319D01*
G01X1599627Y492896D02*
Y494263D01*
G01X1598875Y557994D02*
X1609418Y553624D01*
G01X1599104Y559144D02*
X1609647Y554774D01*
G01X1598875Y557994D02*
X1609418Y553624D01*
G01D02*
X1610052D01*
G01X1609647Y554774D02*
X1610281D01*
G01X1609418Y553624D02*
X1610052D01*
G01D02*
X1617218Y550655D01*
G01X1610281Y554774D02*
X1617447Y551805D01*
G01X1617218Y550655D02*
X1655761D01*
G01X1617447Y551805D02*
X1655284D01*
G01X1599104Y559144D02*
X1609647Y554774D01*
G01D02*
X1610281D01*
G01X1598875Y557994D02*
X1609418Y553624D01*
G01X1609647Y554774D02*
X1610281D01*
G01D02*
X1617447Y551805D01*
G01X1609418Y553624D02*
X1610052D01*
G01X1610281Y554774D02*
X1617447Y551805D01*
G01X1610052Y553624D02*
X1617218Y550655D01*
G01X1617447Y551805D02*
X1655284D01*
G01X1617218Y550655D02*
X1655761D01*
G01X1654613Y522305D02*
X1647551Y533384D01*
G01X1655474Y523096D02*
X1648369Y534243D01*
G01X1647551Y533384D02*
X1644739Y534971D01*
G01X1648369Y534243D02*
X1645146Y536062D01*
G01X1644739Y534971D02*
X1637699Y536441D01*
G01X1645146Y536062D02*
X1637631Y537631D01*
G01X1637699Y536441D02*
X1628684Y533454D01*
G01X1637631Y537631D02*
X1628605Y534640D01*
G01X1637699Y536441D02*
X1628684Y533454D01*
G01D02*
X1613340Y536344D01*
G01X1628605Y534640D02*
X1628604D01*
G01X1628684Y533454D02*
X1613340Y536344D01*
G01X1628604Y534640D02*
X1613803Y537428D01*
G01X1613340Y536344D02*
X1606243Y541424D01*
G01X1613803Y537428D02*
X1606711Y542504D01*
G01X1606243Y541424D02*
X1596088Y543454D01*
G01X1606711Y542504D02*
X1596089Y544627D01*
G01X1594128Y552970D02*
X1609791Y549836D01*
G01X1594127Y551797D02*
X1609322Y548756D01*
G01X1609791Y549836D02*
X1617124Y544589D01*
G01X1609322Y548756D02*
X1616661Y543505D01*
G01X1617124Y544589D02*
X1628096Y542522D01*
G01D02*
X1628097D01*
G01X1616661Y543505D02*
X1627881Y541392D01*
G01X1617124Y544589D02*
X1628096Y542522D01*
G01X1627883Y541391D02*
X1628029Y541364D01*
G01X1617124Y544589D02*
X1628096Y542522D01*
G01X1628029Y541364D02*
X1628176Y541336D01*
G01X1628096Y542522D02*
X1628097D01*
G01D02*
X1637194Y545536D01*
G01X1628176Y541336D02*
X1637262Y544347D01*
G01X1637194Y545536D02*
X1647962Y543290D01*
G01X1637262Y544347D02*
X1647552Y542200D01*
G01X1647962Y543290D02*
X1653761Y540016D01*
G01X1647552Y542200D02*
X1652945Y539155D01*
G01X1651169Y537197D02*
X1646527Y539818D01*
G01X1651985Y538058D02*
X1646937Y540908D01*
G01X1646527Y539818D02*
X1637415Y541720D01*
G01X1646937Y540908D02*
X1637347Y542909D01*
G01X1637415Y541720D02*
X1628338Y538711D01*
G01X1637347Y542909D02*
X1628258Y539897D01*
G01X1628338Y538711D02*
X1615578Y541112D01*
G01X1628258Y539897D02*
X1616041Y542196D01*
G01X1615578Y541113D02*
X1608221Y546378D01*
G01X1616041Y542196D02*
X1608689Y547458D01*
G01X1608221Y546378D02*
X1596010Y548819D01*
G01X1608689Y547458D02*
X1596011Y549992D01*
G01X1655474Y523096D02*
X1648369Y534243D01*
G01X1654613Y522305D02*
X1647551Y533384D01*
G01X1648369Y534243D02*
X1645146Y536062D01*
G01X1647551Y533384D02*
X1644739Y534971D01*
G01X1645146Y536062D02*
X1637631Y537631D01*
G01X1644739Y534971D02*
X1637699Y536441D01*
G01X1637631Y537631D02*
X1628605Y534640D01*
G01D02*
X1628604D01*
G01X1637699Y536441D02*
X1628684Y533454D01*
G01X1628605Y534640D02*
X1628604D01*
G01D02*
X1613803Y537428D01*
G01X1628684Y533454D02*
X1613340Y536344D01*
G01X1613803Y537428D02*
X1606711Y542504D01*
G01X1613340Y536344D02*
X1606243Y541424D01*
G01X1606711Y542504D02*
X1596089Y544627D01*
G01X1606243Y541424D02*
X1596088Y543454D01*
G01X1594127Y551797D02*
X1609322Y548756D01*
G01X1594128Y552970D02*
X1609791Y549836D01*
G01X1609322Y548756D02*
X1616661Y543505D01*
G01X1609791Y549836D02*
X1617124Y544589D01*
G01X1616661Y543505D02*
X1627881Y541392D01*
G01X1627883Y541391D02*
X1628029Y541364D01*
G01D02*
X1628176Y541336D01*
G01X1617124Y544589D02*
X1628096Y542522D01*
G01X1616661Y543505D02*
X1627881Y541392D01*
G01X1628176Y541336D02*
X1637262Y544347D01*
G01X1628096Y542522D02*
X1628097D01*
G01X1628176Y541336D02*
X1637262Y544347D01*
G01X1628097Y542522D02*
X1637194Y545536D01*
G01X1637262Y544347D02*
X1647552Y542200D01*
G01X1637194Y545536D02*
X1647962Y543290D01*
G01X1647552Y542200D02*
X1652945Y539155D01*
G01X1647962Y543290D02*
X1653761Y540016D01*
G01X1651985Y538058D02*
X1646937Y540908D01*
G01X1651169Y537197D02*
X1646527Y539818D01*
G01X1646937Y540908D02*
X1637347Y542909D01*
G01X1646527Y539818D02*
X1637415Y541720D01*
G01X1637347Y542909D02*
X1628258Y539897D01*
G01X1637415Y541720D02*
X1628338Y538711D01*
G01X1628258Y539897D02*
X1616041Y542196D01*
G01X1628338Y538711D02*
X1615578Y541112D01*
G01X1616041Y542196D02*
X1608689Y547458D01*
G01X1615578Y541113D02*
X1608221Y546378D01*
G01X1608689Y547458D02*
X1596011Y549992D01*
G01X1608221Y546378D02*
X1596010Y548819D01*
G01X1656521Y524058D02*
X1649416Y535206D01*
G01X1657382Y524849D02*
X1650232Y536067D01*
G01X1649416Y535206D02*
X1645493Y537420D01*
G01X1650232Y536067D02*
X1645903Y538510D01*
G01X1645493Y537420D02*
X1637548Y539077D01*
G01X1645903Y538510D02*
X1637480Y540267D01*
G01X1637548Y539077D02*
X1628512Y536083D01*
G01X1637480Y540266D02*
X1628432Y537269D01*
G01X1628512Y536083D02*
X1614500Y538721D01*
G01X1628430Y537269D02*
X1614963Y539805D01*
G01X1614500Y538721D02*
X1607166Y543970D01*
G01X1614963Y539805D02*
X1607634Y545050D01*
G01X1607166Y543970D02*
X1596121Y546178D01*
G01X1607634Y545050D02*
X1596122Y547351D01*
G01X1657382Y524849D02*
X1650232Y536067D01*
G01X1656521Y524058D02*
X1649416Y535206D01*
G01X1650232Y536067D02*
X1645903Y538510D01*
G01X1649416Y535206D02*
X1645493Y537420D01*
G01X1645903Y538510D02*
X1637480Y540267D01*
G01X1645493Y537420D02*
X1637548Y539077D01*
G01X1637480Y540266D02*
X1628432Y537269D01*
G01X1637548Y539077D02*
X1628512Y536083D01*
G01X1628430Y537269D02*
X1614963Y539805D01*
G01X1628512Y536083D02*
X1614500Y538721D01*
G01X1614963Y539805D02*
X1607634Y545050D01*
G01X1614500Y538721D02*
X1607166Y543970D01*
G01X1607634Y545050D02*
X1596122Y547351D01*
G01X1607166Y543970D02*
X1596121Y546178D01*
G01X1718977Y205542D02*
X1686127D01*
G01X1719454Y206692D02*
X1686604D01*
G01X1686127Y205542D02*
X1679870Y211799D01*
G01X1686604Y206692D02*
X1680347Y212949D01*
G01X1679870Y211799D02*
X1672054D01*
G01X1680347Y212949D02*
X1672531D01*
G01X1672054Y211799D02*
X1667999Y215854D01*
G01X1672531Y212949D02*
X1668476Y217004D01*
G01X1667999Y215854D02*
X1658874D01*
G01X1658871Y215851D02*
X1658869D01*
G01X1658866Y215854D02*
X1657088D01*
G01X1668476Y217004D02*
X1656611D01*
G01X1657088Y215854D02*
X1655423Y214189D01*
G01X1656611Y217004D02*
X1654946Y215339D01*
G01X1655423Y214189D02*
X1651411D01*
G01X1654946Y215339D02*
X1651888D01*
G01X1657139Y210352D02*
X1658222Y209269D01*
G01X1657616Y211502D02*
X1658699Y210419D01*
G01X1658222Y209269D02*
X1666650D01*
G01X1658699Y210419D02*
X1667127D01*
G01X1666650Y209269D02*
X1670328Y205591D01*
G01X1667127Y210419D02*
X1670805Y206741D01*
G01X1670328Y205591D02*
X1673377D01*
G01X1670805Y206741D02*
X1672900D01*
G01X1673377Y205591D02*
X1676927Y209141D01*
G01X1672900Y206741D02*
X1676450Y210291D01*
G01X1676927Y209141D02*
X1678139D01*
G01X1676450Y210291D02*
X1678616D01*
G01X1678139Y209141D02*
X1684380Y202900D01*
G01X1678616Y210291D02*
X1684857Y204050D01*
G01X1684380Y202900D02*
X1718034D01*
G01X1684857Y204050D02*
X1718511D01*
G01X1684380Y202900D02*
X1718034D01*
G01X1653476Y201536D02*
X1658551D01*
G01X1653953Y202686D02*
X1658074D01*
G01X1658551Y201536D02*
X1660603Y203588D01*
G01X1658074Y202686D02*
X1660126Y204738D01*
G01X1660603Y203588D02*
X1665257D01*
G01X1660126Y204738D02*
X1665734D01*
G01X1665257Y203588D02*
X1670250Y198595D01*
G01X1665734Y204738D02*
X1671400Y199072D01*
G01X1670250Y198595D02*
Y195250D01*
G01X1671400Y199072D02*
Y195727D01*
G01X1670250Y195250D02*
X1672791Y192709D01*
G01X1671400Y195727D02*
X1673268Y193859D01*
G01X1672791Y192709D02*
X1683184D01*
G01X1673268Y193859D02*
X1682707D01*
G01X1683184Y192709D02*
X1684775Y194300D01*
G01X1682707Y193859D02*
X1683625Y194777D01*
G01X1684775Y194300D02*
Y196449D01*
G01X1683625Y194777D02*
Y196926D01*
G01X1684775Y196449D02*
X1685693Y197367D01*
G01X1683625Y196926D02*
X1685216Y198517D01*
G01X1685693Y197367D02*
X1702133D01*
G01X1685216Y198517D02*
X1686246D01*
G01X1685693Y197367D02*
X1702133D01*
G01X1686247Y198518D02*
X1687199D01*
G01X1685693Y197367D02*
X1702133D01*
G01X1687200Y198517D02*
X1702610D01*
G01X1702133Y197367D02*
X1710371Y189129D01*
G01X1702610Y198517D02*
X1710848Y190279D01*
G01X1710371Y189129D02*
X1711453D01*
G01X1710848Y190279D02*
X1711930D01*
G01X1711453Y189129D02*
X1715249Y185333D01*
G01X1711930Y190279D02*
X1715726Y186483D01*
G01X1719454Y206692D02*
X1686604D01*
G01X1718977Y205542D02*
X1686127D01*
G01X1686604Y206692D02*
X1680347Y212949D01*
G01X1686127Y205542D02*
X1679870Y211799D01*
G01X1680347Y212949D02*
X1672531D01*
G01X1679870Y211799D02*
X1672054D01*
G01X1672531Y212949D02*
X1668476Y217004D01*
G01X1672054Y211799D02*
X1667999Y215854D01*
G01X1668476Y217004D02*
X1656611D01*
G01X1667999Y215854D02*
X1658874D01*
G01X1668476Y217004D02*
X1656611D01*
G01X1658871Y215851D02*
X1658869D01*
G01X1668476Y217004D02*
X1656611D01*
G01X1658866Y215854D02*
X1657088D01*
G01X1656611Y217004D02*
X1654946Y215339D01*
G01X1657088Y215854D02*
X1655423Y214189D01*
G01X1654946Y215339D02*
X1651888D01*
G01X1655423Y214189D02*
X1651411D01*
G01X1657616Y211502D02*
X1658699Y210419D01*
G01X1657139Y210352D02*
X1658222Y209269D01*
G01X1658699Y210419D02*
X1667127D01*
G01X1658222Y209269D02*
X1666650D01*
G01X1667127Y210419D02*
X1670805Y206741D01*
G01X1666650Y209269D02*
X1670328Y205591D01*
G01X1670805Y206741D02*
X1672900D01*
G01X1670328Y205591D02*
X1673377D01*
G01X1672900Y206741D02*
X1676450Y210291D01*
G01X1673377Y205591D02*
X1676927Y209141D01*
G01X1676450Y210291D02*
X1678616D01*
G01X1676927Y209141D02*
X1678139D01*
G01X1678616Y210291D02*
X1684857Y204050D01*
G01X1678139Y209141D02*
X1684380Y202900D01*
G01X1684857Y204050D02*
X1718511D01*
G01X1684380Y202900D02*
X1718034D01*
G01X1653953Y202686D02*
X1658074D01*
G01X1653476Y201536D02*
X1658551D01*
G01X1658074Y202686D02*
X1660126Y204738D01*
G01X1658551Y201536D02*
X1660603Y203588D01*
G01X1660126Y204738D02*
X1665734D01*
G01X1660603Y203588D02*
X1665257D01*
G01X1665734Y204738D02*
X1671400Y199072D01*
G01X1665257Y203588D02*
X1670250Y198595D01*
G01X1671400Y199072D02*
Y195727D01*
G01X1670250Y198595D02*
Y195250D01*
G01X1671400Y195727D02*
X1673268Y193859D01*
G01X1670250Y195250D02*
X1672791Y192709D01*
G01X1673268Y193859D02*
X1682707D01*
G01X1672791Y192709D02*
X1683184D01*
G01X1682707Y193859D02*
X1683625Y194777D01*
G01X1683184Y192709D02*
X1684775Y194300D01*
G01X1683625Y194777D02*
Y196926D01*
G01X1684775Y194300D02*
Y196449D01*
G01X1683625Y196926D02*
X1685216Y198517D01*
G01X1684775Y196449D02*
X1685693Y197367D01*
G01X1685216Y198517D02*
X1686246D01*
G01X1686247Y198518D02*
X1687199D01*
G01X1687200Y198517D02*
X1702610D01*
G01X1685693Y197367D02*
X1702133D01*
G01X1702610Y198517D02*
X1710848Y190279D01*
G01X1702133Y197367D02*
X1710371Y189129D01*
G01X1710848Y190279D02*
X1711930D01*
G01X1710371Y189129D02*
X1711453D01*
G01X1711930Y190279D02*
X1715726Y186483D01*
G01X1711453Y189129D02*
X1715249Y185333D01*
G01X1650852Y207697D02*
X1654424Y204125D01*
G01X1651330Y208846D02*
X1654901Y205275D01*
G01X1654424Y204125D02*
X1657487D01*
G01X1654901Y205275D02*
X1657010D01*
G01X1657487Y204125D02*
X1659452Y206090D01*
G01X1657010Y205275D02*
X1658975Y207240D01*
G01X1659452Y206090D02*
X1666292D01*
G01X1658975Y207240D02*
X1666769D01*
G01X1666292Y206090D02*
X1669331Y203051D01*
G01X1666769Y207240D02*
X1669808Y204201D01*
G01X1669331Y203051D02*
X1678231D01*
G01X1669808Y204201D02*
X1678708D01*
G01X1678231Y203051D02*
X1680882Y200400D01*
G01X1678708Y204201D02*
X1681359Y201550D01*
G01X1680882Y200400D02*
X1716997D01*
G01X1681359Y201550D02*
X1717474D01*
G01X1713825Y169675D02*
X1693175D01*
G01X1713348Y168525D02*
X1693652D01*
G01X1693175Y169675D02*
X1690100Y166600D01*
G01X1693652Y168525D02*
X1690577Y165450D01*
G01X1690100Y166600D02*
X1687760D01*
G01X1690577Y165450D02*
X1687283D01*
G01X1687760Y166600D02*
X1685080Y169280D01*
G01X1687283Y165450D02*
X1683930Y168803D01*
G01X1685080Y169280D02*
Y171229D01*
G01X1683930Y168803D02*
Y170752D01*
G01X1685080Y171229D02*
X1680246Y176063D01*
G01X1683930Y170752D02*
X1679769Y174913D01*
G01X1680246Y176063D02*
X1678088D01*
G01X1679769Y174913D02*
X1677611D01*
G01X1678088Y176063D02*
X1675187Y178964D01*
G01X1677611Y174913D02*
X1674710Y177814D01*
G01X1675187Y178964D02*
X1668880D01*
G01X1668879Y178965D02*
X1667835D01*
G01X1674710Y177814D02*
X1668403D01*
G01X1668879Y178965D02*
X1667835D01*
G01X1668402Y177815D02*
X1667358D01*
G01X1668879Y178965D02*
X1667835D01*
G01D02*
X1665300Y181500D01*
G01X1667358Y177815D02*
X1664150Y181023D01*
G01X1665300Y181500D02*
Y182300D01*
G01X1664150Y181023D02*
Y181823D01*
G01X1665300Y182300D02*
X1660315Y187285D01*
G01X1664150Y181823D02*
X1659838Y186135D01*
G01X1660315Y187285D02*
X1654813D01*
G01X1659838Y186135D02*
X1654336D01*
G01X1654813Y187285D02*
X1651618Y190480D01*
G01X1654336Y186135D02*
X1651141Y189330D01*
G01X1714788Y171025D02*
X1687215D01*
G01X1715265Y172175D02*
X1687692D01*
G01X1687215Y171025D02*
X1680638Y177602D01*
G01X1687692Y172175D02*
X1681115Y178752D01*
G01X1680638Y177602D02*
X1678549D01*
G01X1681115Y178752D02*
X1679026D01*
G01X1678549Y177602D02*
X1676103Y180048D01*
G01X1679026Y178752D02*
X1676580Y181198D01*
G01X1676103Y180048D02*
X1670124D01*
G01X1676580Y181198D02*
X1670601D01*
G01X1670124Y180048D02*
X1668800Y181372D01*
G01X1670601Y181198D02*
X1669950Y181849D01*
G01X1668800Y181372D02*
Y183100D01*
G01X1669950Y181849D02*
Y183577D01*
G01X1668800Y183100D02*
X1667700Y184200D01*
G01X1669950Y183577D02*
X1668177Y185350D01*
G01X1667700Y184200D02*
X1666300D01*
G01X1668177Y185350D02*
X1666777D01*
G01X1666300Y184200D02*
X1661854Y188646D01*
G01X1666777Y185350D02*
X1662331Y189796D01*
G01X1661854Y188646D02*
X1655577D01*
G01X1662331Y189796D02*
X1656054D01*
G01X1655577Y188646D02*
X1652393Y191830D01*
G01X1656054Y189796D02*
X1652870Y192980D01*
G01X1656958Y192596D02*
X1663604D01*
G01X1656481Y191446D02*
X1663127D01*
G01X1663604Y192596D02*
X1668600Y187600D01*
G01X1663127Y191446D02*
X1668123Y186450D01*
G01X1668600Y187600D02*
X1675900D01*
G01X1668123Y186450D02*
X1675423D01*
G01X1675900Y187600D02*
X1678500Y185000D01*
G01X1675423Y186450D02*
X1677350Y184523D01*
G01X1678500Y185000D02*
Y182824D01*
G01X1677350Y184523D02*
Y182347D01*
G01X1678500Y182824D02*
X1679781Y181543D01*
G01X1677350Y182347D02*
X1679304Y180393D01*
G01X1679781Y181543D02*
X1682421D01*
G01X1679304Y180393D02*
X1681944D01*
G01X1682421Y181543D02*
X1686314Y177650D01*
G01X1681944Y180393D02*
X1685837Y176500D01*
G01X1686314Y177650D02*
X1701952D01*
G01X1685837Y176500D02*
X1702429D01*
G01X1701952Y177650D02*
X1703821Y179519D01*
G01X1702429Y176500D02*
X1704298Y178369D01*
G01X1703821Y179519D02*
X1715169D01*
G01X1704298Y178369D02*
X1714692D01*
G01X1703573Y181181D02*
X1714381D01*
G01X1713904Y182331D02*
X1703096D01*
G01X1701492Y179100D02*
X1703573Y181181D01*
G01X1703096Y182331D02*
X1701015Y180250D01*
G01X1689473Y179100D02*
X1701492D01*
G01X1701015Y180250D02*
X1689950D01*
G01X1688350Y180223D02*
X1689473Y179100D01*
G01X1689950Y180250D02*
X1689500Y180700D01*
G01X1688350Y181524D02*
Y180223D01*
G01X1689500Y180700D02*
Y182001D01*
G01X1680413Y189461D02*
X1681368Y188506D01*
G01X1683241Y186633D02*
X1688350Y181524D01*
G01X1689500Y182001D02*
X1680890Y190611D01*
G01X1679823Y189461D02*
X1680413D01*
G01X1680890Y190611D02*
X1679346D01*
G01X1669013Y189460D02*
X1679822D01*
G01X1679345Y190610D02*
X1669490D01*
G01X1666846Y191627D02*
X1669013Y189460D01*
G01X1669490Y190610D02*
X1667996Y192104D01*
G01X1666846Y196434D02*
Y191627D01*
G01X1667996Y192104D02*
Y196911D01*
G01X1665422Y197858D02*
X1666846Y196434D01*
G01X1667996Y196911D02*
X1665899Y199008D01*
G01X1663364Y197858D02*
X1665422D01*
G01X1665899Y199008D02*
X1662887D01*
G01X1662610Y197104D02*
X1663364Y197858D01*
G01X1662887Y199008D02*
X1662133Y198254D01*
G01X1659926Y197104D02*
X1662610D01*
G01D02*
X1663364Y197858D01*
G01X1662133Y198254D02*
X1660403D01*
G01X1658788Y198242D02*
X1659926Y197104D01*
G01X1660403Y198254D02*
X1659265Y199392D01*
G01X1653233Y198242D02*
X1658788D01*
G01X1659265Y199392D02*
X1653710D01*
G01X1651330Y208846D02*
X1654901Y205275D01*
G01X1650852Y207697D02*
X1654424Y204125D01*
G01X1654901Y205275D02*
X1657010D01*
G01X1654424Y204125D02*
X1657487D01*
G01X1657010Y205275D02*
X1658975Y207240D01*
G01X1657487Y204125D02*
X1659452Y206090D01*
G01X1658975Y207240D02*
X1666769D01*
G01X1659452Y206090D02*
X1666292D01*
G01X1666769Y207240D02*
X1669808Y204201D01*
G01X1666292Y206090D02*
X1669331Y203051D01*
G01X1669808Y204201D02*
X1678708D01*
G01X1669331Y203051D02*
X1678231D01*
G01X1678708Y204201D02*
X1681359Y201550D01*
G01X1678231Y203051D02*
X1680882Y200400D01*
G01X1681359Y201550D02*
X1717474D01*
G01X1680882Y200400D02*
X1716997D01*
G01X1713348Y168525D02*
X1693652D01*
G01X1713825Y169675D02*
X1693175D01*
G01X1693652Y168525D02*
X1690577Y165450D01*
G01X1693175Y169675D02*
X1690100Y166600D01*
G01X1690577Y165450D02*
X1687283D01*
G01X1690100Y166600D02*
X1687760D01*
G01X1687283Y165450D02*
X1683930Y168803D01*
G01X1687760Y166600D02*
X1685080Y169280D01*
G01X1683930Y168803D02*
Y170752D01*
G01X1685080Y169280D02*
Y171229D01*
G01X1683930Y170752D02*
X1679769Y174913D01*
G01X1685080Y171229D02*
X1680246Y176063D01*
G01X1679769Y174913D02*
X1677611D01*
G01X1680246Y176063D02*
X1678088D01*
G01X1677611Y174913D02*
X1674710Y177814D01*
G01X1678088Y176063D02*
X1675187Y178964D01*
G01X1674710Y177814D02*
X1668403D01*
G01X1675187Y178964D02*
X1668880D01*
G01X1674710Y177814D02*
X1668403D01*
G01X1668402Y177815D02*
X1667358D01*
G01D02*
X1664150Y181023D01*
G01X1668879Y178965D02*
X1667835D01*
G01X1667358Y177815D02*
X1664150Y181023D01*
G01X1667835Y178965D02*
X1665300Y181500D01*
G01X1664150Y181023D02*
Y181823D01*
G01X1665300Y181500D02*
Y182300D01*
G01X1664150Y181823D02*
X1659838Y186135D01*
G01X1665300Y182300D02*
X1660315Y187285D01*
G01X1659838Y186135D02*
X1654336D01*
G01X1660315Y187285D02*
X1654813D01*
G01X1654336Y186135D02*
X1651141Y189330D01*
G01X1654813Y187285D02*
X1651618Y190480D01*
G01X1715265Y172175D02*
X1687692D01*
G01X1714788Y171025D02*
X1687215D01*
G01X1687692Y172175D02*
X1681115Y178752D01*
G01X1687215Y171025D02*
X1680638Y177602D01*
G01X1681115Y178752D02*
X1679026D01*
G01X1680638Y177602D02*
X1678549D01*
G01X1679026Y178752D02*
X1676580Y181198D01*
G01X1678549Y177602D02*
X1676103Y180048D01*
G01X1676580Y181198D02*
X1670601D01*
G01X1676103Y180048D02*
X1670124D01*
G01X1670601Y181198D02*
X1669950Y181849D01*
G01X1670124Y180048D02*
X1668800Y181372D01*
G01X1669950Y181849D02*
Y183577D01*
G01X1668800Y181372D02*
Y183100D01*
G01X1669950Y183577D02*
X1668177Y185350D01*
G01X1668800Y183100D02*
X1667700Y184200D01*
G01X1668177Y185350D02*
X1666777D01*
G01X1667700Y184200D02*
X1666300D01*
G01X1666777Y185350D02*
X1662331Y189796D01*
G01X1666300Y184200D02*
X1661854Y188646D01*
G01X1662331Y189796D02*
X1656054D01*
G01X1661854Y188646D02*
X1655577D01*
G01X1656054Y189796D02*
X1652870Y192980D01*
G01X1655577Y188646D02*
X1652393Y191830D01*
G01X1656481Y191446D02*
X1663127D01*
G01X1656958Y192596D02*
X1663604D01*
G01X1663127Y191446D02*
X1668123Y186450D01*
G01X1663604Y192596D02*
X1668600Y187600D01*
G01X1668123Y186450D02*
X1675423D01*
G01X1668600Y187600D02*
X1675900D01*
G01X1675423Y186450D02*
X1677350Y184523D01*
G01X1675900Y187600D02*
X1678500Y185000D01*
G01X1677350Y184523D02*
Y182347D01*
G01X1678500Y185000D02*
Y182824D01*
G01X1677350Y182347D02*
X1679304Y180393D01*
G01X1678500Y182824D02*
X1679781Y181543D01*
G01X1679304Y180393D02*
X1681944D01*
G01X1679781Y181543D02*
X1682421D01*
G01X1681944Y180393D02*
X1685837Y176500D01*
G01X1682421Y181543D02*
X1686314Y177650D01*
G01X1685837Y176500D02*
X1702429D01*
G01X1686314Y177650D02*
X1701952D01*
G01X1702429Y176500D02*
X1704298Y178369D01*
G01X1701952Y177650D02*
X1703821Y179519D01*
G01X1704298Y178369D02*
X1714692D01*
G01X1703821Y179519D02*
X1715169D01*
G01X1659265Y199392D02*
X1653710D01*
G01X1653233Y198242D02*
X1658788D01*
G01X1660403Y198254D02*
X1659265Y199392D01*
G01X1658788Y198242D02*
X1659926Y197104D01*
G01X1662133Y198254D02*
X1660403D01*
G01X1659926Y197104D02*
X1662610D01*
G01X1662887Y199008D02*
X1662133Y198254D01*
G01D02*
X1660403D01*
G01X1662610Y197104D02*
X1663364Y197858D01*
G01X1665899Y199008D02*
X1662887D01*
G01X1663364Y197858D02*
X1665422D01*
G01X1667996Y196911D02*
X1665899Y199008D01*
G01X1665422Y197858D02*
X1666846Y196434D01*
G01X1667996Y192104D02*
Y196911D01*
G01X1666846Y196434D02*
Y191627D01*
G01X1669490Y190610D02*
X1667996Y192104D01*
G01X1666846Y191627D02*
X1669013Y189460D01*
G01X1679345Y190610D02*
X1669490D01*
G01X1669013Y189460D02*
X1679822D01*
G01X1680890Y190611D02*
X1679346D01*
G01X1679823Y189461D02*
X1680413D01*
G01X1689500Y182001D02*
X1680890Y190611D01*
G01X1680413Y189461D02*
X1681368Y188506D01*
G01X1689500Y182001D02*
X1680890Y190611D01*
G01X1683241Y186633D02*
X1688350Y181524D01*
G01X1689500Y180700D02*
Y182001D01*
G01X1688350Y181524D02*
Y180223D01*
G01X1689950Y180250D02*
X1689500Y180700D01*
G01X1688350Y180223D02*
X1689473Y179100D01*
G01X1701015Y180250D02*
X1689950D01*
G01X1689473Y179100D02*
X1701492D01*
G01X1703096Y182331D02*
X1701015Y180250D01*
G01X1701492Y179100D02*
X1703573Y181181D01*
G01X1713904Y182331D02*
X1703096D01*
G01X1703573Y181181D02*
X1714381D01*
G01X1718248Y223450D02*
X1711203Y216405D01*
G01X1717771Y224600D02*
X1710726Y217555D01*
G01X1711203Y216405D02*
X1694551D01*
G01X1710726Y217555D02*
X1695028D01*
G01X1694551Y216405D02*
X1688364Y222592D01*
G01X1695028Y217555D02*
X1688841Y223742D01*
G01X1693514Y213905D02*
X1687417Y220002D01*
G01X1687894Y221152D02*
X1693991Y215055D01*
G01X1712240Y213905D02*
X1693514D01*
G01X1693991Y215055D02*
X1711763D01*
G01X1719285Y220950D02*
X1712240Y213905D01*
G01X1711763Y215055D02*
X1718808Y222100D01*
G01X1713787Y211405D02*
X1692477D01*
G01X1713310Y212555D02*
X1692954D01*
G01X1692477Y211405D02*
X1686428Y217454D01*
G01X1692954Y212555D02*
X1686905Y218604D01*
G01X1686428Y217454D02*
X1674322D01*
G01D02*
X1670168Y221608D01*
G01X1715616Y208865D02*
X1687361D01*
G01X1715139Y210015D02*
X1687838D01*
G01X1687361Y208865D02*
X1681317Y214909D01*
G01X1687838Y210015D02*
X1681794Y216059D01*
G01X1681317Y214909D02*
X1673330D01*
G01X1681794Y216059D02*
X1673807D01*
G01X1673330Y214909D02*
X1669131Y219108D01*
G01X1673807Y216059D02*
X1669608Y220258D01*
G01X1717771Y224600D02*
X1710726Y217555D01*
G01X1718248Y223450D02*
X1711203Y216405D01*
G01X1710726Y217555D02*
X1695028D01*
G01X1711203Y216405D02*
X1694551D01*
G01X1695028Y217555D02*
X1688841Y223742D01*
G01X1694551Y216405D02*
X1688364Y222592D01*
G01X1711763Y215055D02*
X1718808Y222100D01*
G01X1719285Y220950D02*
X1712240Y213905D01*
G01X1693991Y215055D02*
X1711763D01*
G01X1712240Y213905D02*
X1693514D01*
G01X1687894Y221152D02*
X1693991Y215055D01*
G01X1693514Y213905D02*
X1687417Y220002D01*
G01X1713310Y212555D02*
X1692954D01*
G01X1713787Y211405D02*
X1692477D01*
G01X1692954Y212555D02*
X1686905Y218604D01*
G01X1692477Y211405D02*
X1686428Y217454D01*
G01D02*
X1674322D01*
G01D02*
X1670168Y221608D01*
G01X1715139Y210015D02*
X1687838D01*
G01X1715616Y208865D02*
X1687361D01*
G01X1687838Y210015D02*
X1681794Y216059D01*
G01X1687361Y208865D02*
X1681317Y214909D01*
G01X1681794Y216059D02*
X1673807D01*
G01X1681317Y214909D02*
X1673330D01*
G01X1673807Y216059D02*
X1669608Y220258D01*
G01X1673330Y214909D02*
X1669131Y219108D01*
G01X1782561Y239939D02*
X1710143D01*
G01X1793138Y241089D02*
X1710620D01*
G01X1710143Y239939D02*
X1703107Y246975D01*
G01X1710620Y241089D02*
X1703584Y248125D01*
G01X1703107Y246975D02*
X1695937D01*
G01X1703584Y248125D02*
X1695460D01*
G01X1695937Y246975D02*
X1690856Y241894D01*
G01X1695460Y248125D02*
X1689706Y242371D01*
G01X1690856Y241894D02*
Y232400D01*
G01X1689706Y242371D02*
Y232877D01*
G01X1690856Y232400D02*
X1688772Y230316D01*
G01X1689706Y232877D02*
X1688295Y231466D01*
G01X1688772Y230316D02*
X1679221D01*
G01X1688295Y231466D02*
X1679698D01*
G01X1679221Y230316D02*
X1675429Y234108D01*
G01X1679698Y231466D02*
X1675906Y235258D01*
G01X1675429Y234108D02*
X1658979D01*
G01X1675906Y235258D02*
X1659456D01*
G01X1658979Y234108D02*
X1658282Y234805D01*
G01X1659456Y235258D02*
X1658759Y235955D01*
G01X1658282Y234805D02*
X1654229D01*
G01X1658759Y235955D02*
X1654706D01*
G01X1713083Y226054D02*
X1712164D01*
G01D02*
X1711209Y225099D01*
G01X1710255Y223226D02*
X1709336D01*
G01D02*
X1708320Y222210D01*
G01X1714515Y230032D02*
X1707843Y223360D01*
G01X1708320Y222210D02*
X1695820D01*
G01X1707843Y223360D02*
X1696297D01*
G01X1695820Y222210D02*
X1690303Y227727D01*
G01X1696297Y223360D02*
X1690780Y228877D01*
G01X1690303Y227727D02*
X1678273D01*
G01X1690780Y228877D02*
X1678750D01*
G01X1678273Y227727D02*
X1674392Y231608D01*
G01X1678750Y228877D02*
X1674869Y232758D01*
G01X1674392Y231608D02*
X1657942D01*
G01X1674869Y232758D02*
X1658419D01*
G01X1657942Y231608D02*
X1657245Y232305D01*
G01X1658419Y232758D02*
X1657722Y233455D01*
G01X1657245Y232305D02*
X1653192D01*
G01X1657722Y233455D02*
X1653669D01*
G01X1716627Y225950D02*
X1710278Y219601D01*
G01X1716150Y227100D02*
X1709801Y220751D01*
G01X1710278Y219601D02*
X1704389D01*
G01X1701739D02*
X1700389D01*
G01X1697739D02*
X1694892D01*
G01X1709801Y220751D02*
X1695369D01*
G01X1694892Y219601D02*
X1689266Y225227D01*
G01X1695369Y220751D02*
X1689743Y226377D01*
G01X1689266Y225227D02*
X1677160D01*
G01X1689743Y226377D02*
X1677637D01*
G01X1677160Y225227D02*
X1673279Y229108D01*
G01X1677637Y226377D02*
X1673756Y230258D01*
G01X1673279Y229108D02*
X1656905D01*
G01X1673756Y230258D02*
X1657382D01*
G01X1656905Y229108D02*
X1656208Y229805D01*
G01X1657382Y230258D02*
X1656685Y230955D01*
G01X1688364Y222592D02*
X1676258D01*
G01X1688841Y223742D02*
X1676735D01*
G01X1676258Y222592D02*
X1672242Y226608D01*
G01X1676735Y223742D02*
X1672719Y227758D01*
G01X1672242Y226608D02*
X1655868D01*
G01X1672719Y227758D02*
X1656345D01*
G01X1655868Y226608D02*
X1655171Y227305D01*
G01X1656345Y227758D02*
X1655648Y228455D01*
G01X1654831Y224108D02*
X1654134Y224805D01*
G01X1654611Y225955D02*
X1655308Y225258D01*
G01X1671205Y224108D02*
X1654831D01*
G01X1655308Y225258D02*
X1671682D01*
G01X1675311Y220002D02*
X1671205Y224108D01*
G01X1671682Y225258D02*
X1675788Y221152D01*
G01X1687417Y220002D02*
X1675311D01*
G01X1675788Y221152D02*
X1687894D01*
G01X1686905Y218604D02*
X1674799D01*
G01D02*
X1670645Y222758D01*
G01X1670168Y221608D02*
X1653794D01*
G01X1670645Y222758D02*
X1654271D01*
G01X1653794Y221608D02*
X1653097Y222305D01*
G01X1654271Y222758D02*
X1653574Y223455D01*
G01X1669131Y219108D02*
X1652757D01*
G01X1669608Y220258D02*
X1653234D01*
G01X1652757Y219108D02*
X1652060Y219805D01*
G01X1653234Y220258D02*
X1652537Y220955D01*
G01X1655743Y238455D02*
X1659796D01*
G01X1655266Y237305D02*
X1659319D01*
G01X1659796Y238455D02*
X1660493Y237758D01*
G01X1659319Y237305D02*
X1660016Y236608D01*
G01X1660493Y237758D02*
X1676960D01*
G01X1660016Y236608D02*
X1676483D01*
G01X1676960Y237758D02*
X1677966Y236752D01*
G01X1676483Y236608D02*
X1677489Y235602D01*
G01X1677966Y236752D02*
X1685115D01*
G01X1677489Y235602D02*
X1685592D01*
G01X1685115Y236752D02*
X1687206Y238843D01*
G01X1685592Y235602D02*
X1688356Y238366D01*
G01X1687206Y238843D02*
Y243408D01*
G01X1688356Y238366D02*
Y242931D01*
G01X1687206Y243408D02*
X1694423Y250625D01*
G01X1688356Y242931D02*
X1694900Y249475D01*
G01X1694423Y250625D02*
X1704621D01*
G01X1694900Y249475D02*
X1704144D01*
G01X1704621Y250625D02*
X1711657Y243589D01*
G01X1704144Y249475D02*
X1711180Y242439D01*
G01X1711657Y243589D02*
X1797685D01*
G01X1711180Y242439D02*
X1797208D01*
G01X1793138Y241089D02*
X1710620D01*
G01X1793138D02*
X1710620D01*
G01X1793138D02*
X1710620D01*
G01X1782561Y239939D02*
X1710143D01*
G01X1710620Y241089D02*
X1703584Y248125D01*
G01X1710143Y239939D02*
X1703107Y246975D01*
G01X1703584Y248125D02*
X1695460D01*
G01X1703107Y246975D02*
X1695937D01*
G01X1695460Y248125D02*
X1689706Y242371D01*
G01X1695937Y246975D02*
X1690856Y241894D01*
G01X1689706Y242371D02*
Y232877D01*
G01X1690856Y241894D02*
Y232400D01*
G01X1689706Y232877D02*
X1688295Y231466D01*
G01X1690856Y232400D02*
X1688772Y230316D01*
G01X1688295Y231466D02*
X1679698D01*
G01X1688772Y230316D02*
X1679221D01*
G01X1679698Y231466D02*
X1675906Y235258D01*
G01X1679221Y230316D02*
X1675429Y234108D01*
G01X1675906Y235258D02*
X1659456D01*
G01X1675429Y234108D02*
X1658979D01*
G01X1659456Y235258D02*
X1658759Y235955D01*
G01X1658979Y234108D02*
X1658282Y234805D01*
G01X1658759Y235955D02*
X1654706D01*
G01X1658282Y234805D02*
X1654229D01*
G01X1714515Y230032D02*
X1707843Y223360D01*
G01X1714515Y230032D02*
X1707843Y223360D01*
G01X1713083Y226054D02*
X1712164D01*
G01X1714515Y230032D02*
X1707843Y223360D01*
G01X1712164Y226054D02*
X1711209Y225099D01*
G01X1714515Y230032D02*
X1707843Y223360D01*
G01X1710255Y223226D02*
X1709336D01*
G01X1714515Y230032D02*
X1707843Y223360D01*
G01X1709336Y223226D02*
X1708320Y222210D01*
G01X1707843Y223360D02*
X1696297D01*
G01X1708320Y222210D02*
X1695820D01*
G01X1696297Y223360D02*
X1690780Y228877D01*
G01X1695820Y222210D02*
X1690303Y227727D01*
G01X1690780Y228877D02*
X1678750D01*
G01X1690303Y227727D02*
X1678273D01*
G01X1678750Y228877D02*
X1674869Y232758D01*
G01X1678273Y227727D02*
X1674392Y231608D01*
G01X1674869Y232758D02*
X1658419D01*
G01X1674392Y231608D02*
X1657942D01*
G01X1658419Y232758D02*
X1657722Y233455D01*
G01X1657942Y231608D02*
X1657245Y232305D01*
G01X1657722Y233455D02*
X1653669D01*
G01X1657245Y232305D02*
X1653192D01*
G01X1716150Y227100D02*
X1709801Y220751D01*
G01X1716627Y225950D02*
X1710278Y219601D01*
G01X1709801Y220751D02*
X1695369D01*
G01X1710278Y219601D02*
X1704389D01*
G01X1709801Y220751D02*
X1695369D01*
G01X1701739Y219601D02*
X1700389D01*
G01X1709801Y220751D02*
X1695369D01*
G01X1697739Y219601D02*
X1694892D01*
G01X1695369Y220751D02*
X1689743Y226377D01*
G01X1694892Y219601D02*
X1689266Y225227D01*
G01X1689743Y226377D02*
X1677637D01*
G01X1689266Y225227D02*
X1677160D01*
G01X1677637Y226377D02*
X1673756Y230258D01*
G01X1677160Y225227D02*
X1673279Y229108D01*
G01X1673756Y230258D02*
X1657382D01*
G01X1673279Y229108D02*
X1656905D01*
G01X1657382Y230258D02*
X1656685Y230955D01*
G01X1656905Y229108D02*
X1656208Y229805D01*
G01X1688841Y223742D02*
X1676735D01*
G01X1688364Y222592D02*
X1676258D01*
G01X1676735Y223742D02*
X1672719Y227758D01*
G01X1676258Y222592D02*
X1672242Y226608D01*
G01X1672719Y227758D02*
X1656345D01*
G01X1672242Y226608D02*
X1655868D01*
G01X1656345Y227758D02*
X1655648Y228455D01*
G01X1655868Y226608D02*
X1655171Y227305D01*
G01X1675788Y221152D02*
X1687894D01*
G01X1687417Y220002D02*
X1675311D01*
G01X1671682Y225258D02*
X1675788Y221152D01*
G01X1675311Y220002D02*
X1671205Y224108D01*
G01X1655308Y225258D02*
X1671682D01*
G01X1671205Y224108D02*
X1654831D01*
G01X1654611Y225955D02*
X1655308Y225258D01*
G01X1654831Y224108D02*
X1654134Y224805D01*
G01X1686905Y218604D02*
X1674799D01*
G01D02*
X1670645Y222758D01*
G01D02*
X1654271D01*
G01X1670168Y221608D02*
X1653794D01*
G01X1654271Y222758D02*
X1653574Y223455D01*
G01X1653794Y221608D02*
X1653097Y222305D01*
G01X1669608Y220258D02*
X1653234D01*
G01X1669131Y219108D02*
X1652757D01*
G01X1653234Y220258D02*
X1652537Y220955D01*
G01X1652757Y219108D02*
X1652060Y219805D01*
G01X1655266Y237305D02*
X1659319D01*
G01X1655743Y238455D02*
X1659796D01*
G01X1659319Y237305D02*
X1660016Y236608D01*
G01X1659796Y238455D02*
X1660493Y237758D01*
G01X1660016Y236608D02*
X1676483D01*
G01X1660493Y237758D02*
X1676960D01*
G01X1676483Y236608D02*
X1677489Y235602D01*
G01X1676960Y237758D02*
X1677966Y236752D01*
G01X1677489Y235602D02*
X1685592D01*
G01X1677966Y236752D02*
X1685115D01*
G01X1685592Y235602D02*
X1688356Y238366D01*
G01X1685115Y236752D02*
X1687206Y238843D01*
G01X1688356Y238366D02*
Y242931D01*
G01X1687206Y238843D02*
Y243408D01*
G01X1688356Y242931D02*
X1694900Y249475D01*
G01X1687206Y243408D02*
X1694423Y250625D01*
G01X1694900Y249475D02*
X1704144D01*
G01X1694423Y250625D02*
X1704621D01*
G01X1704144Y249475D02*
X1711180Y242439D01*
G01X1704621Y250625D02*
X1711657Y243589D01*
G01X1711180Y242439D02*
X1797208D01*
G01X1711657Y243589D02*
X1797685D01*
G01X1651550Y272850D02*
X1655648D01*
G01X1651073Y271700D02*
X1655498D01*
G01X1651073D02*
X1655498D01*
G01X1651550Y272850D02*
X1655648D01*
G01X1659571Y288298D02*
Y262870D01*
G01X1660721Y288775D02*
Y262393D01*
G01X1659571Y262870D02*
X1659051Y262350D01*
G01D02*
X1658032D01*
G01X1660721Y262393D02*
X1659528Y261200D01*
G01X1659051Y262350D02*
X1658032D01*
G01X1659528Y261200D02*
X1658011D01*
G01X1660721Y288775D02*
Y262393D01*
G01X1659571Y288298D02*
Y262870D01*
G01X1660721Y262393D02*
X1659528Y261200D01*
G01X1659571Y262870D02*
X1659051Y262350D01*
G01X1660721Y262393D02*
X1659528Y261200D01*
G01D02*
X1658011D01*
G01X1659051Y262350D02*
X1658032D01*
G01X1867844Y265168D02*
X1677203D01*
G01X1867367Y264018D02*
X1676726D01*
G01X1677203Y265168D02*
X1669051Y273320D01*
G01X1676726Y264018D02*
X1667901Y272843D01*
G01X1669051Y273320D02*
Y407650D01*
G01X1667901Y272843D02*
Y407173D01*
G01X1867367Y264018D02*
X1676726D01*
G01X1867844Y265168D02*
X1677203D01*
G01X1676726Y264018D02*
X1667901Y272843D01*
G01X1677203Y265168D02*
X1669051Y273320D01*
G01X1667901Y272843D02*
Y407173D01*
G01X1669051Y273320D02*
Y407650D01*
G01X1865571Y262068D02*
X1674872D01*
G01X1865094Y260918D02*
X1674395D01*
G01X1674872Y262068D02*
X1665073Y271867D01*
G01X1674395Y260918D02*
X1663923Y271390D01*
G01X1665073Y271867D02*
Y303127D01*
G01X1663923Y271390D02*
Y302650D01*
G01X1865094Y260918D02*
X1674395D01*
G01X1865571Y262068D02*
X1674872D01*
G01X1674395Y260918D02*
X1663923Y271390D01*
G01X1674872Y262068D02*
X1665073Y271867D01*
G01X1663923Y271390D02*
Y302650D01*
G01X1665073Y271867D02*
Y303127D01*
G01X1657048Y281585D02*
X1653044D01*
G01X1657048Y282735D02*
X1653521D01*
G01X1657048D02*
X1653521D01*
G01X1657048Y281585D02*
X1653044D01*
G01X1654478Y289687D02*
X1658182D01*
G01X1654955Y290837D02*
X1658659D01*
G01X1658182Y289687D02*
X1659571Y288298D01*
G01X1658659Y290837D02*
X1660721Y288775D01*
G01X1654955Y290837D02*
X1658659D01*
G01X1654478Y289687D02*
X1658182D01*
G01X1658659Y290837D02*
X1660721Y288775D01*
G01X1658182Y289687D02*
X1659571Y288298D01*
G01X1665073Y303127D02*
X1661354Y306846D01*
G01X1663923Y302650D02*
X1660204Y306369D01*
G01X1661354Y306846D02*
Y379219D01*
G01X1660204Y306369D02*
Y379696D01*
G01X1663923Y302650D02*
X1660204Y306369D01*
G01X1665073Y303127D02*
X1661354Y306846D01*
G01X1660204Y306369D02*
Y379696D01*
G01X1661354Y306846D02*
Y379219D01*
G01D02*
X1665951Y383816D01*
G01X1660204Y379696D02*
X1664801Y384293D01*
G01X1665951Y383816D02*
Y406364D01*
G01X1664801Y384293D02*
Y405887D01*
G01X1660204Y379696D02*
X1664801Y384293D01*
G01X1661354Y379219D02*
X1665951Y383816D01*
G01X1664801Y384293D02*
Y405887D01*
G01X1665951Y383816D02*
Y406364D01*
G01X1669051Y407650D02*
X1667237Y409464D01*
G01X1667901Y407173D02*
X1666760Y408314D01*
G01X1667237Y409464D02*
X1667236D01*
G01X1667901Y407173D02*
X1666760Y408314D01*
G01X1669051Y407650D02*
X1667237Y409464D01*
G01D02*
X1667236D01*
G01X1714682Y491320D02*
X1709804Y498095D01*
G01X1715425Y492258D02*
X1710816Y498659D01*
G01X1709804Y498095D02*
X1707980Y502494D01*
G01X1710816Y498659D02*
X1708924Y503222D01*
G01X1707980Y502494D02*
X1705949Y504039D01*
G01X1708924Y503222D02*
X1706449Y505104D01*
G01X1705949Y504039D02*
X1702916Y504742D01*
G01X1706449Y505104D02*
X1702931Y505920D01*
G01X1702916Y504742D02*
X1698785Y503892D01*
G01X1702931Y505920D02*
X1698817Y505073D01*
G01X1698785Y503892D02*
X1693100Y505389D01*
G01X1698817Y505073D02*
X1693523Y506468D01*
G01X1693100Y505389D02*
X1687679Y508276D01*
G01X1693523Y506468D02*
X1688457Y509166D01*
G01X1687679Y508276D02*
X1684840Y512224D01*
G01X1688457Y509166D02*
X1685587Y513157D01*
G01X1684840Y512224D02*
X1682096Y513395D01*
G01X1685587Y513157D02*
X1682214Y514596D01*
G01X1682096Y513395D02*
X1675723Y512054D01*
G01X1682214Y514596D02*
X1675769Y513239D01*
G01X1675723Y512054D02*
X1663251Y515703D01*
G01X1675769Y513239D02*
X1663779Y516747D01*
G01X1663251Y515703D02*
X1654613Y522305D01*
G01X1663779Y516747D02*
X1655474Y523096D01*
G01X1661207Y528335D02*
X1667276Y523694D01*
G01X1660346Y527544D02*
X1666748Y522650D01*
G01X1667276Y523694D02*
X1675936Y521161D01*
G01X1666748Y522650D02*
X1675890Y519975D01*
G01X1675936Y521161D02*
X1682892Y522628D01*
G01X1675890Y519975D02*
X1682774Y521427D01*
G01X1682892Y522628D02*
X1695211Y517370D01*
G01X1682774Y521427D02*
X1695088Y516172D01*
G01X1695211Y517370D02*
X1704314Y519194D01*
G01X1695088Y516172D02*
X1704240Y518006D01*
G01X1704314Y519194D02*
X1711574Y516774D01*
G01X1704240Y518006D02*
X1711484Y515591D01*
G01X1711574Y516774D02*
X1720380Y518292D01*
G01X1711484Y515591D02*
X1712814Y515820D01*
G01X1711574Y516774D02*
X1720380Y518292D01*
G01X1714291Y500591D02*
X1711916Y506319D01*
G01D02*
X1708643Y508807D01*
G01X1712860Y507047D02*
X1709143Y509872D01*
G01X1708643Y508807D02*
X1703431Y510015D01*
G01X1709143Y509872D02*
X1703446Y511193D01*
G01X1703431Y510015D02*
X1699012Y509107D01*
G01X1703446Y511193D02*
X1699044Y510288D01*
G01X1699012Y509107D02*
X1694974Y510171D01*
G01X1699044Y510288D02*
X1695397Y511249D01*
G01X1694974Y510171D02*
X1691126Y512220D01*
G01X1695397Y511249D02*
X1691904Y513110D01*
G01X1691126Y512220D02*
X1688151Y516358D01*
G01X1691904Y513110D02*
X1688898Y517291D01*
G01X1688151Y516358D02*
X1682444Y518792D01*
G01X1688898Y517291D02*
X1682562Y519992D01*
G01X1682444Y518792D02*
X1675697Y517374D01*
G01X1682562Y519992D02*
X1675743Y518559D01*
G01X1675697Y517374D02*
X1665592Y520331D01*
G01X1675743Y518559D02*
X1666121Y521375D01*
G01X1665592Y520331D02*
X1658428Y525810D01*
G01X1666121Y521375D02*
X1659289Y526600D01*
G01X1658428Y525810D02*
X1651169Y537197D01*
G01X1715425Y492258D02*
X1710816Y498659D01*
G01X1714682Y491320D02*
X1709804Y498095D01*
G01X1710816Y498659D02*
X1708924Y503222D01*
G01X1709804Y498095D02*
X1707980Y502494D01*
G01X1708924Y503222D02*
X1706449Y505104D01*
G01X1707980Y502494D02*
X1705949Y504039D01*
G01X1706449Y505104D02*
X1702931Y505920D01*
G01X1705949Y504039D02*
X1702916Y504742D01*
G01X1702931Y505920D02*
X1698817Y505073D01*
G01X1702916Y504742D02*
X1698785Y503892D01*
G01X1698817Y505073D02*
X1693523Y506468D01*
G01X1698785Y503892D02*
X1693100Y505389D01*
G01X1693523Y506468D02*
X1688457Y509166D01*
G01X1693100Y505389D02*
X1687679Y508276D01*
G01X1688457Y509166D02*
X1685587Y513157D01*
G01X1687679Y508276D02*
X1684840Y512224D01*
G01X1685587Y513157D02*
X1682214Y514596D01*
G01X1684840Y512224D02*
X1682096Y513395D01*
G01X1682214Y514596D02*
X1675769Y513239D01*
G01X1682096Y513395D02*
X1675723Y512054D01*
G01X1675769Y513239D02*
X1663779Y516747D01*
G01X1675723Y512054D02*
X1663251Y515703D01*
G01X1663779Y516747D02*
X1655474Y523096D01*
G01X1663251Y515703D02*
X1654613Y522305D01*
G01X1660346Y527544D02*
X1666748Y522650D01*
G01X1661207Y528335D02*
X1667276Y523694D01*
G01X1666748Y522650D02*
X1675890Y519975D01*
G01X1667276Y523694D02*
X1675936Y521161D01*
G01X1675890Y519975D02*
X1682774Y521427D01*
G01X1675936Y521161D02*
X1682892Y522628D01*
G01X1682774Y521427D02*
X1695088Y516172D01*
G01X1682892Y522628D02*
X1695211Y517370D01*
G01X1695088Y516172D02*
X1704240Y518006D01*
G01X1695211Y517370D02*
X1704314Y519194D01*
G01X1704240Y518006D02*
X1711484Y515591D01*
G01X1704314Y519194D02*
X1711574Y516774D01*
G01X1711484Y515591D02*
X1712814Y515820D01*
G01X1711574Y516774D02*
X1720380Y518292D01*
G01X1714291Y500591D02*
X1711916Y506319D01*
G01X1712860Y507047D02*
X1709143Y509872D01*
G01X1711916Y506319D02*
X1708643Y508807D01*
G01X1709143Y509872D02*
X1703446Y511193D01*
G01X1708643Y508807D02*
X1703431Y510015D01*
G01X1703446Y511193D02*
X1699044Y510288D01*
G01X1703431Y510015D02*
X1699012Y509107D01*
G01X1699044Y510288D02*
X1695397Y511249D01*
G01X1699012Y509107D02*
X1694974Y510171D01*
G01X1695397Y511249D02*
X1691904Y513110D01*
G01X1694974Y510171D02*
X1691126Y512220D01*
G01X1691904Y513110D02*
X1688898Y517291D01*
G01X1691126Y512220D02*
X1688151Y516358D01*
G01X1688898Y517291D02*
X1682562Y519992D01*
G01X1688151Y516358D02*
X1682444Y518792D01*
G01X1682562Y519992D02*
X1675743Y518559D01*
G01X1682444Y518792D02*
X1675697Y517374D01*
G01X1675743Y518559D02*
X1666121Y521375D01*
G01X1675697Y517374D02*
X1665592Y520331D01*
G01X1666121Y521375D02*
X1659289Y526600D01*
G01X1665592Y520331D02*
X1658428Y525810D01*
G01D02*
X1651169Y537197D01*
G01X1716305Y493433D02*
X1712047Y499345D01*
G01D02*
X1709942Y504421D01*
G01X1713059Y499909D02*
X1710886Y505149D01*
G01X1709942Y504421D02*
X1707165Y506532D01*
G01X1710886Y505149D02*
X1707665Y507597D01*
G01X1707165Y506532D02*
X1703385Y507408D01*
G01X1707665Y507597D02*
X1703400Y508586D01*
G01X1703385Y507408D02*
X1698928Y506491D01*
G01X1703400Y508586D02*
X1698960Y507672D01*
G01X1698928Y506491D02*
X1694233Y507727D01*
G01D02*
X1694167Y507746D01*
G01X1698960Y507672D02*
X1694538Y508836D01*
G01X1698928Y506491D02*
X1694233Y507727D01*
G01X1694538Y508836D02*
X1694486Y508851D01*
G01X1698928Y506491D02*
X1694233Y507727D01*
G01X1694486Y508851D02*
X1694460Y508858D01*
G01X1694037Y507780D02*
X1693918Y507843D01*
G01D02*
X1693919D01*
G01D02*
X1689403Y510248D01*
G01X1694460Y508858D02*
X1690181Y511138D01*
G01X1689403Y510248D02*
X1686496Y514291D01*
G01X1690181Y511138D02*
X1687243Y515224D01*
G01X1686496Y514291D02*
X1682290Y516086D01*
G01X1687243Y515224D02*
X1682408Y517287D01*
G01X1682290Y516086D02*
X1675739Y514706D01*
G01X1682408Y517287D02*
X1675785Y515891D01*
G01X1675739Y514706D02*
X1664422Y518017D01*
G01X1675785Y515892D02*
X1664950Y519061D01*
G01X1664422Y518017D02*
X1656521Y524058D01*
G01X1664950Y519061D02*
X1657382Y524849D01*
G01X1716305Y493433D02*
X1712047Y499345D01*
G01X1713059Y499909D02*
X1710886Y505149D01*
G01X1712047Y499345D02*
X1709942Y504421D01*
G01X1710886Y505149D02*
X1707665Y507597D01*
G01X1709942Y504421D02*
X1707165Y506532D01*
G01X1707665Y507597D02*
X1703400Y508586D01*
G01X1707165Y506532D02*
X1703385Y507408D01*
G01X1703400Y508586D02*
X1698960Y507672D01*
G01X1703385Y507408D02*
X1698928Y506491D01*
G01X1698960Y507672D02*
X1694538Y508836D01*
G01D02*
X1694486Y508851D01*
G01D02*
X1694460Y508858D01*
G01X1698928Y506491D02*
X1694233Y507727D01*
G01X1698960Y507672D02*
X1694538Y508836D01*
G01X1694233Y507727D02*
X1694167Y507746D01*
G01X1694460Y508858D02*
X1690181Y511138D01*
G01X1694037Y507780D02*
X1693918Y507843D01*
G01X1694460Y508858D02*
X1690181Y511138D01*
G01X1693918Y507843D02*
X1693919D01*
G01X1694460Y508858D02*
X1690181Y511138D01*
G01X1693919Y507843D02*
X1689403Y510248D01*
G01X1690181Y511138D02*
X1687243Y515224D01*
G01X1689403Y510248D02*
X1686496Y514291D01*
G01X1687243Y515224D02*
X1682408Y517287D01*
G01X1686496Y514291D02*
X1682290Y516086D01*
G01X1682408Y517287D02*
X1675785Y515891D01*
G01X1682290Y516086D02*
X1675739Y514706D01*
G01X1675785Y515892D02*
X1664950Y519061D01*
G01X1675739Y514706D02*
X1664422Y518017D01*
G01X1664950Y519061D02*
X1657382Y524849D01*
G01X1664422Y518017D02*
X1656521Y524058D01*
G01X1722586Y483380D02*
X1703318Y494804D01*
G01X1723003Y484470D02*
X1710645Y491798D01*
G01X1722586Y483380D02*
X1703318Y494804D01*
G01X1708365Y493149D02*
X1707204Y493838D01*
G01X1722586Y483380D02*
X1703318Y494804D01*
G01X1704924Y495189D02*
X1703763Y495878D01*
G01X1703318Y494804D02*
X1695127Y496897D01*
G01X1703763Y495878D02*
X1695148Y498079D01*
G01X1695127Y496897D02*
X1691138Y496025D01*
G01X1695148Y498079D02*
X1691163Y497208D01*
G01X1691138Y496025D02*
X1686424Y497267D01*
G01X1691163Y497208D02*
X1686899Y498332D01*
G01X1686424Y497267D02*
X1684466Y498556D01*
G01X1686899Y498332D02*
X1685315Y499375D01*
G01X1684466Y498556D02*
X1678531Y508316D01*
G01X1685315Y499375D02*
X1679265Y509323D01*
G01X1678531Y508316D02*
X1670986Y510120D01*
G01X1679265Y509323D02*
X1670953Y511311D01*
G01X1670986Y510120D02*
X1661040Y507150D01*
G01X1670953Y511311D02*
X1665684Y509738D01*
G01X1670986Y510120D02*
X1661040Y507150D01*
G01X1665684Y509737D02*
X1660871Y508300D01*
G01X1660222Y504045D02*
X1671430Y507393D01*
G01X1659927Y505158D02*
X1671397Y508584D01*
G01X1671430Y507393D02*
X1676905Y506083D01*
G01X1671397Y508584D02*
X1677639Y507090D01*
G01X1676905Y506083D02*
X1682624Y496677D01*
G01X1677639Y507090D02*
X1683473Y497496D01*
G01X1682624Y496677D02*
X1685257Y494944D01*
G01X1683473Y497496D02*
X1685732Y496009D01*
G01X1685257Y494944D02*
X1691316Y493348D01*
G01X1685732Y496009D02*
X1691341Y494531D01*
G01X1691316Y493348D02*
X1695374Y494237D01*
G01X1691341Y494531D02*
X1695395Y495419D01*
G01X1695374Y494237D02*
X1701966Y492551D01*
G01X1695395Y495419D02*
X1702411Y493625D01*
G01X1701966Y492551D02*
X1721789Y480798D01*
G01X1702411Y493625D02*
X1722206Y481888D01*
G01X1722767Y477250D02*
X1700960Y490178D01*
G01X1723186Y478339D02*
X1701405Y491252D01*
G01X1700960Y490178D02*
X1695340Y491617D01*
G01X1701405Y491252D02*
X1695361Y492799D01*
G01X1695340Y491617D02*
X1691341Y490741D01*
G01X1695361Y492799D02*
X1691366Y491924D01*
G01X1691341Y490741D02*
X1684036Y492663D01*
G01X1691366Y491924D02*
X1684512Y493728D01*
G01X1684036Y492663D02*
X1680776Y494811D01*
G01X1684512Y493728D02*
X1681625Y495630D01*
G01X1680776Y494811D02*
X1675280Y503850D01*
G01X1681625Y495630D02*
X1676014Y504857D01*
G01X1675280Y503850D02*
X1671503Y504752D01*
G01X1676014Y504857D02*
X1671470Y505943D01*
G01X1671503Y504752D02*
X1656345Y500224D01*
G01X1671470Y505943D02*
X1656067Y501342D01*
G01X1656729Y497678D02*
X1671576Y502113D01*
G01X1656451Y498796D02*
X1671543Y503304D01*
G01X1671576Y502113D02*
X1673652Y501616D01*
G01X1671543Y503304D02*
X1674385Y502624D01*
G01X1673652Y501616D02*
X1680063Y491074D01*
G01X1674385Y502624D02*
X1681098Y491586D01*
G01X1680063Y491074D02*
X1683459Y482384D01*
G01X1681098Y491586D02*
X1684382Y483183D01*
G01X1683459Y482384D02*
X1688244Y479669D01*
G01X1684382Y483183D02*
X1688439Y480881D01*
G01X1688244Y479669D02*
X1694042Y480826D01*
G01X1688439Y480881D02*
X1694102Y482011D01*
G01X1694042Y480826D02*
X1701138Y478648D01*
G01X1694102Y482011D02*
X1701172Y479841D01*
G01X1701138Y478648D02*
X1703174Y479149D01*
G01X1701172Y479841D02*
X1703139Y480325D01*
G01X1703174Y479149D02*
X1706662Y478505D01*
G01X1703139Y480325D02*
X1706641Y479679D01*
G01X1706662Y478505D02*
X1710086Y479267D01*
G01X1706641Y479679D02*
X1710120Y480453D01*
G01X1710086Y479267D02*
X1713575Y478276D01*
G01X1710120Y480453D02*
X1714033Y479342D01*
G01X1723003Y484470D02*
X1710645Y491798D01*
G01X1708365Y493149D02*
X1707204Y493838D01*
G01X1704924Y495189D02*
X1703763Y495878D01*
G01X1722586Y483380D02*
X1703318Y494804D01*
G01X1703763Y495878D02*
X1695148Y498079D01*
G01X1703318Y494804D02*
X1695127Y496897D01*
G01X1695148Y498079D02*
X1691163Y497208D01*
G01X1695127Y496897D02*
X1691138Y496025D01*
G01X1691163Y497208D02*
X1686899Y498332D01*
G01X1691138Y496025D02*
X1686424Y497267D01*
G01X1686899Y498332D02*
X1685315Y499375D01*
G01X1686424Y497267D02*
X1684466Y498556D01*
G01X1685315Y499375D02*
X1679265Y509323D01*
G01X1684466Y498556D02*
X1678531Y508316D01*
G01X1679265Y509323D02*
X1670953Y511311D01*
G01X1678531Y508316D02*
X1670986Y510120D01*
G01X1670953Y511311D02*
X1665684Y509738D01*
G01Y509737D02*
X1660871Y508300D01*
G01X1670986Y510120D02*
X1661040Y507150D01*
G01X1659927Y505158D02*
X1671397Y508584D01*
G01X1660222Y504045D02*
X1671430Y507393D01*
G01X1671397Y508584D02*
X1677639Y507090D01*
G01X1671430Y507393D02*
X1676905Y506083D01*
G01X1677639Y507090D02*
X1683473Y497496D01*
G01X1676905Y506083D02*
X1682624Y496677D01*
G01X1683473Y497496D02*
X1685732Y496009D01*
G01X1682624Y496677D02*
X1685257Y494944D01*
G01X1685732Y496009D02*
X1691341Y494531D01*
G01X1685257Y494944D02*
X1691316Y493348D01*
G01X1691341Y494531D02*
X1695395Y495419D01*
G01X1691316Y493348D02*
X1695374Y494237D01*
G01X1695395Y495419D02*
X1702411Y493625D01*
G01X1695374Y494237D02*
X1701966Y492551D01*
G01X1702411Y493625D02*
X1722206Y481888D01*
G01X1701966Y492551D02*
X1721789Y480798D01*
G01X1723186Y478339D02*
X1701405Y491252D01*
G01X1722767Y477250D02*
X1700960Y490178D01*
G01X1701405Y491252D02*
X1695361Y492799D01*
G01X1700960Y490178D02*
X1695340Y491617D01*
G01X1695361Y492799D02*
X1691366Y491924D01*
G01X1695340Y491617D02*
X1691341Y490741D01*
G01X1691366Y491924D02*
X1684512Y493728D01*
G01X1691341Y490741D02*
X1684036Y492663D01*
G01X1684512Y493728D02*
X1681625Y495630D01*
G01X1684036Y492663D02*
X1680776Y494811D01*
G01X1681625Y495630D02*
X1676014Y504857D01*
G01X1680776Y494811D02*
X1675280Y503850D01*
G01X1676014Y504857D02*
X1671470Y505943D01*
G01X1675280Y503850D02*
X1671503Y504752D01*
G01X1671470Y505943D02*
X1656067Y501342D01*
G01X1671503Y504752D02*
X1656345Y500224D01*
G01X1656451Y498796D02*
X1671543Y503304D01*
G01X1656729Y497678D02*
X1671576Y502113D01*
G01X1671543Y503304D02*
X1674385Y502624D01*
G01X1671576Y502113D02*
X1673652Y501616D01*
G01X1674385Y502624D02*
X1681098Y491586D01*
G01X1673652Y501616D02*
X1680063Y491074D01*
G01X1681098Y491586D02*
X1684382Y483183D01*
G01X1680063Y491074D02*
X1683459Y482384D01*
G01X1684382Y483183D02*
X1688439Y480881D01*
G01X1683459Y482384D02*
X1688244Y479669D01*
G01X1688439Y480881D02*
X1694102Y482011D01*
G01X1688244Y479669D02*
X1694042Y480826D01*
G01X1694102Y482011D02*
X1701172Y479841D01*
G01X1694042Y480826D02*
X1701138Y478648D01*
G01X1701172Y479841D02*
X1703139Y480325D01*
G01X1701138Y478648D02*
X1703174Y479149D01*
G01X1703139Y480325D02*
X1706641Y479679D01*
G01X1703174Y479149D02*
X1706662Y478505D01*
G01X1706641Y479679D02*
X1710120Y480453D01*
G01X1706662Y478505D02*
X1710086Y479267D01*
G01X1710120Y480453D02*
X1714033Y479342D01*
G01X1710086Y479267D02*
X1713575Y478276D01*
G01X1655761Y550655D02*
X1658381Y553275D01*
G01X1655284Y551805D02*
X1657904Y554425D01*
G01X1658381Y553275D02*
X1699483D01*
G01X1702133D02*
X1703483D01*
G01X1706133D02*
X1707483D01*
G01X1657904Y554425D02*
X1707960D01*
G01X1707483Y553275D02*
X1714608Y546150D01*
G01X1707960Y554425D02*
X1715085Y547300D01*
G01X1655284Y551805D02*
X1657904Y554425D01*
G01X1655761Y550655D02*
X1658381Y553275D01*
G01X1657904Y554425D02*
X1707960D01*
G01X1658381Y553275D02*
X1699483D01*
G01X1657904Y554425D02*
X1707960D01*
G01X1702133Y553275D02*
X1703483D01*
G01X1657904Y554425D02*
X1707960D01*
G01X1706133Y553275D02*
X1707483D01*
G01X1707960Y554425D02*
X1715085Y547300D01*
G01X1707483Y553275D02*
X1714608Y546150D01*
G01X1653761Y540016D02*
X1661207Y528335D01*
G01X1652945Y539155D02*
X1660346Y527544D01*
G01X1659289Y526600D02*
X1651985Y538058D01*
G01X1652945Y539155D02*
X1660346Y527544D01*
G01X1653761Y540016D02*
X1661207Y528335D01*
G01X1659289Y526600D02*
X1651985Y538058D01*
G01X1814223Y204400D02*
X1720119D01*
G01X1830700Y205550D02*
X1720596D01*
G01X1720119Y204400D02*
X1718977Y205542D01*
G01X1720596Y205550D02*
X1719454Y206692D01*
G01X1718745Y203816D02*
X1718793D01*
G01X1718268Y202666D02*
X1718316D01*
G01D02*
X1729181Y191801D01*
G01X1718793Y203816D02*
X1729658Y192951D01*
G01X1729181Y191801D02*
X1730531D01*
G01X1733181D02*
X1734531D01*
G01X1737181D02*
X1738531D01*
G01X1741181D02*
X1742531D01*
G01X1745181D02*
X1796622D01*
G01X1729658Y192951D02*
X1797099D01*
G01X1715249Y185333D02*
X1743161D01*
G01X1745811D02*
X1747161D01*
G01X1749811D02*
X1751161D01*
G01X1753811D02*
X1776040D01*
G01X1715726Y186483D02*
X1776517D01*
G01X1830700Y205550D02*
X1720596D01*
G01X1830700D02*
X1720596D01*
G01X1830700D02*
X1720596D01*
G01X1830700D02*
X1720596D01*
G01X1830700D02*
X1720596D01*
G01X1814223Y204400D02*
X1720119D01*
G01X1720596Y205550D02*
X1719454Y206692D01*
G01X1720119Y204400D02*
X1718977Y205542D01*
G01X1718745Y203816D02*
X1718793D01*
G01D02*
X1729658Y192951D01*
G01X1718268Y202666D02*
X1718316D01*
G01X1718793Y203816D02*
X1729658Y192951D01*
G01X1718316Y202666D02*
X1729181Y191801D01*
G01X1729658Y192951D02*
X1797099D01*
G01X1729181Y191801D02*
X1730531D01*
G01X1729658Y192951D02*
X1797099D01*
G01X1733181Y191801D02*
X1734531D01*
G01X1729658Y192951D02*
X1797099D01*
G01X1737181Y191801D02*
X1738531D01*
G01X1729658Y192951D02*
X1797099D01*
G01X1741181Y191801D02*
X1742531D01*
G01X1729658Y192951D02*
X1797099D01*
G01X1745181Y191801D02*
X1796622D01*
G01X1715726Y186483D02*
X1776517D01*
G01X1715249Y185333D02*
X1743161D01*
G01X1715726Y186483D02*
X1776517D01*
G01X1745811Y185333D02*
X1747161D01*
G01X1715726Y186483D02*
X1776517D01*
G01X1749811Y185333D02*
X1751161D01*
G01X1715726Y186483D02*
X1776517D01*
G01X1753811Y185333D02*
X1776040D01*
G01X1716997Y200400D02*
X1728792Y188605D01*
G01X1717474Y201550D02*
X1729269Y189755D01*
G01X1728792Y188605D02*
X1730142D01*
G01X1732792D02*
X1734142D01*
G01X1736792D02*
X1738142D01*
G01X1740792D02*
X1786068D01*
G01X1729269Y189755D02*
X1786545D01*
G01X1768063Y176976D02*
Y180987D01*
G01X1766913Y177063D02*
Y180510D01*
G01X1768063Y180987D02*
X1766350Y182700D01*
G01X1766913Y180510D02*
X1765873Y181550D01*
G01X1766350Y182700D02*
X1762800D01*
G01X1765873Y181550D02*
X1763277D01*
G01X1762800Y182700D02*
X1761000Y180900D01*
G01X1763277Y181550D02*
X1762150Y180423D01*
G01X1761000Y180900D02*
Y171400D01*
G01X1762150Y180423D02*
Y170923D01*
G01X1761000Y171400D02*
X1758340Y168740D01*
G01X1762150Y170923D02*
X1758817Y167590D01*
G01X1758340Y168740D02*
X1714760D01*
G01X1758817Y167590D02*
X1714283D01*
G01X1714760Y168740D02*
X1713825Y169675D01*
G01X1714283Y167590D02*
X1713348Y168525D01*
G01X1755465Y176074D02*
Y172173D01*
G01X1754315Y176075D02*
Y172650D01*
G01X1755465Y172173D02*
X1753382Y170090D01*
G01X1754315Y172650D02*
X1752905Y171240D01*
G01X1755465Y172173D02*
X1753382Y170090D01*
G01D02*
X1715723D01*
G01X1752905Y171240D02*
X1751555D01*
G01X1753382Y170090D02*
X1715723D01*
G01X1748905Y171240D02*
X1747555D01*
G01X1753382Y170090D02*
X1715723D01*
G01X1744905Y171240D02*
X1743555D01*
G01X1753382Y170090D02*
X1715723D01*
G01X1740905Y171240D02*
X1739555D01*
G01X1753382Y170090D02*
X1715723D01*
G01X1736905Y171240D02*
X1716200D01*
G01X1715723Y170090D02*
X1714788Y171025D01*
G01X1716200Y171240D02*
X1715265Y172175D01*
G01X1715169Y179519D02*
X1717274Y177414D01*
G01X1714692Y178369D02*
X1716124Y176937D01*
G01X1717274Y177414D02*
Y174959D01*
G01X1716124Y176937D02*
Y174482D01*
G01X1717274Y174959D02*
X1718493Y173740D01*
G01X1716124Y174482D02*
X1718016Y172590D01*
G01X1718493Y173740D02*
X1732979D01*
G01X1718016Y172590D02*
X1733456D01*
G01X1732979Y173740D02*
X1735700Y176461D01*
G01X1733456Y172590D02*
X1736850Y175984D01*
G01X1735700Y176461D02*
Y181000D01*
G01X1736850Y175984D02*
Y180523D01*
G01X1735700Y181000D02*
X1737350Y182650D01*
G01X1736850Y180523D02*
X1737827Y181500D01*
G01X1737350Y182650D02*
X1741250D01*
G01X1737827Y181500D02*
X1740773D01*
G01X1741250Y182650D02*
X1742867Y181033D01*
G01X1740773Y181500D02*
X1741717Y180556D01*
G01X1742867Y181033D02*
Y176976D01*
G01X1741717Y180556D02*
Y176975D01*
G01X1729176Y179824D02*
Y177033D01*
G01X1730326Y176975D02*
Y180301D01*
G01X1726650Y182350D02*
X1729176Y179824D01*
G01X1730326Y180301D02*
X1727127Y183500D01*
G01X1715550Y182350D02*
X1716900D01*
G01X1719550D02*
X1720900D01*
G01X1723550D02*
X1726650D01*
G01X1727127Y183500D02*
X1715073D01*
G01X1714381Y181181D02*
X1715550Y182350D01*
G01X1715073Y183500D02*
X1713904Y182331D01*
G01X1717474Y201550D02*
X1729269Y189755D01*
G01X1716997Y200400D02*
X1728792Y188605D01*
G01X1729269Y189755D02*
X1786545D01*
G01X1728792Y188605D02*
X1730142D01*
G01X1729269Y189755D02*
X1786545D01*
G01X1732792Y188605D02*
X1734142D01*
G01X1729269Y189755D02*
X1786545D01*
G01X1736792Y188605D02*
X1738142D01*
G01X1729269Y189755D02*
X1786545D01*
G01X1740792Y188605D02*
X1786068D01*
G01X1766913Y177063D02*
Y180510D01*
G01X1768063Y176976D02*
Y180987D01*
G01X1766913Y180510D02*
X1765873Y181550D01*
G01X1768063Y180987D02*
X1766350Y182700D01*
G01X1765873Y181550D02*
X1763277D01*
G01X1766350Y182700D02*
X1762800D01*
G01X1763277Y181550D02*
X1762150Y180423D01*
G01X1762800Y182700D02*
X1761000Y180900D01*
G01X1762150Y180423D02*
Y170923D01*
G01X1761000Y180900D02*
Y171400D01*
G01X1762150Y170923D02*
X1758817Y167590D01*
G01X1761000Y171400D02*
X1758340Y168740D01*
G01X1758817Y167590D02*
X1714283D01*
G01X1758340Y168740D02*
X1714760D01*
G01X1714283Y167590D02*
X1713348Y168525D01*
G01X1714760Y168740D02*
X1713825Y169675D01*
G01X1754315Y176075D02*
Y172650D01*
G01X1755465Y176074D02*
Y172173D01*
G01X1754315Y172650D02*
X1752905Y171240D01*
G01D02*
X1751555D01*
G01X1755465Y172173D02*
X1753382Y170090D01*
G01X1752905Y171240D02*
X1751555D01*
G01X1748905D02*
X1747555D01*
G01X1744905D02*
X1743555D01*
G01X1740905D02*
X1739555D01*
G01X1736905D02*
X1716200D01*
G01X1753382Y170090D02*
X1715723D01*
G01X1716200Y171240D02*
X1715265Y172175D01*
G01X1715723Y170090D02*
X1714788Y171025D01*
G01X1714692Y178369D02*
X1716124Y176937D01*
G01X1715169Y179519D02*
X1717274Y177414D01*
G01X1716124Y176937D02*
Y174482D01*
G01X1717274Y177414D02*
Y174959D01*
G01X1716124Y174482D02*
X1718016Y172590D01*
G01X1717274Y174959D02*
X1718493Y173740D01*
G01X1718016Y172590D02*
X1733456D01*
G01X1718493Y173740D02*
X1732979D01*
G01X1733456Y172590D02*
X1736850Y175984D01*
G01X1732979Y173740D02*
X1735700Y176461D01*
G01X1736850Y175984D02*
Y180523D01*
G01X1735700Y176461D02*
Y181000D01*
G01X1736850Y180523D02*
X1737827Y181500D01*
G01X1735700Y181000D02*
X1737350Y182650D01*
G01X1737827Y181500D02*
X1740773D01*
G01X1737350Y182650D02*
X1741250D01*
G01X1740773Y181500D02*
X1741717Y180556D01*
G01X1741250Y182650D02*
X1742867Y181033D01*
G01X1741717Y180556D02*
Y176975D01*
G01X1742867Y181033D02*
Y176976D01*
G01X1715073Y183500D02*
X1713904Y182331D01*
G01X1714381Y181181D02*
X1715550Y182350D01*
G01X1727127Y183500D02*
X1715073D01*
G01X1715550Y182350D02*
X1716900D01*
G01X1727127Y183500D02*
X1715073D01*
G01X1719550Y182350D02*
X1720900D01*
G01X1727127Y183500D02*
X1715073D01*
G01X1723550Y182350D02*
X1726650D01*
G01X1730326Y180301D02*
X1727127Y183500D01*
G01X1726650Y182350D02*
X1729176Y179824D01*
G01X1730326Y176975D02*
Y180301D01*
G01X1729176Y179824D02*
Y177033D01*
G01X1773250Y212081D02*
Y218050D01*
G01X1760511Y214161D02*
X1759556Y215116D01*
G01X1757683Y216989D02*
X1756728Y217944D01*
G01X1754199Y222100D02*
X1761661Y214638D01*
G01X1760511Y211942D02*
Y214161D01*
G01X1761661Y214638D02*
Y212220D01*
G01X1748050Y212081D02*
Y215062D01*
G01X1749200Y212081D02*
Y215539D01*
G01X1748050Y215062D02*
X1744762Y218350D01*
G01X1749200Y215539D02*
X1745239Y219500D01*
G01X1720732Y218350D02*
X1713787Y211405D01*
G01X1720255Y219500D02*
X1713310Y212555D01*
G01X1735300Y212600D02*
Y213200D01*
G01X1736450Y212600D02*
Y213677D01*
G01X1735300Y213200D02*
X1733800Y214700D01*
G01X1736450Y213677D02*
X1734277Y215850D01*
G01X1733800Y214700D02*
X1732450D01*
G01X1729800D02*
X1728450D01*
G01X1725800D02*
X1721451D01*
G01X1734277Y215850D02*
X1720973D01*
G01X1721451Y214700D02*
X1720116Y213365D01*
G01X1718242Y211491D02*
X1715616Y208865D01*
G01X1720973Y215850D02*
X1715139Y210015D01*
G01X1773250Y212081D02*
Y218050D01*
G01X1761661Y214638D02*
Y212220D01*
G01X1760511Y211942D02*
Y214161D01*
G01X1754199Y222100D02*
X1761661Y214638D01*
G01X1760511Y214161D02*
X1759556Y215116D01*
G01X1754199Y222100D02*
X1761661Y214638D01*
G01X1757683Y216989D02*
X1756728Y217944D01*
G01X1754199Y222100D02*
X1761661Y214638D01*
G01X1749200Y212081D02*
Y215539D01*
G01X1748050Y212081D02*
Y215062D01*
G01X1749200Y215539D02*
X1745239Y219500D01*
G01X1748050Y215062D02*
X1744762Y218350D01*
G01X1749200Y215539D02*
X1745239Y219500D01*
G01X1720255D02*
X1713310Y212555D01*
G01X1720732Y218350D02*
X1713787Y211405D01*
G01X1736450Y212600D02*
Y213677D01*
G01X1735300Y212600D02*
Y213200D01*
G01X1736450Y213677D02*
X1734277Y215850D01*
G01X1735300Y213200D02*
X1733800Y214700D01*
G01X1734277Y215850D02*
X1720973D01*
G01X1733800Y214700D02*
X1732450D01*
G01X1734277Y215850D02*
X1720973D01*
G01X1729800Y214700D02*
X1728450D01*
G01X1734277Y215850D02*
X1720973D01*
G01X1725800Y214700D02*
X1721451D01*
G01X1720973Y215850D02*
X1715139Y210015D01*
G01X1721451Y214700D02*
X1720116Y213365D01*
G01X1720973Y215850D02*
X1715139Y210015D01*
G01X1718242Y211491D02*
X1715616Y208865D01*
G01X1785218Y228882D02*
X1714992D01*
G01X1785695Y230032D02*
X1714515D01*
G01X1714992Y228882D02*
X1714037Y227927D01*
G01X1776051Y225950D02*
X1716627D01*
G01X1776528Y227100D02*
X1716150D01*
G01X1773250Y218050D02*
X1770678Y220622D01*
G01X1768805Y222495D02*
X1767850Y223450D01*
G01X1774400Y218527D02*
X1768327Y224600D01*
G01X1767850Y223450D02*
X1766500D01*
G01X1763850D02*
X1762500D01*
G01X1759850D02*
X1758500D01*
G01X1755850D02*
X1718248D01*
G01X1768327Y224600D02*
X1717771D01*
G01X1753722Y220950D02*
X1752372D01*
G01X1749722D02*
X1748372D01*
G01X1745722D02*
X1719285D01*
G01X1718808Y222100D02*
X1754199D01*
G01X1754854Y219818D02*
X1753722Y220950D01*
G01X1744762Y218350D02*
X1743412D01*
G01X1744762D02*
X1743412D01*
G01X1740762D02*
X1739412D01*
G01X1736762D02*
X1735412D01*
G01X1732762D02*
X1720732D01*
G01X1745239Y219500D02*
X1720255D01*
G01X1785695Y230032D02*
X1714515D01*
G01X1785218Y228882D02*
X1714992D01*
G01D02*
X1714037Y227927D01*
G01X1776528Y227100D02*
X1716150D01*
G01X1776051Y225950D02*
X1716627D01*
G01X1774400Y218527D02*
X1768327Y224600D01*
G01X1773250Y218050D02*
X1770678Y220622D01*
G01X1774400Y218527D02*
X1768327Y224600D01*
G01X1768805Y222495D02*
X1767850Y223450D01*
G01X1768327Y224600D02*
X1717771D01*
G01X1767850Y223450D02*
X1766500D01*
G01X1768327Y224600D02*
X1717771D01*
G01X1763850Y223450D02*
X1762500D01*
G01X1768327Y224600D02*
X1717771D01*
G01X1759850Y223450D02*
X1758500D01*
G01X1768327Y224600D02*
X1717771D01*
G01X1755850Y223450D02*
X1718248D01*
G01X1754854Y219818D02*
X1753722Y220950D01*
G01X1718808Y222100D02*
X1754199D01*
G01X1753722Y220950D02*
X1752372D01*
G01X1718808Y222100D02*
X1754199D01*
G01X1749722Y220950D02*
X1748372D01*
G01X1718808Y222100D02*
X1754199D01*
G01X1745722Y220950D02*
X1719285D01*
G01X1745239Y219500D02*
X1720255D01*
G01X1744762Y218350D02*
X1743412D01*
G01X1745239Y219500D02*
X1720255D01*
G01X1740762Y218350D02*
X1739412D01*
G01X1745239Y219500D02*
X1720255D01*
G01X1736762Y218350D02*
X1735412D01*
G01X1745239Y219500D02*
X1720255D01*
G01X1732762Y218350D02*
X1720732D01*
G01X1749483Y468989D02*
X1754422Y464050D01*
G01D02*
X1785306D01*
G01X1749483Y468989D02*
X1754422Y464050D01*
G01D02*
X1785306D01*
G01X1776128Y489644D02*
X1770081Y492150D01*
G01X1776128Y489644D02*
X1770081Y492150D01*
G01X1773085D02*
X1770311Y493300D01*
G01X1770081Y492150D02*
X1765527D01*
G01X1770311Y493300D02*
X1765298D01*
G01X1765527Y492150D02*
X1762539Y490911D01*
G01X1765298Y493300D02*
X1761887Y491886D01*
G01X1762539Y490911D02*
X1760429Y488801D01*
G01X1761887Y491886D02*
X1761725Y491724D01*
G01X1762539Y490911D02*
X1760429Y488801D01*
G01X1761725Y491725D02*
X1759452Y489452D01*
G01X1760429Y488801D02*
X1758661Y484534D01*
G01X1759452Y489452D02*
X1757685Y485186D01*
G01X1758661Y484534D02*
X1755827Y481700D01*
G01X1757685Y485186D02*
X1755350Y482850D01*
G01X1755827Y481700D02*
X1744863D01*
G01X1755350Y482850D02*
X1744977D01*
G01X1744863Y481700D02*
X1731482Y484356D01*
G01X1744977Y482850D02*
X1731818Y485463D01*
G01X1731482Y484356D02*
X1714682Y491320D01*
G01X1731818Y485463D02*
X1730571Y485980D01*
G01X1731482Y484356D02*
X1714682Y491320D01*
G01X1728123Y486995D02*
X1726876Y487512D01*
G01X1731482Y484356D02*
X1714682Y491320D01*
G01X1724428Y488527D02*
X1715425Y492258D01*
G01X1715426Y516271D02*
X1720282Y517108D01*
G01X1720380Y518292D02*
X1727280Y515887D01*
G01X1720282Y517108D02*
X1726414Y514970D01*
G01X1727280Y515887D02*
X1731750Y505108D01*
G01X1726414Y514970D02*
X1726931Y513723D01*
G01X1727280Y515887D02*
X1731750Y505108D01*
G01X1727947Y511275D02*
X1728464Y510028D01*
G01X1727280Y515887D02*
X1731750Y505108D01*
G01X1729479Y507580D02*
X1730600Y504878D01*
G01X1731750Y505108D02*
Y501300D01*
G01X1730600Y504878D02*
Y501300D01*
G01X1746450Y495750D02*
Y494653D01*
G01X1745300Y495900D02*
Y495130D01*
G01X1746450Y494653D02*
X1744747Y492950D01*
G01X1745300Y495130D02*
X1744270Y494100D01*
G01X1744747Y492950D02*
X1727193D01*
G01X1744270Y494100D02*
X1727307D01*
G01X1727193Y492950D02*
X1722305Y493922D01*
G01X1727307Y494100D02*
X1722641Y495028D01*
G01X1722305Y493922D02*
X1717728Y495818D01*
G01X1722641Y495028D02*
X1718470Y496757D01*
G01X1717728Y495818D02*
X1714291Y500591D01*
G01X1718470Y496757D02*
X1715303Y501155D01*
G01D02*
X1712860Y507047D01*
G01X1773085Y492150D02*
X1770311Y493300D01*
G01X1776128Y489644D02*
X1770081Y492150D01*
G01X1770311Y493300D02*
X1765298D01*
G01X1770081Y492150D02*
X1765527D01*
G01X1765298Y493300D02*
X1761887Y491886D01*
G01X1765527Y492150D02*
X1762539Y490911D01*
G01X1761887Y491886D02*
X1761725Y491724D01*
G01Y491725D02*
X1759452Y489452D01*
G01X1762539Y490911D02*
X1760429Y488801D01*
G01X1759452Y489452D02*
X1757685Y485186D01*
G01X1760429Y488801D02*
X1758661Y484534D01*
G01X1757685Y485186D02*
X1755350Y482850D01*
G01X1758661Y484534D02*
X1755827Y481700D01*
G01X1755350Y482850D02*
X1744977D01*
G01X1755827Y481700D02*
X1744863D01*
G01X1744977Y482850D02*
X1731818Y485463D01*
G01X1744863Y481700D02*
X1731482Y484356D01*
G01X1731818Y485463D02*
X1730571Y485980D01*
G01X1728123Y486995D02*
X1726876Y487512D01*
G01X1724428Y488527D02*
X1715425Y492258D01*
G01X1731482Y484356D02*
X1714682Y491320D01*
G01X1715426Y516271D02*
X1720282Y517108D01*
G01D02*
X1726414Y514970D01*
G01X1720380Y518292D02*
X1727280Y515887D01*
G01X1726414Y514970D02*
X1726931Y513723D01*
G01X1727947Y511275D02*
X1728464Y510028D01*
G01X1729479Y507580D02*
X1730600Y504878D01*
G01X1727280Y515887D02*
X1731750Y505108D01*
G01X1730600Y504878D02*
Y501300D01*
G01X1731750Y505108D02*
Y501300D01*
G01X1745300Y495900D02*
Y495130D01*
G01X1746450Y495750D02*
Y494653D01*
G01X1745300Y495130D02*
X1744270Y494100D01*
G01X1746450Y494653D02*
X1744747Y492950D01*
G01X1744270Y494100D02*
X1727307D01*
G01X1744747Y492950D02*
X1727193D01*
G01X1727307Y494100D02*
X1722641Y495028D01*
G01X1727193Y492950D02*
X1722305Y493922D01*
G01X1722641Y495028D02*
X1718470Y496757D01*
G01X1722305Y493922D02*
X1717728Y495818D01*
G01X1718470Y496757D02*
X1715303Y501155D01*
G01X1717728Y495818D02*
X1714291Y500591D01*
G01X1715303Y501155D02*
X1712860Y507047D01*
G01X1756650Y495956D02*
Y493923D01*
G01X1755500Y495956D02*
Y494400D01*
G01X1756650Y493923D02*
X1753149Y490422D01*
G01X1755500Y494400D02*
X1752672Y491572D01*
G01X1753149Y490422D02*
X1726996D01*
G01X1752672Y491572D02*
X1727110D01*
G01X1726996Y490422D02*
X1720411Y491731D01*
G01X1727110Y491572D02*
X1720747Y492837D01*
G01X1720411Y491731D02*
X1716305Y493433D01*
G01X1720747Y492838D02*
X1717048Y494371D01*
G01D02*
X1713059Y499909D01*
G01X1755500Y495956D02*
Y494400D01*
G01X1756650Y495956D02*
Y493923D01*
G01X1755500Y494400D02*
X1752672Y491572D01*
G01X1756650Y493923D02*
X1753149Y490422D01*
G01X1752672Y491572D02*
X1727110D01*
G01X1753149Y490422D02*
X1726996D01*
G01X1727110Y491572D02*
X1720747Y492837D01*
G01X1726996Y490422D02*
X1720411Y491731D01*
G01X1720747Y492838D02*
X1717048Y494371D01*
G01X1720411Y491731D02*
X1716305Y493433D01*
G01X1717048Y494371D02*
X1713059Y499909D01*
G01X1768400Y486905D02*
Y485400D01*
G01X1767250Y486905D02*
Y485877D01*
G01X1768400Y485400D02*
X1767367Y484366D01*
G01X1767250Y485877D02*
X1766715Y485342D01*
G01X1767367Y484366D02*
X1759387Y481059D01*
G01X1766715Y485342D02*
X1758737Y482037D01*
G01X1759387Y481059D02*
X1756828Y478500D01*
G01X1758737Y482037D02*
X1756351Y479650D01*
G01X1756828Y478500D02*
X1747117D01*
G01X1756351Y479650D02*
X1747231D01*
G01X1747117Y478500D02*
X1722586Y483380D01*
G01X1747231Y479650D02*
X1727005Y483674D01*
G01X1747117Y478500D02*
X1722586Y483380D01*
G01X1724406Y484191D02*
X1723003Y484470D01*
G01X1721790Y480798D02*
X1746668Y475850D01*
G01X1722206Y481888D02*
X1746782Y477000D01*
G01X1746668Y475850D02*
X1758277D01*
G01X1746782Y477000D02*
X1757800D01*
G01X1758277Y475850D02*
X1760193Y477765D01*
G01X1757800Y477000D02*
X1759541Y478741D01*
G01X1760193Y477765D02*
X1764326Y479477D01*
G01X1759541Y478741D02*
X1764044Y480605D01*
G01X1764326Y479477D02*
X1780792Y481096D01*
G01X1764044Y480605D02*
X1780623Y482235D01*
G01X1781829Y469150D02*
X1763498D01*
G01X1781352Y470300D02*
X1763612D01*
G01X1763498Y469150D02*
X1722767Y477250D01*
G01X1763612Y470300D02*
X1739268Y475142D01*
G01X1763498Y469150D02*
X1722767Y477250D01*
G01X1736669Y475658D02*
X1735345Y475922D01*
G01X1763498Y469150D02*
X1722767Y477250D01*
G01X1732746Y476439D02*
X1731422Y476702D01*
G01X1763498Y469150D02*
X1722767Y477250D01*
G01X1728823Y477219D02*
X1723186Y478340D01*
G01X1713575Y478276D02*
X1719022Y475048D01*
G01X1714033Y479342D02*
X1719437Y476139D01*
G01X1719022Y475048D02*
X1749483Y468989D01*
G01X1719437Y476139D02*
X1750050Y470050D01*
G01D02*
X1754900Y465200D01*
G01D02*
X1785077D01*
G01X1767250Y486905D02*
Y485877D01*
G01X1768400Y486905D02*
Y485400D01*
G01X1767250Y485877D02*
X1766715Y485342D01*
G01X1768400Y485400D02*
X1767367Y484366D01*
G01X1766715Y485342D02*
X1758737Y482037D01*
G01X1767367Y484366D02*
X1759387Y481059D01*
G01X1758737Y482037D02*
X1756351Y479650D01*
G01X1759387Y481059D02*
X1756828Y478500D01*
G01X1756351Y479650D02*
X1747231D01*
G01X1756828Y478500D02*
X1747117D01*
G01X1747231Y479650D02*
X1727005Y483674D01*
G01X1724406Y484191D02*
X1723003Y484470D01*
G01X1747117Y478500D02*
X1722586Y483380D01*
G01X1722206Y481888D02*
X1746782Y477000D01*
G01X1721790Y480798D02*
X1746668Y475850D01*
G01X1746782Y477000D02*
X1757800D01*
G01X1746668Y475850D02*
X1758277D01*
G01X1757800Y477000D02*
X1759541Y478741D01*
G01X1758277Y475850D02*
X1760193Y477765D01*
G01X1759541Y478741D02*
X1764044Y480605D01*
G01X1760193Y477765D02*
X1764326Y479477D01*
G01X1764044Y480605D02*
X1780623Y482235D01*
G01X1764326Y479477D02*
X1780792Y481096D01*
G01X1781352Y470300D02*
X1763612D01*
G01X1781829Y469150D02*
X1763498D01*
G01X1763612Y470300D02*
X1739268Y475142D01*
G01X1736669Y475658D02*
X1735345Y475922D01*
G01X1732746Y476439D02*
X1731422Y476702D01*
G01X1728823Y477219D02*
X1723186Y478340D01*
G01X1763498Y469150D02*
X1722767Y477250D01*
G01X1714033Y479342D02*
X1719437Y476139D01*
G01X1713575Y478276D02*
X1719022Y475048D01*
G01X1719437Y476139D02*
X1750050Y470050D01*
G01X1719022Y475048D02*
X1749483Y468989D01*
G01X1750050Y470050D02*
X1754900Y465200D01*
G01D02*
X1785077D01*
G01X1714608Y546150D02*
X1725920D01*
G01X1715085Y547300D02*
X1726397D01*
G01X1725920Y546150D02*
X1729515Y542555D01*
G01X1726397Y547300D02*
X1729992Y543705D01*
G01X1729515Y542555D02*
X1738021D01*
G01X1740671D02*
X1742021D01*
G01X1744671D02*
X1746455D01*
G01X1729992Y543705D02*
X1745978D01*
G01X1746455Y542555D02*
X1748850Y544950D01*
G01X1745978Y543705D02*
X1748373Y546100D01*
G01X1748850Y544950D02*
X1760931D01*
G01X1748373Y546100D02*
X1761408D01*
G01X1760931Y544950D02*
X1763581Y542300D01*
G01X1765454Y540427D02*
X1766409Y539472D01*
G01X1768282Y537599D02*
X1769237Y536644D01*
G01X1761408Y546100D02*
X1769714Y537794D01*
G01X1769237Y536644D02*
X1777471D01*
G01X1769714Y537794D02*
X1776994D01*
G01X1715085Y547300D02*
X1726397D01*
G01X1714608Y546150D02*
X1725920D01*
G01X1726397Y547300D02*
X1729992Y543705D01*
G01X1725920Y546150D02*
X1729515Y542555D01*
G01X1729992Y543705D02*
X1745978D01*
G01X1729515Y542555D02*
X1738021D01*
G01X1729992Y543705D02*
X1745978D01*
G01X1740671Y542555D02*
X1742021D01*
G01X1729992Y543705D02*
X1745978D01*
G01X1744671Y542555D02*
X1746455D01*
G01X1745978Y543705D02*
X1748373Y546100D01*
G01X1746455Y542555D02*
X1748850Y544950D01*
G01X1748373Y546100D02*
X1761408D01*
G01X1748850Y544950D02*
X1760931D01*
G01X1761408Y546100D02*
X1769714Y537794D01*
G01X1760931Y544950D02*
X1763581Y542300D01*
G01X1761408Y546100D02*
X1769714Y537794D01*
G01X1765454Y540427D02*
X1766409Y539472D01*
G01X1761408Y546100D02*
X1769714Y537794D01*
G01X1768282Y537599D02*
X1769237Y536644D01*
G01X1769714Y537794D02*
X1776994D01*
G01X1769237Y536644D02*
X1777471D01*
G01X1817307Y176975D02*
Y179706D01*
G01X1818457Y176975D02*
Y179229D01*
G01X1817307Y179706D02*
X1823906Y186305D01*
G01X1818457Y179229D02*
X1824383Y185155D01*
G01X1823906Y186305D02*
X1827991D01*
G01X1824383Y185155D02*
X1828468D01*
G01X1827991Y186305D02*
X1832700Y191014D01*
G01X1828468Y185155D02*
X1833850Y190537D01*
G01X1832700Y191014D02*
Y201923D01*
G01X1833850Y190537D02*
Y202400D01*
G01X1832700Y201923D02*
X1830223Y204400D01*
G01X1833850Y202400D02*
X1830700Y205550D01*
G01X1830223Y204400D02*
X1828873D01*
G01X1826223D02*
X1824873D01*
G01X1822223D02*
X1820873D01*
G01X1818223D02*
X1816873D01*
G01X1796622Y191801D02*
X1804709Y183714D01*
G01X1797099Y192951D02*
X1805859Y184191D01*
G01X1804709Y183714D02*
Y176975D01*
G01X1805859Y184191D02*
Y176976D01*
G01X1776040Y185333D02*
X1779512Y181861D01*
G01X1776517Y186483D02*
X1780662Y182338D01*
G01X1779512Y181861D02*
Y176975D01*
G01X1780662Y182338D02*
Y176976D01*
G01X1818457Y176975D02*
Y179229D01*
G01X1817307Y176975D02*
Y179706D01*
G01X1818457Y179229D02*
X1824383Y185155D01*
G01X1817307Y179706D02*
X1823906Y186305D01*
G01X1824383Y185155D02*
X1828468D01*
G01X1823906Y186305D02*
X1827991D01*
G01X1828468Y185155D02*
X1833850Y190537D01*
G01X1827991Y186305D02*
X1832700Y191014D01*
G01X1833850Y190537D02*
Y202400D01*
G01X1832700Y191014D02*
Y201923D01*
G01X1833850Y202400D02*
X1830700Y205550D01*
G01X1832700Y201923D02*
X1830223Y204400D01*
G01D02*
X1828873D01*
G01X1826223D02*
X1824873D01*
G01X1822223D02*
X1820873D01*
G01X1818223D02*
X1816873D01*
G01X1797099Y192951D02*
X1805859Y184191D01*
G01X1796622Y191801D02*
X1804709Y183714D01*
G01X1805859Y184191D02*
Y176976D01*
G01X1804709Y183714D02*
Y176975D01*
G01X1776517Y186483D02*
X1780662Y182338D01*
G01X1776040Y185333D02*
X1779512Y181861D01*
G01X1780662Y182338D02*
Y176976D01*
G01X1779512Y181861D02*
Y176975D01*
G01X1786068Y188605D02*
X1792110Y182563D01*
G01X1786545Y189755D02*
X1793260Y183040D01*
G01X1792110Y182563D02*
Y176975D01*
G01X1793260Y183040D02*
Y176976D01*
G01X1786545Y189755D02*
X1793260Y183040D01*
G01X1786068Y188605D02*
X1792110Y182563D01*
G01X1793260Y183040D02*
Y176976D01*
G01X1792110Y182563D02*
Y176975D01*
G01X1811050Y212681D02*
Y215950D01*
G01X1812200Y212682D02*
Y216427D01*
G01X1811050Y215950D02*
X1807500Y219500D01*
G01X1812200Y216427D02*
X1807977Y220650D01*
G01X1798233Y212913D02*
Y215867D01*
G01X1799383Y212900D02*
Y216344D01*
G01X1798233Y215867D02*
X1790907Y223193D01*
G01X1799383Y216344D02*
X1785695Y230032D01*
G01X1785850Y212081D02*
Y216151D01*
G01X1787000Y212081D02*
Y216628D01*
G01X1785850Y216151D02*
X1781707Y220294D01*
G01X1787000Y216628D02*
X1776528Y227100D01*
G01X1774400Y212082D02*
Y218527D01*
G01X1824760Y221830D02*
Y212611D01*
G01X1823610Y221353D02*
Y212611D01*
G01X1812200Y212682D02*
Y216427D01*
G01X1811050Y212681D02*
Y215950D01*
G01X1812200Y216427D02*
X1807977Y220650D01*
G01X1811050Y215950D02*
X1807500Y219500D01*
G01X1799383Y212900D02*
Y216344D01*
G01X1798233Y212913D02*
Y215867D01*
G01X1799383Y216344D02*
X1785695Y230032D01*
G01X1798233Y215867D02*
X1790907Y223193D01*
G01X1799383Y216344D02*
X1785695Y230032D01*
G01X1799383Y216344D02*
X1785695Y230032D01*
G01X1799383Y216344D02*
X1785695Y230032D01*
G01X1799383Y216344D02*
X1785695Y230032D01*
G01X1787000Y212081D02*
Y216628D01*
G01X1785850Y212081D02*
Y216151D01*
G01X1787000Y216628D02*
X1776528Y227100D01*
G01X1785850Y216151D02*
X1781707Y220294D01*
G01X1787000Y216628D02*
X1776528Y227100D01*
G01X1787000Y216628D02*
X1776528Y227100D01*
G01X1787000Y216628D02*
X1776528Y227100D01*
G01X1787000Y216628D02*
X1776528Y227100D01*
G01X1774400Y212082D02*
Y218527D01*
G01X1823610Y221353D02*
Y212611D01*
G01X1824760Y221830D02*
Y212611D01*
G01X1807500Y219500D02*
X1804400D01*
G01X1807977Y220650D02*
X1804877D01*
G01X1804400Y219500D02*
X1796700Y227200D01*
G01X1804877Y220650D02*
X1797850Y227677D01*
G01X1796700Y227200D02*
Y235900D01*
G01X1797850Y227677D02*
Y236377D01*
G01X1796700Y235900D02*
X1792661Y239939D01*
G01X1797850Y236377D02*
X1793138Y241089D01*
G01X1792661Y239939D02*
X1789361D01*
G01X1786661D02*
X1785261D01*
G01X1790907Y223193D02*
X1789988D01*
G01X1789033Y225067D02*
X1788078Y226022D01*
G01D02*
X1787159D01*
G01X1786205Y227895D02*
X1785218Y228882D01*
G01X1781707Y220294D02*
X1780788D01*
G01X1779834Y222167D02*
X1778879Y223122D01*
G01D02*
X1777960D01*
G01X1777006Y224995D02*
X1776051Y225950D01*
G01X1797685Y243589D02*
X1805657Y235617D01*
G01X1797208Y242439D02*
X1805180Y234467D01*
G01X1805657Y235617D02*
X1810973D01*
G01X1805180Y234467D02*
X1810496D01*
G01X1810973Y235617D02*
X1824760Y221830D01*
G01X1810496Y234467D02*
X1814955Y230008D01*
G01X1810973Y235617D02*
X1824760Y221830D01*
G01X1816885Y228078D02*
X1817840Y227123D01*
G01X1810973Y235617D02*
X1824760Y221830D01*
G01X1819770Y225193D02*
X1820725Y224238D01*
G01X1810973Y235617D02*
X1824760Y221830D01*
G01X1822655Y222308D02*
X1823610Y221353D01*
G01X1807977Y220650D02*
X1804877D01*
G01X1807500Y219500D02*
X1804400D01*
G01X1804877Y220650D02*
X1797850Y227677D01*
G01X1804400Y219500D02*
X1796700Y227200D01*
G01X1797850Y227677D02*
Y236377D01*
G01X1796700Y227200D02*
Y235900D01*
G01X1797850Y236377D02*
X1793138Y241089D01*
G01X1796700Y235900D02*
X1792661Y239939D01*
G01D02*
X1789361D01*
G01X1786661D02*
X1785261D01*
G01X1790907Y223193D02*
X1789988D01*
G01X1789033Y225067D02*
X1788078Y226022D01*
G01D02*
X1787159D01*
G01X1786205Y227895D02*
X1785218Y228882D01*
G01X1781707Y220294D02*
X1780788D01*
G01X1779834Y222167D02*
X1778879Y223122D01*
G01D02*
X1777960D01*
G01X1777006Y224995D02*
X1776051Y225950D01*
G01X1797208Y242439D02*
X1805180Y234467D01*
G01X1797685Y243589D02*
X1805657Y235617D01*
G01X1805180Y234467D02*
X1810496D01*
G01X1805657Y235617D02*
X1810973D01*
G01X1810496Y234467D02*
X1814955Y230008D01*
G01X1816885Y228078D02*
X1817840Y227123D01*
G01X1819770Y225193D02*
X1820725Y224238D01*
G01X1822655Y222308D02*
X1823610Y221353D01*
G01X1810973Y235617D02*
X1824760Y221830D01*
G01X1785306Y464050D02*
X1789336Y465719D01*
G01X1785306Y464050D02*
X1789336Y465719D01*
G01X1787600Y488480D02*
Y487569D01*
G01X1786450Y488480D02*
Y488046D01*
G01X1787600Y487569D02*
X1785598Y485569D01*
G01X1786450Y488046D02*
X1785121Y486719D01*
G01X1785598Y485569D02*
X1782248D01*
G01X1785121Y486719D02*
X1782477D01*
G01X1782248Y485569D02*
X1778758Y487014D01*
G01X1782477Y486719D02*
X1779411Y487990D01*
G01X1778758Y487014D02*
X1776128Y489644D01*
G01X1779411Y487990D02*
X1776780Y490619D01*
G01D02*
X1775533Y491136D01*
G01X1786450Y488480D02*
Y488046D01*
G01X1787600Y488480D02*
Y487569D01*
G01X1786450Y488046D02*
X1785121Y486719D01*
G01X1787600Y487569D02*
X1785598Y485569D01*
G01X1785121Y486719D02*
X1782477D01*
G01X1785598Y485569D02*
X1782248D01*
G01X1782477Y486719D02*
X1779411Y487990D01*
G01X1782248Y485569D02*
X1778758Y487014D01*
G01X1779411Y487990D02*
X1776780Y490619D01*
G01X1778758Y487014D02*
X1776128Y489644D01*
G01X1776780Y490619D02*
X1775533Y491136D01*
G01X1780792Y481096D02*
X1784075Y481749D01*
G01X1780623Y482235D02*
X1783739Y482855D01*
G01X1784075Y481749D02*
X1786195Y482628D01*
G01X1783739Y482855D02*
X1785542Y483603D01*
G01X1786195Y482628D02*
X1788447Y484880D01*
G01X1785542Y483603D02*
X1787970Y486030D01*
G01X1788447Y484880D02*
X1795719D01*
G01X1787970Y486030D02*
X1795489D01*
G01X1795719Y484880D02*
X1798041Y485843D01*
G01X1795489Y486030D02*
X1797389Y486818D01*
G01X1798041Y485843D02*
X1799100Y486902D01*
G01X1797389Y486818D02*
X1797950Y487379D01*
G01X1799100Y486902D02*
Y488380D01*
G01X1797950Y487379D02*
Y488580D01*
G01X1810050Y488280D02*
Y486951D01*
G01X1808900Y488280D02*
Y487428D01*
G01X1810050Y486951D02*
X1807018Y483919D01*
G01X1808900Y487428D02*
X1806451Y484980D01*
G01X1807018Y483919D02*
X1798323Y482190D01*
G01X1806451Y484980D02*
X1798209Y483340D01*
G01X1798323Y482190D02*
X1789294D01*
G01X1798209Y483340D02*
X1788817D01*
G01X1789294Y482190D02*
X1787450Y480346D01*
G01X1788817Y483340D02*
X1786300Y480823D01*
G01X1787450Y480346D02*
Y478654D01*
G01X1786300Y480823D02*
Y478883D01*
G01X1787450Y478654D02*
X1784703Y472023D01*
G01X1786300Y478883D02*
X1783727Y472675D01*
G01X1784703Y472023D02*
X1784540Y471860D01*
G01Y471861D02*
X1781829Y469150D01*
G01X1783727Y472675D02*
X1781352Y470300D01*
G01X1785077Y465200D02*
X1788684Y466695D01*
G01X1789336Y465719D02*
X1803141Y479524D01*
G01X1788684Y466695D02*
X1789664Y467675D01*
G01X1789336Y465719D02*
X1803141Y479524D01*
G01X1791538Y469549D02*
X1792493Y470504D01*
G01X1789336Y465719D02*
X1803141Y479524D01*
G01X1794367Y472378D02*
X1799661Y477672D01*
G01X1789336Y465719D02*
X1803141Y479524D01*
G01X1801534Y479545D02*
X1802489Y480500D01*
G01X1803141Y479524D02*
X1812615Y483450D01*
G01X1802489Y480500D02*
X1812386Y484600D01*
G01X1812615Y483450D02*
X1816306D01*
G01X1812386Y484600D02*
X1816077D01*
G01X1816306Y483450D02*
X1820864Y485338D01*
G01X1816077Y484600D02*
X1820212Y486314D01*
G01X1820864Y485338D02*
X1822200Y486673D01*
G01X1820212Y486314D02*
X1821050Y487150D01*
G01X1822200Y486673D02*
Y488300D01*
G01X1821050Y487150D02*
Y488480D01*
G01X1780623Y482235D02*
X1783739Y482855D01*
G01X1780792Y481096D02*
X1784075Y481749D01*
G01X1783739Y482855D02*
X1785542Y483603D01*
G01X1784075Y481749D02*
X1786195Y482628D01*
G01X1785542Y483603D02*
X1787970Y486030D01*
G01X1786195Y482628D02*
X1788447Y484880D01*
G01X1787970Y486030D02*
X1795489D01*
G01X1788447Y484880D02*
X1795719D01*
G01X1795489Y486030D02*
X1797389Y486818D01*
G01X1795719Y484880D02*
X1798041Y485843D01*
G01X1797389Y486818D02*
X1797950Y487379D01*
G01X1798041Y485843D02*
X1799100Y486902D01*
G01X1797950Y487379D02*
Y488580D01*
G01X1799100Y486902D02*
Y488380D01*
G01X1808900Y488280D02*
Y487428D01*
G01X1810050Y488280D02*
Y486951D01*
G01X1808900Y487428D02*
X1806451Y484980D01*
G01X1810050Y486951D02*
X1807018Y483919D01*
G01X1806451Y484980D02*
X1798209Y483340D01*
G01X1807018Y483919D02*
X1798323Y482190D01*
G01X1798209Y483340D02*
X1788817D01*
G01X1798323Y482190D02*
X1789294D01*
G01X1788817Y483340D02*
X1786300Y480823D01*
G01X1789294Y482190D02*
X1787450Y480346D01*
G01X1786300Y480823D02*
Y478883D01*
G01X1787450Y480346D02*
Y478654D01*
G01X1786300Y478883D02*
X1783727Y472675D01*
G01X1787450Y478654D02*
X1784703Y472023D01*
G01X1783727Y472675D02*
X1781352Y470300D01*
G01X1784703Y472023D02*
X1784540Y471860D01*
G01X1783727Y472675D02*
X1781352Y470300D01*
G01X1784540Y471861D02*
X1781829Y469150D01*
G01X1785077Y465200D02*
X1788684Y466695D01*
G01D02*
X1789664Y467675D01*
G01X1791538Y469549D02*
X1792493Y470504D01*
G01X1794367Y472378D02*
X1799661Y477672D01*
G01X1801534Y479545D02*
X1802489Y480500D01*
G01X1789336Y465719D02*
X1803141Y479524D01*
G01X1802489Y480500D02*
X1812386Y484600D01*
G01X1803141Y479524D02*
X1812615Y483450D01*
G01X1812386Y484600D02*
X1816077D01*
G01X1812615Y483450D02*
X1816306D01*
G01X1816077Y484600D02*
X1820212Y486314D01*
G01X1816306Y483450D02*
X1820864Y485338D01*
G01X1820212Y486314D02*
X1821050Y487150D01*
G01X1820864Y485338D02*
X1822200Y486673D01*
G01X1821050Y487150D02*
Y488480D01*
G01X1822200Y486673D02*
Y488300D01*
G01X1777471Y536644D02*
X1784127Y543300D01*
G01D02*
X1785527D01*
G01X1776994Y537794D02*
X1783650Y544450D01*
G01X1784127Y543300D02*
X1785527D01*
G01X1783650Y544450D02*
X1785050D01*
G01X1785527Y543300D02*
X1792250Y550023D01*
G01X1785050Y544450D02*
X1791100Y550500D01*
G01X1792250Y550023D02*
Y554023D01*
G01X1791100Y550500D02*
Y554500D01*
G01X1792250Y554023D02*
X1792977Y554750D01*
G01X1791100Y554500D02*
X1792500Y555900D01*
G01X1792977Y554750D02*
X1796450D01*
G01X1799100D02*
X1800450D01*
G01X1792500Y555900D02*
X1799973D01*
G01X1800450Y554750D02*
X1802972Y557272D01*
G01X1804845Y559145D02*
X1805800Y560100D01*
G01X1799973Y555900D02*
X1804650Y560577D01*
G01X1805800Y560100D02*
Y561450D01*
G01Y564100D02*
Y566600D01*
G01Y569250D02*
Y570600D01*
G01X1804650Y560577D02*
Y571077D01*
G01X1805800Y570600D02*
X1806250Y571050D01*
G01X1804650Y571077D02*
X1805773Y572200D01*
G01X1806250Y571050D02*
X1807132D01*
G01X1805773Y572200D02*
X1807132D01*
G01X1776994Y537794D02*
X1783650Y544450D01*
G01X1777471Y536644D02*
X1784127Y543300D01*
G01X1776994Y537794D02*
X1783650Y544450D01*
G01D02*
X1785050D01*
G01X1784127Y543300D02*
X1785527D01*
G01X1785050Y544450D02*
X1791100Y550500D01*
G01X1785527Y543300D02*
X1792250Y550023D01*
G01X1791100Y550500D02*
Y554500D01*
G01X1792250Y550023D02*
Y554023D01*
G01X1791100Y554500D02*
X1792500Y555900D01*
G01X1792250Y554023D02*
X1792977Y554750D01*
G01X1792500Y555900D02*
X1799973D01*
G01X1792977Y554750D02*
X1796450D01*
G01X1792500Y555900D02*
X1799973D01*
G01X1799100Y554750D02*
X1800450D01*
G01X1799973Y555900D02*
X1804650Y560577D01*
G01X1800450Y554750D02*
X1802972Y557272D01*
G01X1799973Y555900D02*
X1804650Y560577D01*
G01X1804845Y559145D02*
X1805800Y560100D01*
G01X1804650Y560577D02*
Y571077D01*
G01X1805800Y560100D02*
Y561450D01*
G01X1804650Y560577D02*
Y571077D01*
G01X1805800Y564100D02*
Y566600D01*
G01X1804650Y560577D02*
Y571077D01*
G01X1805800Y569250D02*
Y570600D01*
G01X1804650Y571077D02*
X1805773Y572200D01*
G01X1805800Y570600D02*
X1806250Y571050D01*
G01X1805773Y572200D02*
X1807132D01*
G01X1806250Y571050D02*
X1807132D01*
G01X1912332Y241401D02*
X1891611D01*
G01X1911855Y240251D02*
X1891134D01*
G01X1891611Y241401D02*
X1867844Y265168D01*
G01X1891134Y240251D02*
X1882701Y248684D01*
G01X1891611Y241401D02*
X1867844Y265168D01*
G01X1882701Y248684D02*
X1881782D01*
G01X1891611Y241401D02*
X1867844Y265168D01*
G01X1880827Y250558D02*
X1879872Y251513D01*
G01X1891611Y241401D02*
X1867844Y265168D01*
G01X1879872Y251513D02*
X1878953D01*
G01X1891611Y241401D02*
X1867844Y265168D01*
G01X1877999Y253386D02*
X1877044Y254341D01*
G01X1891611Y241401D02*
X1867844Y265168D01*
G01X1877044Y254341D02*
X1876125D01*
G01X1891611Y241401D02*
X1867844Y265168D01*
G01X1875170Y256215D02*
X1874216Y257169D01*
G01X1891611Y241401D02*
X1867844Y265168D01*
G01X1874216Y257169D02*
X1873296D01*
G01X1891611Y241401D02*
X1867844Y265168D01*
G01X1872342Y259043D02*
X1867367Y264018D01*
G01X1911855Y240251D02*
X1891134D01*
G01X1912332Y241401D02*
X1891611D01*
G01X1891134Y240251D02*
X1882701Y248684D01*
G01D02*
X1881782D01*
G01X1880827Y250558D02*
X1879872Y251513D01*
G01D02*
X1878953D01*
G01X1877999Y253386D02*
X1877044Y254341D01*
G01D02*
X1876125D01*
G01X1875170Y256215D02*
X1874216Y257169D01*
G01D02*
X1873296D01*
G01X1872342Y259043D02*
X1867367Y264018D01*
G01X1891611Y241401D02*
X1867844Y265168D01*
G01X1901429Y238301D02*
X1889338D01*
G01X1900952Y237151D02*
X1888861D01*
G01X1889338Y238301D02*
X1865571Y262068D01*
G01X1888861Y237151D02*
X1882508Y243504D01*
G01X1889338Y238301D02*
X1865571Y262068D01*
G01X1882508Y243504D02*
X1881589D01*
G01X1889338Y238301D02*
X1865571Y262068D01*
G01X1880634Y245378D02*
X1879680Y246332D01*
G01X1889338Y238301D02*
X1865571Y262068D01*
G01X1879680Y246332D02*
X1878761D01*
G01X1889338Y238301D02*
X1865571Y262068D01*
G01X1877806Y248206D02*
X1876851Y249161D01*
G01X1889338Y238301D02*
X1865571Y262068D01*
G01X1876851Y249161D02*
X1875932D01*
G01X1889338Y238301D02*
X1865571Y262068D01*
G01X1874978Y251034D02*
X1874023Y251989D01*
G01X1889338Y238301D02*
X1865571Y262068D01*
G01X1874023Y251989D02*
X1873104D01*
G01X1889338Y238301D02*
X1865571Y262068D01*
G01X1872149Y253863D02*
X1865094Y260918D01*
G01X1900952Y237151D02*
X1888861D01*
G01X1901429Y238301D02*
X1889338D01*
G01X1888861Y237151D02*
X1882508Y243504D01*
G01D02*
X1881589D01*
G01X1880634Y245378D02*
X1879680Y246332D01*
G01D02*
X1878761D01*
G01X1877806Y248206D02*
X1876851Y249161D01*
G01D02*
X1875932D01*
G01X1874978Y251034D02*
X1874023Y251989D01*
G01D02*
X1873104D01*
G01X1872149Y253863D02*
X1865094Y260918D01*
G01X1889338Y238301D02*
X1865571Y262068D01*
G01X1909948Y206050D02*
X1911877D01*
G01X1909878Y207200D02*
X1911400D01*
G01X1911877Y206050D02*
X1914380Y208553D01*
G01X1911400Y207200D02*
X1913230Y209030D01*
G01X1914380Y208553D02*
Y225885D01*
G01X1913230Y209030D02*
Y226362D01*
G01X1909878Y207200D02*
X1911400D01*
G01X1909948Y206050D02*
X1911877D01*
G01X1911400Y207200D02*
X1913230Y209030D01*
G01X1911877Y206050D02*
X1914380Y208553D01*
G01X1913230Y209030D02*
Y226362D01*
G01X1914380Y208553D02*
Y225885D01*
G01X1905389Y202671D02*
X1906265D01*
G01X1905116Y203821D02*
X1905788D01*
G01X1906265Y202671D02*
X1907388Y203794D01*
G01X1905788Y203821D02*
X1906238Y204271D01*
G01X1907388Y203794D02*
Y232342D01*
G01X1906238Y204271D02*
Y231865D01*
G01X1905116Y203821D02*
X1905788D01*
G01X1905389Y202671D02*
X1906265D01*
G01X1905788Y203821D02*
X1906238Y204271D01*
G01X1906265Y202671D02*
X1907388Y203794D01*
G01X1906238Y204271D02*
Y231865D01*
G01X1907388Y203794D02*
Y232342D01*
G01X1914380Y225885D02*
X1919535Y231040D01*
G01X1913230Y226362D02*
X1918385Y231517D01*
G01X1919535Y231040D02*
Y234198D01*
G01X1918385Y231517D02*
Y233721D01*
G01X1919535Y234198D02*
X1912332Y241401D01*
G01X1918385Y233721D02*
X1911855Y240251D01*
G01X1913230Y226362D02*
X1918385Y231517D01*
G01X1914380Y225885D02*
X1919535Y231040D01*
G01X1918385Y231517D02*
Y233721D01*
G01X1919535Y231040D02*
Y234198D01*
G01X1918385Y233721D02*
X1911855Y240251D01*
G01X1919535Y234198D02*
X1912332Y241401D01*
G01X1907388Y232342D02*
X1901429Y238301D01*
G01X1906238Y231865D02*
X1900952Y237151D01*
G01X1906238Y231865D02*
X1900952Y237151D01*
G01X1907388Y232342D02*
X1901429Y238301D01*
G54D13*
G01X141880Y30540D02*
X145072Y33732D01*
G01X137599Y32580D02*
X138115D01*
G01X137576Y31520D02*
X138558D01*
G01X138115Y32580D02*
X138826Y33291D01*
G01X138558Y31520D02*
X139886Y32848D01*
G01X137576Y31520D02*
X138558D01*
G01X137599Y32580D02*
X138115D01*
G01X138558Y31520D02*
X139886Y32848D01*
G01X138115Y32580D02*
X138826Y33291D01*
G01X141880Y30540D02*
X145072Y33732D01*
G01X137599Y32580D02*
X138115D01*
G01X137576Y31520D02*
X138558D01*
G01X138115Y32580D02*
X138826Y33291D01*
G01X138558Y31520D02*
X139886Y32848D01*
G01X141880Y30540D02*
X145072Y33732D01*
G01X141880Y30540D02*
X145072Y33732D01*
G01X141880Y30540D02*
X145072Y33732D01*
G01X141880Y30540D02*
X145072Y33732D01*
G01X137576Y31520D02*
X138558D01*
G01X137599Y32580D02*
X138115D01*
G01X138558Y31520D02*
X139886Y32848D01*
G01X138115Y32580D02*
X138826Y33291D01*
G01X140175Y51419D02*
Y59616D01*
G01X141235Y57457D02*
Y59176D01*
G01X140175Y59616D02*
X143900Y63341D01*
G01X141235Y59176D02*
X144960Y62901D01*
G01X143900Y63341D02*
Y97690D01*
G01X144960Y62901D02*
Y97250D01*
G01X141880Y33149D02*
X142989D01*
G01D02*
X144012Y34172D01*
G01D02*
Y36793D01*
G01Y40707D02*
Y42080D01*
G01Y45906D02*
Y48681D01*
G01X145072Y33732D02*
Y49122D01*
G01X144012Y48681D02*
X142978Y49715D01*
G01D02*
X141880D01*
G01X145072Y49122D02*
X141880Y52314D01*
G01X134926Y51354D02*
Y59928D01*
G01X135986Y57420D02*
Y59488D01*
G01X134926Y59928D02*
X138800Y63802D01*
G01X135986Y59488D02*
X139860Y63362D01*
G01X138800Y63802D02*
Y109020D01*
G01X139860Y63362D02*
Y77580D01*
G01X138800Y63802D02*
Y109020D01*
G01X139860Y79820D02*
Y80580D01*
G01X138800Y63802D02*
Y109020D01*
G01X139860Y82820D02*
Y93480D01*
G01X138800Y63802D02*
Y109020D01*
G01X138826Y33291D02*
Y36580D01*
G01Y40920D02*
Y41880D01*
G01Y46020D02*
Y48553D01*
G01X139886Y32848D02*
Y48994D01*
G01X138826Y48553D02*
X137879Y49500D01*
G01X139886Y48994D02*
X136780Y52100D01*
G01X135986Y57420D02*
Y59488D01*
G01X134926Y51354D02*
Y59928D01*
G01X135986Y59488D02*
X139860Y63362D01*
G01X134926Y59928D02*
X138800Y63802D01*
G01X139860Y63362D02*
Y77580D01*
G01Y79820D02*
Y80580D01*
G01Y82820D02*
Y93480D01*
G01X138800Y63802D02*
Y109020D01*
G01X139886Y32848D02*
Y48994D01*
G01X138826Y33291D02*
Y36580D01*
G01X139886Y32848D02*
Y48994D01*
G01X138826Y40920D02*
Y41880D01*
G01X139886Y32848D02*
Y48994D01*
G01X138826Y46020D02*
Y48553D01*
G01X139886Y48994D02*
X136780Y52100D01*
G01X138826Y48553D02*
X137879Y49500D01*
G01X140175Y51419D02*
Y59616D01*
G01X141235Y57457D02*
Y59176D01*
G01X140175Y59616D02*
X143900Y63341D01*
G01X141235Y59176D02*
X144960Y62901D01*
G01X143900Y63341D02*
Y97690D01*
G01X144960Y62901D02*
Y97250D01*
G01X141880Y33149D02*
X142989D01*
G01D02*
X144012Y34172D01*
G01D02*
Y36793D01*
G01Y40707D02*
Y42080D01*
G01Y45906D02*
Y48681D01*
G01X145072Y33732D02*
Y49122D01*
G01X144012Y48681D02*
X142978Y49715D01*
G01D02*
X141880D01*
G01X145072Y49122D02*
X141880Y52314D01*
G01X134926Y51354D02*
Y59928D01*
G01X135986Y57420D02*
Y59488D01*
G01X134926Y59928D02*
X138800Y63802D01*
G01X135986Y59488D02*
X139860Y63362D01*
G01X138800Y63802D02*
Y109020D01*
G01X139860Y63362D02*
Y77580D01*
G01X138800Y63802D02*
Y109020D01*
G01X139860Y79820D02*
Y80580D01*
G01X138800Y63802D02*
Y109020D01*
G01X139860Y82820D02*
Y93480D01*
G01X138800Y63802D02*
Y109020D01*
G01X138826Y33291D02*
Y36580D01*
G01Y40920D02*
Y41880D01*
G01Y46020D02*
Y48553D01*
G01X139886Y32848D02*
Y48994D01*
G01X138826Y48553D02*
X137879Y49500D01*
G01X139886Y48994D02*
X136780Y52100D01*
G01X141880Y33149D02*
X142989D01*
G01D02*
X144012Y34172D01*
G01X145072Y33732D02*
Y49122D01*
G01X144012Y34172D02*
Y36793D01*
G01X145072Y33732D02*
Y49122D01*
G01X144012Y40707D02*
Y42080D01*
G01X145072Y33732D02*
Y49122D01*
G01X144012Y45906D02*
Y48681D01*
G01X145072Y49122D02*
X141880Y52314D01*
G01X144012Y48681D02*
X142978Y49715D01*
G01X145072Y49122D02*
X141880Y52314D01*
G01X142978Y49715D02*
X141880D01*
G01X141235Y57457D02*
Y59176D01*
G01X140175Y51419D02*
Y59616D01*
G01X141235Y59176D02*
X144960Y62901D01*
G01X140175Y59616D02*
X143900Y63341D01*
G01X144960Y62901D02*
Y97250D01*
G01X143900Y63341D02*
Y97690D01*
G01X141880Y33149D02*
X142989D01*
G01D02*
X144012Y34172D01*
G01X145072Y33732D02*
Y49122D01*
G01X144012Y34172D02*
Y36793D01*
G01X145072Y33732D02*
Y49122D01*
G01X144012Y40707D02*
Y42080D01*
G01X145072Y33732D02*
Y49122D01*
G01X144012Y45906D02*
Y48681D01*
G01X145072Y49122D02*
X141880Y52314D01*
G01X144012Y48681D02*
X142978Y49715D01*
G01X145072Y49122D02*
X141880Y52314D01*
G01X142978Y49715D02*
X141880D01*
G01X141235Y57457D02*
Y59176D01*
G01X140175Y51419D02*
Y59616D01*
G01X141235Y59176D02*
X144960Y62901D01*
G01X140175Y59616D02*
X143900Y63341D01*
G01X144960Y62901D02*
Y97250D01*
G01X143900Y63341D02*
Y97690D01*
G01X135986Y57420D02*
Y59488D01*
G01X134926Y51354D02*
Y59928D01*
G01X135986Y59488D02*
X139860Y63362D01*
G01X134926Y59928D02*
X138800Y63802D01*
G01X139860Y63362D02*
Y77580D01*
G01Y79820D02*
Y80580D01*
G01Y82820D02*
Y93480D01*
G01X138800Y63802D02*
Y109020D01*
G01X139886Y32848D02*
Y48994D01*
G01X138826Y33291D02*
Y36580D01*
G01X139886Y32848D02*
Y48994D01*
G01X138826Y40920D02*
Y41880D01*
G01X139886Y32848D02*
Y48994D01*
G01X138826Y46020D02*
Y48553D01*
G01X139886Y48994D02*
X136780Y52100D01*
G01X138826Y48553D02*
X137879Y49500D01*
G01X143900Y97690D02*
X145582Y99372D01*
G01X144960Y97250D02*
X146642Y98932D01*
G01X145582Y99372D02*
Y101960D01*
G01X146642Y98932D02*
Y102400D01*
G01X145582Y101960D02*
X143900Y103642D01*
G01X146642Y102400D02*
X144960Y104082D01*
G01X143900Y103642D02*
Y109040D01*
G01X144960Y104082D02*
Y108600D01*
G01X143900Y109040D02*
X145282Y110422D01*
G01X144960Y108600D02*
X146342Y109982D01*
G01X145282Y110422D02*
Y114128D01*
G01X146342Y109982D02*
Y114568D01*
G01X145282Y114128D02*
X143900Y115510D01*
G01X146342Y114568D02*
X144960Y115950D01*
G01X143900Y115510D02*
Y133607D01*
G01X144960Y115950D02*
Y134047D01*
G01X143900Y133607D02*
X143028Y134479D01*
G01X144960Y134047D02*
X143468Y135539D01*
G01X143028Y134479D02*
X141501D01*
G01X143468Y135539D02*
X141944D01*
G01X141501Y134479D02*
X140012Y135968D01*
G01X141944Y135539D02*
X141072Y136411D01*
G01X140012Y135968D02*
Y139350D01*
G01X141072Y136411D02*
Y138907D01*
G01X140012Y139350D02*
X141501Y140839D01*
G01X141072Y138907D02*
X141944Y139779D01*
G01X141501Y140839D02*
X143028D01*
G01X141944Y139779D02*
X143471D01*
G01X143028Y140839D02*
X143900Y141711D01*
G01X143471Y139779D02*
X144960Y141268D01*
G01X143900Y141711D02*
Y142661D01*
G01X144960Y141268D02*
Y143101D01*
G01X143900Y142661D02*
X141645Y144916D01*
G01X144960Y143101D02*
X142705Y145356D01*
G01X141645Y144916D02*
Y146502D01*
G01X142705Y145356D02*
Y146062D01*
G01X141645Y146502D02*
X143072Y147928D01*
G01X142705Y146062D02*
X143822Y147178D01*
G01X143072Y147928D02*
X145318Y150175D01*
G01X143822Y147178D02*
X145758Y149115D01*
G01X145318Y150175D02*
X153617D01*
G01X145758Y149115D02*
X154057D01*
G01X153617Y150175D02*
X159582Y156140D01*
G01X154057Y149115D02*
X160642Y155700D01*
G01X159582Y156140D02*
Y163540D01*
G01X160642Y155700D02*
Y163100D01*
G01X139860Y95720D02*
Y109463D01*
G01X138800Y109020D02*
X136612Y111208D01*
G01X139860Y109463D02*
X137672Y111651D01*
G01X136612Y111208D02*
Y113924D01*
G01X137672Y111651D02*
Y113481D01*
G01X136612Y113924D02*
X140012Y117324D01*
G01X137672Y113481D02*
X141072Y116881D01*
G01X140012Y117324D02*
Y119320D01*
G01X141072Y116881D02*
Y119763D01*
G01X140012Y119320D02*
X138840Y120492D01*
G01D02*
X137701D01*
G01X141072Y119763D02*
X139283Y121552D01*
G01X138840Y120492D02*
X137701D01*
G01D02*
X136212Y121981D01*
G01X139283Y121552D02*
X138144D01*
G01X137701Y120492D02*
X136212Y121981D01*
G01X138144Y121552D02*
X137272Y122424D01*
G01X136212Y121981D02*
Y125363D01*
G01X137272Y122424D02*
Y124920D01*
G01X136212Y125363D02*
X137701Y126852D01*
G01X137272Y124920D02*
X138144Y125792D01*
G01X136212Y125363D02*
X137701Y126852D01*
G01D02*
X138840D01*
G01X138144Y125792D02*
X139283D01*
G01X137701Y126852D02*
X138840D01*
G01D02*
X139712Y127724D01*
G01X139283Y125792D02*
X140772Y127281D01*
G01X139712Y127724D02*
Y130223D01*
G01X140772Y127281D02*
Y130663D01*
G01X139712Y130223D02*
X136212Y133723D01*
G01X140772Y130663D02*
X137272Y134163D01*
G01X136212Y133723D02*
Y145769D01*
G01X137272Y134163D02*
Y145329D01*
G01X136212Y145769D02*
X140722Y150278D01*
G01X137272Y145329D02*
X141472Y149528D01*
G01X140722Y150278D02*
X144953Y154510D01*
G01X141472Y149528D02*
X145393Y153450D01*
G01X144953Y154510D02*
X152653D01*
G01X145393Y153450D02*
X153093D01*
G01X152653Y154510D02*
X155258Y157115D01*
G01X153093Y153450D02*
X156318Y156675D01*
G01X139860Y95720D02*
Y109463D01*
G01D02*
X137672Y111651D01*
G01X138800Y109020D02*
X136612Y111208D01*
G01X137672Y111651D02*
Y113481D01*
G01X136612Y111208D02*
Y113924D01*
G01X137672Y113481D02*
X141072Y116881D01*
G01X136612Y113924D02*
X140012Y117324D01*
G01X141072Y116881D02*
Y119763D01*
G01X140012Y117324D02*
Y119320D01*
G01X141072Y119763D02*
X139283Y121552D01*
G01X140012Y119320D02*
X138840Y120492D01*
G01X141072Y119763D02*
X139283Y121552D01*
G01D02*
X138144D01*
G01X138840Y120492D02*
X137701D01*
G01X139283Y121552D02*
X138144D01*
G01D02*
X137272Y122424D01*
G01X137701Y120492D02*
X136212Y121981D01*
G01X137272Y122424D02*
Y124920D01*
G01X136212Y121981D02*
Y125363D01*
G01X137272Y124920D02*
X138144Y125792D01*
G01D02*
X139283D01*
G01X136212Y125363D02*
X137701Y126852D01*
G01X138144Y125792D02*
X139283D01*
G01D02*
X140772Y127281D01*
G01X137701Y126852D02*
X138840D01*
G01X139283Y125792D02*
X140772Y127281D01*
G01X138840Y126852D02*
X139712Y127724D01*
G01X140772Y127281D02*
Y130663D01*
G01X139712Y127724D02*
Y130223D01*
G01X140772Y130663D02*
X137272Y134163D01*
G01X139712Y130223D02*
X136212Y133723D01*
G01X137272Y134163D02*
Y145329D01*
G01X136212Y133723D02*
Y145769D01*
G01X137272Y145329D02*
X141472Y149528D01*
G01X136212Y145769D02*
X140722Y150278D01*
G01X141472Y149528D02*
X145393Y153450D01*
G01X140722Y150278D02*
X144953Y154510D01*
G01X145393Y153450D02*
X153093D01*
G01X144953Y154510D02*
X152653D01*
G01X153093Y153450D02*
X156318Y156675D01*
G01X152653Y154510D02*
X155258Y157115D01*
G01X143900Y97690D02*
X145582Y99372D01*
G01X144960Y97250D02*
X146642Y98932D01*
G01X145582Y99372D02*
Y101960D01*
G01X146642Y98932D02*
Y102400D01*
G01X145582Y101960D02*
X143900Y103642D01*
G01X146642Y102400D02*
X144960Y104082D01*
G01X143900Y103642D02*
Y109040D01*
G01X144960Y104082D02*
Y108600D01*
G01X143900Y109040D02*
X145282Y110422D01*
G01X144960Y108600D02*
X146342Y109982D01*
G01X145282Y110422D02*
Y114128D01*
G01X146342Y109982D02*
Y114568D01*
G01X145282Y114128D02*
X143900Y115510D01*
G01X146342Y114568D02*
X144960Y115950D01*
G01X143900Y115510D02*
Y133607D01*
G01X144960Y115950D02*
Y134047D01*
G01X143900Y133607D02*
X143028Y134479D01*
G01X144960Y134047D02*
X143468Y135539D01*
G01X143028Y134479D02*
X141501D01*
G01X143468Y135539D02*
X141944D01*
G01X141501Y134479D02*
X140012Y135968D01*
G01X141944Y135539D02*
X141072Y136411D01*
G01X140012Y135968D02*
Y139350D01*
G01X141072Y136411D02*
Y138907D01*
G01X140012Y139350D02*
X141501Y140839D01*
G01X141072Y138907D02*
X141944Y139779D01*
G01X141501Y140839D02*
X143028D01*
G01X141944Y139779D02*
X143471D01*
G01X143028Y140839D02*
X143900Y141711D01*
G01X143471Y139779D02*
X144960Y141268D01*
G01X143900Y141711D02*
Y142661D01*
G01X144960Y141268D02*
Y143101D01*
G01X143900Y142661D02*
X141645Y144916D01*
G01X144960Y143101D02*
X142705Y145356D01*
G01X141645Y144916D02*
Y146502D01*
G01X142705Y145356D02*
Y146062D01*
G01X141645Y146502D02*
X143072Y147928D01*
G01X142705Y146062D02*
X143822Y147178D01*
G01X143072Y147928D02*
X145318Y150175D01*
G01X143822Y147178D02*
X145758Y149115D01*
G01X145318Y150175D02*
X153617D01*
G01X145758Y149115D02*
X154057D01*
G01X153617Y150175D02*
X159582Y156140D01*
G01X154057Y149115D02*
X160642Y155700D01*
G01X159582Y156140D02*
Y163540D01*
G01X160642Y155700D02*
Y163100D01*
G01X139860Y95720D02*
Y109463D01*
G01X138800Y109020D02*
X136612Y111208D01*
G01X139860Y109463D02*
X137672Y111651D01*
G01X136612Y111208D02*
Y113924D01*
G01X137672Y111651D02*
Y113481D01*
G01X136612Y113924D02*
X140012Y117324D01*
G01X137672Y113481D02*
X141072Y116881D01*
G01X140012Y117324D02*
Y119320D01*
G01X141072Y116881D02*
Y119763D01*
G01X140012Y119320D02*
X138840Y120492D01*
G01D02*
X137701D01*
G01X141072Y119763D02*
X139283Y121552D01*
G01X138840Y120492D02*
X137701D01*
G01D02*
X136212Y121981D01*
G01X139283Y121552D02*
X138144D01*
G01X137701Y120492D02*
X136212Y121981D01*
G01X138144Y121552D02*
X137272Y122424D01*
G01X136212Y121981D02*
Y125363D01*
G01X137272Y122424D02*
Y124920D01*
G01X136212Y125363D02*
X137701Y126852D01*
G01X137272Y124920D02*
X138144Y125792D01*
G01X136212Y125363D02*
X137701Y126852D01*
G01D02*
X138840D01*
G01X138144Y125792D02*
X139283D01*
G01X137701Y126852D02*
X138840D01*
G01D02*
X139712Y127724D01*
G01X139283Y125792D02*
X140772Y127281D01*
G01X139712Y127724D02*
Y130223D01*
G01X140772Y127281D02*
Y130663D01*
G01X139712Y130223D02*
X136212Y133723D01*
G01X140772Y130663D02*
X137272Y134163D01*
G01X136212Y133723D02*
Y145769D01*
G01X137272Y134163D02*
Y145329D01*
G01X136212Y145769D02*
X140722Y150278D01*
G01X137272Y145329D02*
X141472Y149528D01*
G01X140722Y150278D02*
X144953Y154510D01*
G01X141472Y149528D02*
X145393Y153450D01*
G01X144953Y154510D02*
X152653D01*
G01X145393Y153450D02*
X153093D01*
G01X152653Y154510D02*
X155258Y157115D01*
G01X153093Y153450D02*
X156318Y156675D01*
G01X144960Y97250D02*
X146642Y98932D01*
G01X143900Y97690D02*
X145582Y99372D01*
G01X146642Y98932D02*
Y102400D01*
G01X145582Y99372D02*
Y101960D01*
G01X146642Y102400D02*
X144960Y104082D01*
G01X145582Y101960D02*
X143900Y103642D01*
G01X144960Y104082D02*
Y108600D01*
G01X143900Y103642D02*
Y109040D01*
G01X144960Y108600D02*
X146342Y109982D01*
G01X143900Y109040D02*
X145282Y110422D01*
G01X146342Y109982D02*
Y114568D01*
G01X145282Y110422D02*
Y114128D01*
G01X146342Y114568D02*
X144960Y115950D01*
G01X145282Y114128D02*
X143900Y115510D01*
G01X144960Y115950D02*
Y134047D01*
G01X143900Y115510D02*
Y133607D01*
G01X144960Y134047D02*
X143468Y135539D01*
G01X143900Y133607D02*
X143028Y134479D01*
G01X143468Y135539D02*
X141944D01*
G01X143028Y134479D02*
X141501D01*
G01X141944Y135539D02*
X141072Y136411D01*
G01X141501Y134479D02*
X140012Y135968D01*
G01X141072Y136411D02*
Y138907D01*
G01X140012Y135968D02*
Y139350D01*
G01X141072Y138907D02*
X141944Y139779D01*
G01X140012Y139350D02*
X141501Y140839D01*
G01X141944Y139779D02*
X143471D01*
G01X141501Y140839D02*
X143028D01*
G01X143471Y139779D02*
X144960Y141268D01*
G01X143028Y140839D02*
X143900Y141711D01*
G01X144960Y141268D02*
Y143101D01*
G01X143900Y141711D02*
Y142661D01*
G01X144960Y143101D02*
X142705Y145356D01*
G01X143900Y142661D02*
X141645Y144916D01*
G01X142705Y145356D02*
Y146062D01*
G01X141645Y144916D02*
Y146502D01*
G01X142705Y146062D02*
X143822Y147178D01*
G01X141645Y146502D02*
X143072Y147928D01*
G01X143822Y147178D02*
X145758Y149115D01*
G01X143072Y147928D02*
X145318Y150175D01*
G01X145758Y149115D02*
X154057D01*
G01X145318Y150175D02*
X153617D01*
G01X154057Y149115D02*
X160642Y155700D01*
G01X153617Y150175D02*
X159582Y156140D01*
G01X160642Y155700D02*
Y163100D01*
G01X159582Y156140D02*
Y163540D01*
G01X144960Y97250D02*
X146642Y98932D01*
G01X143900Y97690D02*
X145582Y99372D01*
G01X146642Y98932D02*
Y102400D01*
G01X145582Y99372D02*
Y101960D01*
G01X146642Y102400D02*
X144960Y104082D01*
G01X145582Y101960D02*
X143900Y103642D01*
G01X144960Y104082D02*
Y108600D01*
G01X143900Y103642D02*
Y109040D01*
G01X144960Y108600D02*
X146342Y109982D01*
G01X143900Y109040D02*
X145282Y110422D01*
G01X146342Y109982D02*
Y114568D01*
G01X145282Y110422D02*
Y114128D01*
G01X146342Y114568D02*
X144960Y115950D01*
G01X145282Y114128D02*
X143900Y115510D01*
G01X144960Y115950D02*
Y134047D01*
G01X143900Y115510D02*
Y133607D01*
G01X144960Y134047D02*
X143468Y135539D01*
G01X143900Y133607D02*
X143028Y134479D01*
G01X143468Y135539D02*
X141944D01*
G01X143028Y134479D02*
X141501D01*
G01X141944Y135539D02*
X141072Y136411D01*
G01X141501Y134479D02*
X140012Y135968D01*
G01X141072Y136411D02*
Y138907D01*
G01X140012Y135968D02*
Y139350D01*
G01X141072Y138907D02*
X141944Y139779D01*
G01X140012Y139350D02*
X141501Y140839D01*
G01X141944Y139779D02*
X143471D01*
G01X141501Y140839D02*
X143028D01*
G01X143471Y139779D02*
X144960Y141268D01*
G01X143028Y140839D02*
X143900Y141711D01*
G01X144960Y141268D02*
Y143101D01*
G01X143900Y141711D02*
Y142661D01*
G01X144960Y143101D02*
X142705Y145356D01*
G01X143900Y142661D02*
X141645Y144916D01*
G01X142705Y145356D02*
Y146062D01*
G01X141645Y144916D02*
Y146502D01*
G01X142705Y146062D02*
X143822Y147178D01*
G01X141645Y146502D02*
X143072Y147928D01*
G01X143822Y147178D02*
X145758Y149115D01*
G01X143072Y147928D02*
X145318Y150175D01*
G01X145758Y149115D02*
X154057D01*
G01X145318Y150175D02*
X153617D01*
G01X154057Y149115D02*
X160642Y155700D01*
G01X153617Y150175D02*
X159582Y156140D01*
G01X160642Y155700D02*
Y163100D01*
G01X159582Y156140D02*
Y163540D01*
G01X139860Y95720D02*
Y109463D01*
G01D02*
X137672Y111651D01*
G01X138800Y109020D02*
X136612Y111208D01*
G01X137672Y111651D02*
Y113481D01*
G01X136612Y111208D02*
Y113924D01*
G01X137672Y113481D02*
X141072Y116881D01*
G01X136612Y113924D02*
X140012Y117324D01*
G01X141072Y116881D02*
Y119763D01*
G01X140012Y117324D02*
Y119320D01*
G01X141072Y119763D02*
X139283Y121552D01*
G01X140012Y119320D02*
X138840Y120492D01*
G01X141072Y119763D02*
X139283Y121552D01*
G01D02*
X138144D01*
G01X138840Y120492D02*
X137701D01*
G01X139283Y121552D02*
X138144D01*
G01D02*
X137272Y122424D01*
G01X137701Y120492D02*
X136212Y121981D01*
G01X137272Y122424D02*
Y124920D01*
G01X136212Y121981D02*
Y125363D01*
G01X137272Y124920D02*
X138144Y125792D01*
G01D02*
X139283D01*
G01X136212Y125363D02*
X137701Y126852D01*
G01X138144Y125792D02*
X139283D01*
G01D02*
X140772Y127281D01*
G01X137701Y126852D02*
X138840D01*
G01X139283Y125792D02*
X140772Y127281D01*
G01X138840Y126852D02*
X139712Y127724D01*
G01X140772Y127281D02*
Y130663D01*
G01X139712Y127724D02*
Y130223D01*
G01X140772Y130663D02*
X137272Y134163D01*
G01X139712Y130223D02*
X136212Y133723D01*
G01X137272Y134163D02*
Y145329D01*
G01X136212Y133723D02*
Y145769D01*
G01X137272Y145329D02*
X141472Y149528D01*
G01X136212Y145769D02*
X140722Y150278D01*
G01X141472Y149528D02*
X145393Y153450D01*
G01X140722Y150278D02*
X144953Y154510D01*
G01X145393Y153450D02*
X153093D01*
G01X144953Y154510D02*
X152653D01*
G01X153093Y153450D02*
X156318Y156675D01*
G01X152653Y154510D02*
X155258Y157115D01*
G01X159582Y163540D02*
X215502Y219460D01*
G01X160642Y163100D02*
X215942Y218400D01*
G01X155258Y157115D02*
Y164815D01*
G01X156318Y156675D02*
Y164375D01*
G01X155258Y164815D02*
X213753Y223310D01*
G01X156318Y164375D02*
X214193Y222250D01*
G01X155258Y164815D02*
X213753Y223310D01*
G01X156318Y156675D02*
Y164375D01*
G01X155258Y157115D02*
Y164815D01*
G01X156318Y164375D02*
X214193Y222250D01*
G01X155258Y164815D02*
X213753Y223310D01*
G01X159582Y163540D02*
X215502Y219460D01*
G01X160642Y163100D02*
X215942Y218400D01*
G01X155258Y157115D02*
Y164815D01*
G01X156318Y156675D02*
Y164375D01*
G01X155258Y164815D02*
X213753Y223310D01*
G01X156318Y164375D02*
X214193Y222250D01*
G01X155258Y164815D02*
X213753Y223310D01*
G01X160642Y163100D02*
X215942Y218400D01*
G01X159582Y163540D02*
X215502Y219460D01*
G01X160642Y163100D02*
X215942Y218400D01*
G01X159582Y163540D02*
X215502Y219460D01*
G01X156318Y156675D02*
Y164375D01*
G01X155258Y157115D02*
Y164815D01*
G01X156318Y164375D02*
X214193Y222250D01*
G01X155258Y164815D02*
X213753Y223310D01*
G01X144008Y465308D02*
Y461856D01*
G01X142948Y465748D02*
Y461416D01*
G01X144008Y461856D02*
X153991Y451873D01*
G01X142948Y461416D02*
X152931Y451433D01*
G01X153991Y451873D02*
Y448569D01*
G01X152931Y451433D02*
Y448129D01*
G01X153991Y448569D02*
X169660Y432900D01*
G01X152931Y448129D02*
X169220Y431840D01*
G01D02*
X172552D01*
G01X135612Y465688D02*
Y463312D01*
G01X136672Y465248D02*
Y463752D01*
G01X135612Y463312D02*
X149081Y449843D01*
G01X136672Y463752D02*
X150141Y450283D01*
G01X149081Y449843D02*
Y446582D01*
G01X150141Y450283D02*
Y447022D01*
G01X149081Y446582D02*
X166923Y428740D01*
G01X150141Y447022D02*
X167363Y429800D01*
G01X166923Y428740D02*
X171451D01*
G01X167363Y429800D02*
X171891D01*
G01X142948Y465748D02*
Y461416D01*
G01X144008Y465308D02*
Y461856D01*
G01X142948Y461416D02*
X152931Y451433D01*
G01X144008Y461856D02*
X153991Y451873D01*
G01X152931Y451433D02*
Y448129D01*
G01X153991Y451873D02*
Y448569D01*
G01X152931Y448129D02*
X169220Y431840D01*
G01X153991Y448569D02*
X169660Y432900D01*
G01X169220Y431840D02*
X172552D01*
G01X136672Y465248D02*
Y463752D01*
G01X135612Y465688D02*
Y463312D01*
G01X136672Y463752D02*
X150141Y450283D01*
G01X135612Y463312D02*
X149081Y449843D01*
G01X150141Y450283D02*
Y447022D01*
G01X149081Y449843D02*
Y446582D01*
G01X150141Y447022D02*
X167363Y429800D01*
G01X149081Y446582D02*
X166923Y428740D01*
G01X167363Y429800D02*
X171891D01*
G01X166923Y428740D02*
X171451D01*
G01X144008Y465308D02*
Y461856D01*
G01X142948Y465748D02*
Y461416D01*
G01X144008Y461856D02*
X153991Y451873D01*
G01X142948Y461416D02*
X152931Y451433D01*
G01X153991Y451873D02*
Y448569D01*
G01X152931Y451433D02*
Y448129D01*
G01X153991Y448569D02*
X169660Y432900D01*
G01X152931Y448129D02*
X169220Y431840D01*
G01D02*
X172552D01*
G01X135612Y465688D02*
Y463312D01*
G01X136672Y465248D02*
Y463752D01*
G01X135612Y463312D02*
X149081Y449843D01*
G01X136672Y463752D02*
X150141Y450283D01*
G01X149081Y449843D02*
Y446582D01*
G01X150141Y450283D02*
Y447022D01*
G01X149081Y446582D02*
X166923Y428740D01*
G01X150141Y447022D02*
X167363Y429800D01*
G01X166923Y428740D02*
X171451D01*
G01X167363Y429800D02*
X171891D01*
G01X142948Y465748D02*
Y461416D01*
G01X144008Y465308D02*
Y461856D01*
G01X142948Y461416D02*
X152931Y451433D01*
G01X144008Y461856D02*
X153991Y451873D01*
G01X152931Y451433D02*
Y448129D01*
G01X153991Y451873D02*
Y448569D01*
G01X152931Y448129D02*
X169220Y431840D01*
G01X153991Y448569D02*
X169660Y432900D01*
G01X169220Y431840D02*
X172552D01*
G01X136672Y465248D02*
Y463752D01*
G01X135612Y465688D02*
Y463312D01*
G01X136672Y463752D02*
X150141Y450283D01*
G01X135612Y463312D02*
X149081Y449843D01*
G01X150141Y450283D02*
Y447022D01*
G01X149081Y449843D02*
Y446582D01*
G01X150141Y447022D02*
X167363Y429800D01*
G01X149081Y446582D02*
X166923Y428740D01*
G01X167363Y429800D02*
X171891D01*
G01X166923Y428740D02*
X171451D01*
G01X144960Y550270D02*
Y508136D01*
G01Y550270D02*
Y508136D01*
G01Y550270D02*
Y508136D01*
G01Y550270D02*
Y508136D01*
G01Y550270D02*
Y508136D01*
G01Y550270D02*
Y508136D01*
G01Y550270D02*
Y508136D01*
G01X143900Y525680D02*
Y524680D01*
G01X144960Y550270D02*
Y508136D01*
G01X143900Y522440D02*
Y521440D01*
G01X144960Y550270D02*
Y508136D01*
G01X143900Y519200D02*
Y508579D01*
G01X144960Y508136D02*
X140572Y503748D01*
G01X143900Y508579D02*
X142919Y507598D01*
G01X144960Y508136D02*
X140572Y503748D01*
G01X141334Y506013D02*
X139512Y504191D01*
G01X140572Y503748D02*
Y493749D01*
G01X139512Y504191D02*
Y493309D01*
G01X140572Y493749D02*
X141441Y492880D01*
G01X139512Y493309D02*
X141001Y491820D01*
G01X141441Y492880D02*
X145641D01*
G01X141001Y491820D02*
X145201D01*
G01X145641Y492880D02*
X146972Y491549D01*
G01X145201Y491820D02*
X145912Y491109D01*
G01X146972Y491549D02*
Y488290D01*
G01X145912Y491109D02*
Y488730D01*
G01X146972Y488290D02*
X145480Y486798D01*
G01X145912Y488730D02*
X145040Y487858D01*
G01X145480Y486798D02*
X141336D01*
G01X145040Y487858D02*
X140896D01*
G01X141336Y486798D02*
X140494Y485956D01*
G01X140896Y487858D02*
X139434Y486396D01*
G01X140494Y485956D02*
Y484254D01*
G01X139434Y486396D02*
Y483814D01*
G01X140494Y484254D02*
X141390Y483358D01*
G01X139434Y483814D02*
X140950Y482298D01*
G01X141390Y483358D02*
X145480D01*
G01X140950Y482298D02*
X145040D01*
G01X145480Y483358D02*
X146972Y481866D01*
G01X145040Y482298D02*
X145912Y481426D01*
G01X146972Y481866D02*
Y479287D01*
G01X145912Y481426D02*
Y479730D01*
G01X146972Y479287D02*
X145483Y477798D01*
G01X145912Y479730D02*
X145040Y478858D01*
G01X145483Y477798D02*
X141844D01*
G01X145040Y478858D02*
X141401D01*
G01X141844Y477798D02*
X140972Y476926D01*
G01X141401Y478858D02*
X139912Y477369D01*
G01X140972Y476926D02*
Y475230D01*
G01X139912Y477369D02*
Y474787D01*
G01X140972Y475230D02*
X141844Y474358D01*
G01X139912Y474787D02*
X141401Y473298D01*
G01X141844Y474358D02*
X145480D01*
G01X141401Y473298D02*
X145040D01*
G01X145480Y474358D02*
X146972Y472866D01*
G01X145040Y473298D02*
X145912Y472426D01*
G01X146972Y472866D02*
Y468272D01*
G01X145912Y472426D02*
Y468712D01*
G01X146972Y468272D02*
X144008Y465308D01*
G01X145912Y468712D02*
X142948Y465748D01*
G01X138800Y549461D02*
Y509473D01*
G01Y549461D02*
Y509473D01*
G01Y549461D02*
Y509473D01*
G01X139860Y541466D02*
Y509033D01*
G01X138800Y509473D02*
X135612Y506285D01*
G01X139860Y509033D02*
X136672Y505845D01*
G01X135612Y506285D02*
Y471896D01*
G01X136672Y505845D02*
Y472336D01*
G01X135612Y471896D02*
X137104Y470404D01*
G01X136672Y472336D02*
X137544Y471464D01*
G01X137104Y470404D02*
X139445D01*
G01X137544Y471464D02*
X139885D01*
G01X139445Y470404D02*
X140314Y469535D01*
G01X139885Y471464D02*
X141374Y469975D01*
G01X140314Y469535D02*
Y467836D01*
G01X141374Y469975D02*
Y467393D01*
G01X140314Y467836D02*
X139442Y466964D01*
G01X141374Y467393D02*
X139885Y465904D01*
G01X139442Y466964D02*
X136888D01*
G01X139885Y465904D02*
X137328D01*
G01X136888Y466964D02*
X135612Y465688D01*
G01X137328Y465904D02*
X136672Y465248D01*
G01X143900Y525680D02*
Y524680D01*
G01Y522440D02*
Y521440D01*
G01Y519200D02*
Y508579D01*
G01X144960Y550270D02*
Y508136D01*
G01X143900Y508579D02*
X142919Y507598D01*
G01X141334Y506013D02*
X139512Y504191D01*
G01X144960Y508136D02*
X140572Y503748D01*
G01X139512Y504191D02*
Y493309D01*
G01X140572Y503748D02*
Y493749D01*
G01X139512Y493309D02*
X141001Y491820D01*
G01X140572Y493749D02*
X141441Y492880D01*
G01X141001Y491820D02*
X145201D01*
G01X141441Y492880D02*
X145641D01*
G01X145201Y491820D02*
X145912Y491109D01*
G01X145641Y492880D02*
X146972Y491549D01*
G01X145912Y491109D02*
Y488730D01*
G01X146972Y491549D02*
Y488290D01*
G01X145912Y488730D02*
X145040Y487858D01*
G01X146972Y488290D02*
X145480Y486798D01*
G01X145040Y487858D02*
X140896D01*
G01X145480Y486798D02*
X141336D01*
G01X140896Y487858D02*
X139434Y486396D01*
G01X141336Y486798D02*
X140494Y485956D01*
G01X139434Y486396D02*
Y483814D01*
G01X140494Y485956D02*
Y484254D01*
G01X139434Y483814D02*
X140950Y482298D01*
G01X140494Y484254D02*
X141390Y483358D01*
G01X140950Y482298D02*
X145040D01*
G01X141390Y483358D02*
X145480D01*
G01X145040Y482298D02*
X145912Y481426D01*
G01X145480Y483358D02*
X146972Y481866D01*
G01X145912Y481426D02*
Y479730D01*
G01X146972Y481866D02*
Y479287D01*
G01X145912Y479730D02*
X145040Y478858D01*
G01X146972Y479287D02*
X145483Y477798D01*
G01X145040Y478858D02*
X141401D01*
G01X145483Y477798D02*
X141844D01*
G01X141401Y478858D02*
X139912Y477369D01*
G01X141844Y477798D02*
X140972Y476926D01*
G01X139912Y477369D02*
Y474787D01*
G01X140972Y476926D02*
Y475230D01*
G01X139912Y474787D02*
X141401Y473298D01*
G01X140972Y475230D02*
X141844Y474358D01*
G01X141401Y473298D02*
X145040D01*
G01X141844Y474358D02*
X145480D01*
G01X145040Y473298D02*
X145912Y472426D01*
G01X145480Y474358D02*
X146972Y472866D01*
G01X145912Y472426D02*
Y468712D01*
G01X146972Y472866D02*
Y468272D01*
G01X145912Y468712D02*
X142948Y465748D01*
G01X146972Y468272D02*
X144008Y465308D01*
G01X139860Y541466D02*
Y509033D01*
G01X138800Y549461D02*
Y509473D01*
G01X139860Y509033D02*
X136672Y505845D01*
G01X138800Y509473D02*
X135612Y506285D01*
G01X136672Y505845D02*
Y472336D01*
G01X135612Y506285D02*
Y471896D01*
G01X136672Y472336D02*
X137544Y471464D01*
G01X135612Y471896D02*
X137104Y470404D01*
G01X137544Y471464D02*
X139885D01*
G01X137104Y470404D02*
X139445D01*
G01X139885Y471464D02*
X141374Y469975D01*
G01X139445Y470404D02*
X140314Y469535D01*
G01X141374Y469975D02*
Y467393D01*
G01X140314Y469535D02*
Y467836D01*
G01X141374Y467393D02*
X139885Y465904D01*
G01X140314Y467836D02*
X139442Y466964D01*
G01X139885Y465904D02*
X137328D01*
G01X139442Y466964D02*
X136888D01*
G01X137328Y465904D02*
X136672Y465248D01*
G01X136888Y466964D02*
X135612Y465688D01*
G01X144960Y550270D02*
Y508136D01*
G01Y550270D02*
Y508136D01*
G01Y550270D02*
Y508136D01*
G01Y550270D02*
Y508136D01*
G01Y550270D02*
Y508136D01*
G01Y550270D02*
Y508136D01*
G01Y550270D02*
Y508136D01*
G01X143900Y525680D02*
Y524680D01*
G01X144960Y550270D02*
Y508136D01*
G01X143900Y522440D02*
Y521440D01*
G01X144960Y550270D02*
Y508136D01*
G01X143900Y519200D02*
Y508579D01*
G01X144960Y508136D02*
X140572Y503748D01*
G01X143900Y508579D02*
X142919Y507598D01*
G01X144960Y508136D02*
X140572Y503748D01*
G01X141334Y506013D02*
X139512Y504191D01*
G01X140572Y503748D02*
Y493749D01*
G01X139512Y504191D02*
Y493309D01*
G01X140572Y493749D02*
X141441Y492880D01*
G01X139512Y493309D02*
X141001Y491820D01*
G01X141441Y492880D02*
X145641D01*
G01X141001Y491820D02*
X145201D01*
G01X145641Y492880D02*
X146972Y491549D01*
G01X145201Y491820D02*
X145912Y491109D01*
G01X146972Y491549D02*
Y488290D01*
G01X145912Y491109D02*
Y488730D01*
G01X146972Y488290D02*
X145480Y486798D01*
G01X145912Y488730D02*
X145040Y487858D01*
G01X145480Y486798D02*
X141336D01*
G01X145040Y487858D02*
X140896D01*
G01X141336Y486798D02*
X140494Y485956D01*
G01X140896Y487858D02*
X139434Y486396D01*
G01X140494Y485956D02*
Y484254D01*
G01X139434Y486396D02*
Y483814D01*
G01X140494Y484254D02*
X141390Y483358D01*
G01X139434Y483814D02*
X140950Y482298D01*
G01X141390Y483358D02*
X145480D01*
G01X140950Y482298D02*
X145040D01*
G01X145480Y483358D02*
X146972Y481866D01*
G01X145040Y482298D02*
X145912Y481426D01*
G01X146972Y481866D02*
Y479287D01*
G01X145912Y481426D02*
Y479730D01*
G01X146972Y479287D02*
X145483Y477798D01*
G01X145912Y479730D02*
X145040Y478858D01*
G01X145483Y477798D02*
X141844D01*
G01X145040Y478858D02*
X141401D01*
G01X141844Y477798D02*
X140972Y476926D01*
G01X141401Y478858D02*
X139912Y477369D01*
G01X140972Y476926D02*
Y475230D01*
G01X139912Y477369D02*
Y474787D01*
G01X140972Y475230D02*
X141844Y474358D01*
G01X139912Y474787D02*
X141401Y473298D01*
G01X141844Y474358D02*
X145480D01*
G01X141401Y473298D02*
X145040D01*
G01X145480Y474358D02*
X146972Y472866D01*
G01X145040Y473298D02*
X145912Y472426D01*
G01X146972Y472866D02*
Y468272D01*
G01X145912Y472426D02*
Y468712D01*
G01X146972Y468272D02*
X144008Y465308D01*
G01X145912Y468712D02*
X142948Y465748D01*
G01X138800Y549461D02*
Y509473D01*
G01Y549461D02*
Y509473D01*
G01Y549461D02*
Y509473D01*
G01X139860Y541466D02*
Y509033D01*
G01X138800Y509473D02*
X135612Y506285D01*
G01X139860Y509033D02*
X136672Y505845D01*
G01X135612Y506285D02*
Y471896D01*
G01X136672Y505845D02*
Y472336D01*
G01X135612Y471896D02*
X137104Y470404D01*
G01X136672Y472336D02*
X137544Y471464D01*
G01X137104Y470404D02*
X139445D01*
G01X137544Y471464D02*
X139885D01*
G01X139445Y470404D02*
X140314Y469535D01*
G01X139885Y471464D02*
X141374Y469975D01*
G01X140314Y469535D02*
Y467836D01*
G01X141374Y469975D02*
Y467393D01*
G01X140314Y467836D02*
X139442Y466964D01*
G01X141374Y467393D02*
X139885Y465904D01*
G01X139442Y466964D02*
X136888D01*
G01X139885Y465904D02*
X137328D01*
G01X136888Y466964D02*
X135612Y465688D01*
G01X137328Y465904D02*
X136672Y465248D01*
G01X143900Y525680D02*
Y524680D01*
G01Y522440D02*
Y521440D01*
G01Y519200D02*
Y508579D01*
G01X144960Y550270D02*
Y508136D01*
G01X143900Y508579D02*
X142919Y507598D01*
G01X141334Y506013D02*
X139512Y504191D01*
G01X144960Y508136D02*
X140572Y503748D01*
G01X139512Y504191D02*
Y493309D01*
G01X140572Y503748D02*
Y493749D01*
G01X139512Y493309D02*
X141001Y491820D01*
G01X140572Y493749D02*
X141441Y492880D01*
G01X141001Y491820D02*
X145201D01*
G01X141441Y492880D02*
X145641D01*
G01X145201Y491820D02*
X145912Y491109D01*
G01X145641Y492880D02*
X146972Y491549D01*
G01X145912Y491109D02*
Y488730D01*
G01X146972Y491549D02*
Y488290D01*
G01X145912Y488730D02*
X145040Y487858D01*
G01X146972Y488290D02*
X145480Y486798D01*
G01X145040Y487858D02*
X140896D01*
G01X145480Y486798D02*
X141336D01*
G01X140896Y487858D02*
X139434Y486396D01*
G01X141336Y486798D02*
X140494Y485956D01*
G01X139434Y486396D02*
Y483814D01*
G01X140494Y485956D02*
Y484254D01*
G01X139434Y483814D02*
X140950Y482298D01*
G01X140494Y484254D02*
X141390Y483358D01*
G01X140950Y482298D02*
X145040D01*
G01X141390Y483358D02*
X145480D01*
G01X145040Y482298D02*
X145912Y481426D01*
G01X145480Y483358D02*
X146972Y481866D01*
G01X145912Y481426D02*
Y479730D01*
G01X146972Y481866D02*
Y479287D01*
G01X145912Y479730D02*
X145040Y478858D01*
G01X146972Y479287D02*
X145483Y477798D01*
G01X145040Y478858D02*
X141401D01*
G01X145483Y477798D02*
X141844D01*
G01X141401Y478858D02*
X139912Y477369D01*
G01X141844Y477798D02*
X140972Y476926D01*
G01X139912Y477369D02*
Y474787D01*
G01X140972Y476926D02*
Y475230D01*
G01X139912Y474787D02*
X141401Y473298D01*
G01X140972Y475230D02*
X141844Y474358D01*
G01X141401Y473298D02*
X145040D01*
G01X141844Y474358D02*
X145480D01*
G01X145040Y473298D02*
X145912Y472426D01*
G01X145480Y474358D02*
X146972Y472866D01*
G01X145912Y472426D02*
Y468712D01*
G01X146972Y472866D02*
Y468272D01*
G01X145912Y468712D02*
X142948Y465748D01*
G01X146972Y468272D02*
X144008Y465308D01*
G01X139860Y541466D02*
Y509033D01*
G01X138800Y549461D02*
Y509473D01*
G01X139860Y509033D02*
X136672Y505845D01*
G01X138800Y509473D02*
X135612Y506285D01*
G01X136672Y505845D02*
Y472336D01*
G01X135612Y506285D02*
Y471896D01*
G01X136672Y472336D02*
X137544Y471464D01*
G01X135612Y471896D02*
X137104Y470404D01*
G01X137544Y471464D02*
X139885D01*
G01X137104Y470404D02*
X139445D01*
G01X139885Y471464D02*
X141374Y469975D01*
G01X139445Y470404D02*
X140314Y469535D01*
G01X141374Y469975D02*
Y467393D01*
G01X140314Y469535D02*
Y467836D01*
G01X141374Y467393D02*
X139885Y465904D01*
G01X140314Y467836D02*
X139442Y466964D01*
G01X139885Y465904D02*
X137328D01*
G01X139442Y466964D02*
X136888D01*
G01X137328Y465904D02*
X136672Y465248D01*
G01X136888Y466964D02*
X135612Y465688D01*
G01X141076Y557700D02*
X140405Y558371D01*
G01X140175Y557100D02*
X139345Y557930D01*
G01X140405Y558371D02*
Y559648D01*
G01Y563138D02*
Y564029D01*
G01X139345Y557930D02*
Y564470D01*
G01X140405Y564029D02*
X141176Y564800D01*
G01X139345Y564470D02*
X140175Y565300D01*
G01X143900Y549659D02*
Y546920D01*
G01Y544680D02*
Y543680D01*
G01Y541440D02*
Y540440D01*
G01Y538200D02*
Y536424D01*
G01Y534424D02*
Y531267D01*
G01Y529293D02*
Y527920D01*
G01X134792Y552200D02*
Y570211D01*
G01X135852Y558090D02*
Y559460D01*
G01X134792Y552200D02*
Y570211D01*
G01X135852Y563140D02*
Y564560D01*
G01X139860Y550049D02*
Y546800D01*
G01Y544560D02*
Y543414D01*
G01X140175Y557100D02*
X139345Y557930D01*
G01X141076Y557700D02*
X140405Y558371D01*
G01X139345Y557930D02*
Y564470D01*
G01X140405Y558371D02*
Y559648D01*
G01X139345Y557930D02*
Y564470D01*
G01X140405Y563138D02*
Y564029D01*
G01X139345Y564470D02*
X140175Y565300D01*
G01X140405Y564029D02*
X141176Y564800D01*
G01X143900Y549659D02*
Y546920D01*
G01Y544680D02*
Y543680D01*
G01Y541440D02*
Y540440D01*
G01Y538200D02*
Y536424D01*
G01Y534424D02*
Y531267D01*
G01Y529293D02*
Y527920D01*
G01X135852Y558090D02*
Y559460D01*
G01Y563140D02*
Y564560D01*
G01X134792Y552200D02*
Y570211D01*
G01X139860Y550049D02*
Y546800D01*
G01Y544560D02*
Y543414D01*
G01X141076Y557700D02*
X140405Y558371D01*
G01X140175Y557100D02*
X139345Y557930D01*
G01X140405Y558371D02*
Y559648D01*
G01Y563138D02*
Y564029D01*
G01X139345Y557930D02*
Y564470D01*
G01X140405Y564029D02*
X141176Y564800D01*
G01X139345Y564470D02*
X140175Y565300D01*
G01X143900Y549659D02*
Y546920D01*
G01Y544680D02*
Y543680D01*
G01Y541440D02*
Y540440D01*
G01Y538200D02*
Y536424D01*
G01Y534424D02*
Y531267D01*
G01Y529293D02*
Y527920D01*
G01X134792Y552200D02*
Y570211D01*
G01X135852Y558090D02*
Y559460D01*
G01X134792Y552200D02*
Y570211D01*
G01X135852Y563140D02*
Y564560D01*
G01X139860Y550049D02*
Y546800D01*
G01Y544560D02*
Y543414D01*
G01X140175Y557100D02*
X139345Y557930D01*
G01X141076Y557700D02*
X140405Y558371D01*
G01X139345Y557930D02*
Y564470D01*
G01X140405Y558371D02*
Y559648D01*
G01X139345Y557930D02*
Y564470D01*
G01X140405Y563138D02*
Y564029D01*
G01X139345Y564470D02*
X140175Y565300D01*
G01X140405Y564029D02*
X141176Y564800D01*
G01X143900Y549659D02*
Y546920D01*
G01Y544680D02*
Y543680D01*
G01Y541440D02*
Y540440D01*
G01Y538200D02*
Y536424D01*
G01Y534424D02*
Y531267D01*
G01Y529293D02*
Y527920D01*
G01X135852Y558090D02*
Y559460D01*
G01Y563140D02*
Y564560D01*
G01X134792Y552200D02*
Y570211D01*
G01X139860Y550049D02*
Y546800D01*
G01Y544560D02*
Y543414D01*
G01X175637Y33291D02*
X174926Y32580D01*
G01X176697Y32848D02*
X175369Y31520D01*
G01X174926Y32580D02*
X174410D01*
G01X175369Y31520D02*
X174387D01*
G01X212448Y33291D02*
X211737Y32580D01*
G01X213508Y32848D02*
X212180Y31520D01*
G01X211737Y32580D02*
X211221D01*
G01X212180Y31520D02*
X211198D01*
G01X181883Y33732D02*
X178691Y30540D01*
G01X218694Y33732D02*
X215502Y30540D01*
G01X176697Y32848D02*
X175369Y31520D01*
G01X175637Y33291D02*
X174926Y32580D01*
G01X175369Y31520D02*
X174387D01*
G01X174926Y32580D02*
X174410D01*
G01X213508Y32848D02*
X212180Y31520D01*
G01X212448Y33291D02*
X211737Y32580D01*
G01X212180Y31520D02*
X211198D01*
G01X211737Y32580D02*
X211221D01*
G01X175637Y33291D02*
X174926Y32580D01*
G01X176697Y32848D02*
X175369Y31520D01*
G01X174926Y32580D02*
X174410D01*
G01X175369Y31520D02*
X174387D01*
G01X212448Y33291D02*
X211737Y32580D01*
G01X213508Y32848D02*
X212180Y31520D01*
G01X211737Y32580D02*
X211221D01*
G01X212180Y31520D02*
X211198D01*
G01X181883Y33732D02*
X178691Y30540D01*
G01X218694Y33732D02*
X215502Y30540D01*
G01X176697Y32848D02*
X175369Y31520D01*
G01X175637Y33291D02*
X174926Y32580D01*
G01X175369Y31520D02*
X174387D01*
G01X174926Y32580D02*
X174410D01*
G01X213508Y32848D02*
X212180Y31520D01*
G01X212448Y33291D02*
X211737Y32580D01*
G01X212180Y31520D02*
X211198D01*
G01X211737Y32580D02*
X211221D01*
G01X181883Y33732D02*
X178691Y30540D01*
G01X181883Y33732D02*
X178691Y30540D01*
G01X218694Y33732D02*
X215502Y30540D01*
G01X218694Y33732D02*
X215502Y30540D01*
G01X218694Y33732D02*
X215502Y30540D01*
G01X218694Y33732D02*
X215502Y30540D01*
G01X171737Y51354D02*
Y58931D01*
G01X172797Y57420D02*
Y58488D01*
G01X171737Y58931D02*
X175611Y62805D01*
G01X172797Y58488D02*
X173751Y59442D01*
G01X171737Y58931D02*
X175611Y62805D01*
G01X175342Y61033D02*
X176671Y62362D01*
G01X175611Y62805D02*
Y103488D01*
G01X176671Y62362D02*
Y74025D01*
G01X175611Y62805D02*
Y103488D01*
G01X176671Y76274D02*
Y78380D01*
G01X175611Y62805D02*
Y103488D01*
G01X176671Y80620D02*
Y93480D01*
G01X175611Y62805D02*
Y103488D01*
G01Y62805D02*
Y103488D01*
G01Y62805D02*
Y103488D01*
G01X174690Y49500D02*
X175637Y48553D01*
G01X173591Y52100D02*
X176697Y48994D01*
G01X175637Y48553D02*
Y46020D01*
G01Y41880D02*
Y40920D01*
G01Y36580D02*
Y33291D01*
G01X176697Y48994D02*
Y32848D01*
G01X212422Y115998D02*
Y63605D01*
G01Y115998D02*
Y63605D01*
G01Y115998D02*
Y63605D01*
G01Y115998D02*
Y63605D01*
G01Y115998D02*
Y63605D01*
G01X213482Y93980D02*
Y80275D01*
G01X212422Y115998D02*
Y63605D01*
G01X213482Y78026D02*
Y76524D01*
G01X212422Y115998D02*
Y63605D01*
G01X213482Y74275D02*
Y63162D01*
G01X212422Y63605D02*
X208548Y59731D01*
G01X213482Y63162D02*
X212153Y61833D01*
G01X212422Y63605D02*
X208548Y59731D01*
G01X210562Y60242D02*
X209608Y59288D01*
G01X208548Y59731D02*
Y51354D01*
G01X209608Y59288D02*
Y57420D01*
G01X211501Y49500D02*
X212448Y48553D01*
G01X210402Y52100D02*
X213508Y48994D01*
G01X212448Y48553D02*
Y46020D01*
G01Y41880D02*
Y40920D01*
G01Y36580D02*
Y33291D01*
G01X213508Y48994D02*
Y32848D01*
G01X177437Y58199D02*
Y59031D01*
G01X178497Y57720D02*
Y58588D01*
G01X177437Y59031D02*
X180711Y62305D01*
G01X178497Y58588D02*
X179471Y59562D01*
G01X180711Y62305D02*
Y93987D01*
G01X181771Y63934D02*
Y74580D01*
G01X180711Y62305D02*
Y93987D01*
G01X181771Y76820D02*
Y77580D01*
G01X180711Y62305D02*
Y93987D01*
G01X181771Y79820D02*
Y93547D01*
G01X180711Y93987D02*
X181812Y95088D01*
G01X181771Y93547D02*
X182872Y94648D01*
G01X179789Y49715D02*
X180823Y48681D01*
G01X178691Y52314D02*
X181883Y49122D01*
G01X180823Y48681D02*
Y45906D01*
G01Y42080D02*
Y40707D01*
G01Y36793D02*
Y34172D01*
G01X181883Y49122D02*
Y33732D01*
G01X180823Y34172D02*
X179800Y33149D01*
G01X217522Y115701D02*
Y62305D01*
G01X218582Y115258D02*
Y61862D01*
G01X217522Y62305D02*
X214248Y59031D01*
G01X218582Y61862D02*
X215308Y58588D01*
G01X214248Y59031D02*
Y58199D01*
G01X215308Y58588D02*
Y57684D01*
G01X215502Y49715D02*
X216600D01*
G01D02*
X217634Y48681D01*
G01X215502Y52314D02*
X218694Y49122D01*
G01X217634Y48681D02*
Y45906D01*
G01Y42080D02*
Y40707D01*
G01Y36793D02*
Y34172D01*
G01X218694Y49122D02*
Y33732D01*
G01X217634Y34172D02*
X216611Y33149D01*
G01D02*
X215502D01*
G01X172797Y57420D02*
Y58488D01*
G01X171737Y51354D02*
Y58931D01*
G01X172797Y58488D02*
X173751Y59442D01*
G01X175342Y61033D02*
X176671Y62362D01*
G01X171737Y58931D02*
X175611Y62805D01*
G01X176671Y62362D02*
Y74025D01*
G01Y76274D02*
Y78380D01*
G01Y80620D02*
Y93480D01*
G01X175611Y62805D02*
Y103488D01*
G01X173591Y52100D02*
X176697Y48994D01*
G01X174690Y49500D02*
X175637Y48553D01*
G01X176697Y48994D02*
Y32848D01*
G01X175637Y48553D02*
Y46020D01*
G01X176697Y48994D02*
Y32848D01*
G01X175637Y41880D02*
Y40920D01*
G01X176697Y48994D02*
Y32848D01*
G01X175637Y36580D02*
Y33291D01*
G01X213482Y93980D02*
Y80275D01*
G01Y78026D02*
Y76524D01*
G01Y74275D02*
Y63162D01*
G01X212422Y115998D02*
Y63605D01*
G01X213482Y63162D02*
X212153Y61833D01*
G01X210562Y60242D02*
X209608Y59288D01*
G01X212422Y63605D02*
X208548Y59731D01*
G01X209608Y59288D02*
Y57420D01*
G01X208548Y59731D02*
Y51354D01*
G01X210402Y52100D02*
X213508Y48994D01*
G01X211501Y49500D02*
X212448Y48553D01*
G01X213508Y48994D02*
Y32848D01*
G01X212448Y48553D02*
Y46020D01*
G01X213508Y48994D02*
Y32848D01*
G01X212448Y41880D02*
Y40920D01*
G01X213508Y48994D02*
Y32848D01*
G01X212448Y36580D02*
Y33291D01*
G01X171737Y51354D02*
Y58931D01*
G01X172797Y57420D02*
Y58488D01*
G01X171737Y58931D02*
X175611Y62805D01*
G01X172797Y58488D02*
X173751Y59442D01*
G01X171737Y58931D02*
X175611Y62805D01*
G01X175342Y61033D02*
X176671Y62362D01*
G01X175611Y62805D02*
Y103488D01*
G01X176671Y62362D02*
Y74025D01*
G01X175611Y62805D02*
Y103488D01*
G01X176671Y76274D02*
Y78380D01*
G01X175611Y62805D02*
Y103488D01*
G01X176671Y80620D02*
Y93480D01*
G01X175611Y62805D02*
Y103488D01*
G01Y62805D02*
Y103488D01*
G01Y62805D02*
Y103488D01*
G01X174690Y49500D02*
X175637Y48553D01*
G01X173591Y52100D02*
X176697Y48994D01*
G01X175637Y48553D02*
Y46020D01*
G01Y41880D02*
Y40920D01*
G01Y36580D02*
Y33291D01*
G01X176697Y48994D02*
Y32848D01*
G01X212422Y115998D02*
Y63605D01*
G01Y115998D02*
Y63605D01*
G01Y115998D02*
Y63605D01*
G01Y115998D02*
Y63605D01*
G01Y115998D02*
Y63605D01*
G01X213482Y93980D02*
Y80275D01*
G01X212422Y115998D02*
Y63605D01*
G01X213482Y78026D02*
Y76524D01*
G01X212422Y115998D02*
Y63605D01*
G01X213482Y74275D02*
Y63162D01*
G01X212422Y63605D02*
X208548Y59731D01*
G01X213482Y63162D02*
X212153Y61833D01*
G01X212422Y63605D02*
X208548Y59731D01*
G01X210562Y60242D02*
X209608Y59288D01*
G01X208548Y59731D02*
Y51354D01*
G01X209608Y59288D02*
Y57420D01*
G01X211501Y49500D02*
X212448Y48553D01*
G01X210402Y52100D02*
X213508Y48994D01*
G01X212448Y48553D02*
Y46020D01*
G01Y41880D02*
Y40920D01*
G01Y36580D02*
Y33291D01*
G01X213508Y48994D02*
Y32848D01*
G01X177437Y58199D02*
Y59031D01*
G01X178497Y57720D02*
Y58588D01*
G01X177437Y59031D02*
X180711Y62305D01*
G01X178497Y58588D02*
X179471Y59562D01*
G01X180711Y62305D02*
Y93987D01*
G01X181771Y63934D02*
Y74580D01*
G01X180711Y62305D02*
Y93987D01*
G01X181771Y76820D02*
Y77580D01*
G01X180711Y62305D02*
Y93987D01*
G01X181771Y79820D02*
Y93547D01*
G01X180711Y93987D02*
X181812Y95088D01*
G01X181771Y93547D02*
X182872Y94648D01*
G01X179789Y49715D02*
X180823Y48681D01*
G01X178691Y52314D02*
X181883Y49122D01*
G01X180823Y48681D02*
Y45906D01*
G01Y42080D02*
Y40707D01*
G01Y36793D02*
Y34172D01*
G01X181883Y49122D02*
Y33732D01*
G01X180823Y34172D02*
X179800Y33149D01*
G01X217522Y115701D02*
Y62305D01*
G01X218582Y115258D02*
Y61862D01*
G01X217522Y62305D02*
X214248Y59031D01*
G01X218582Y61862D02*
X215308Y58588D01*
G01X214248Y59031D02*
Y58199D01*
G01X215308Y58588D02*
Y57684D01*
G01X215502Y49715D02*
X216600D01*
G01D02*
X217634Y48681D01*
G01X215502Y52314D02*
X218694Y49122D01*
G01X217634Y48681D02*
Y45906D01*
G01Y42080D02*
Y40707D01*
G01Y36793D02*
Y34172D01*
G01X218694Y49122D02*
Y33732D01*
G01X217634Y34172D02*
X216611Y33149D01*
G01D02*
X215502D01*
G01X172797Y57420D02*
Y58488D01*
G01X171737Y51354D02*
Y58931D01*
G01X172797Y58488D02*
X173751Y59442D01*
G01X175342Y61033D02*
X176671Y62362D01*
G01X171737Y58931D02*
X175611Y62805D01*
G01X176671Y62362D02*
Y74025D01*
G01Y76274D02*
Y78380D01*
G01Y80620D02*
Y93480D01*
G01X175611Y62805D02*
Y103488D01*
G01X173591Y52100D02*
X176697Y48994D01*
G01X174690Y49500D02*
X175637Y48553D01*
G01X176697Y48994D02*
Y32848D01*
G01X175637Y48553D02*
Y46020D01*
G01X176697Y48994D02*
Y32848D01*
G01X175637Y41880D02*
Y40920D01*
G01X176697Y48994D02*
Y32848D01*
G01X175637Y36580D02*
Y33291D01*
G01X213482Y93980D02*
Y80275D01*
G01Y78026D02*
Y76524D01*
G01Y74275D02*
Y63162D01*
G01X212422Y115998D02*
Y63605D01*
G01X213482Y63162D02*
X212153Y61833D01*
G01X210562Y60242D02*
X209608Y59288D01*
G01X212422Y63605D02*
X208548Y59731D01*
G01X209608Y59288D02*
Y57420D01*
G01X208548Y59731D02*
Y51354D01*
G01X210402Y52100D02*
X213508Y48994D01*
G01X211501Y49500D02*
X212448Y48553D01*
G01X213508Y48994D02*
Y32848D01*
G01X212448Y48553D02*
Y46020D01*
G01X213508Y48994D02*
Y32848D01*
G01X212448Y41880D02*
Y40920D01*
G01X213508Y48994D02*
Y32848D01*
G01X212448Y36580D02*
Y33291D01*
G01X178497Y57720D02*
Y58588D01*
G01X177437Y58199D02*
Y59031D01*
G01X178497Y58588D02*
X179471Y59562D01*
G01X177437Y59031D02*
X180711Y62305D01*
G01X181771Y63934D02*
Y74580D01*
G01Y76820D02*
Y77580D01*
G01Y79820D02*
Y93547D01*
G01X180711Y62305D02*
Y93987D01*
G01X181771Y93547D02*
X182872Y94648D01*
G01X180711Y93987D02*
X181812Y95088D01*
G01X178691Y52314D02*
X181883Y49122D01*
G01X179789Y49715D02*
X180823Y48681D01*
G01X181883Y49122D02*
Y33732D01*
G01X180823Y48681D02*
Y45906D01*
G01X181883Y49122D02*
Y33732D01*
G01X180823Y42080D02*
Y40707D01*
G01X181883Y49122D02*
Y33732D01*
G01X180823Y36793D02*
Y34172D01*
G01D02*
X179800Y33149D01*
G01X178497Y57720D02*
Y58588D01*
G01X177437Y58199D02*
Y59031D01*
G01X178497Y58588D02*
X179471Y59562D01*
G01X177437Y59031D02*
X180711Y62305D01*
G01X181771Y63934D02*
Y74580D01*
G01Y76820D02*
Y77580D01*
G01Y79820D02*
Y93547D01*
G01X180711Y62305D02*
Y93987D01*
G01X181771Y93547D02*
X182872Y94648D01*
G01X180711Y93987D02*
X181812Y95088D01*
G01X178691Y52314D02*
X181883Y49122D01*
G01X179789Y49715D02*
X180823Y48681D01*
G01X181883Y49122D02*
Y33732D01*
G01X180823Y48681D02*
Y45906D01*
G01X181883Y49122D02*
Y33732D01*
G01X180823Y42080D02*
Y40707D01*
G01X181883Y49122D02*
Y33732D01*
G01X180823Y36793D02*
Y34172D01*
G01D02*
X179800Y33149D01*
G01X218582Y115258D02*
Y61862D01*
G01X217522Y115701D02*
Y62305D01*
G01X218582Y61862D02*
X215308Y58588D01*
G01X217522Y62305D02*
X214248Y59031D01*
G01X215308Y58588D02*
Y57684D01*
G01X214248Y59031D02*
Y58199D01*
G01X215502Y52314D02*
X218694Y49122D01*
G01X215502Y49715D02*
X216600D01*
G01X215502Y52314D02*
X218694Y49122D01*
G01X216600Y49715D02*
X217634Y48681D01*
G01X218694Y49122D02*
Y33732D01*
G01X217634Y48681D02*
Y45906D01*
G01X218694Y49122D02*
Y33732D01*
G01X217634Y42080D02*
Y40707D01*
G01X218694Y49122D02*
Y33732D01*
G01X217634Y36793D02*
Y34172D01*
G01D02*
X216611Y33149D01*
G01D02*
X215502D01*
G01X218582Y115258D02*
Y61862D01*
G01X217522Y115701D02*
Y62305D01*
G01X218582Y61862D02*
X215308Y58588D01*
G01X217522Y62305D02*
X214248Y59031D01*
G01X215308Y58588D02*
Y57684D01*
G01X214248Y59031D02*
Y58199D01*
G01X215502Y52314D02*
X218694Y49122D01*
G01X215502Y49715D02*
X216600D01*
G01X215502Y52314D02*
X218694Y49122D01*
G01X216600Y49715D02*
X217634Y48681D01*
G01X218694Y49122D02*
Y33732D01*
G01X217634Y48681D02*
Y45906D01*
G01X218694Y49122D02*
Y33732D01*
G01X217634Y42080D02*
Y40707D01*
G01X218694Y49122D02*
Y33732D01*
G01X217634Y36793D02*
Y34172D01*
G01D02*
X216611Y33149D01*
G01D02*
X215502D01*
G01X176671Y95720D02*
Y96480D01*
G01Y98720D02*
Y99480D01*
G01Y101720D02*
Y103048D01*
G01X175611Y103488D02*
X178012Y105889D01*
G01X176671Y103048D02*
X179072Y105449D01*
G01X178012Y105889D02*
Y125870D01*
G01X179072Y105449D02*
Y125430D01*
G01X178012Y125870D02*
X185132Y132990D01*
G01X179072Y125430D02*
X186192Y132550D01*
G01X185132Y132990D02*
Y146369D01*
G01X186192Y132550D02*
Y145929D01*
G01X185132Y146369D02*
X188063Y149300D01*
G01X186192Y145929D02*
X188503Y148240D01*
G01X188063Y149300D02*
X191845D01*
G01X188503Y148240D02*
X191405D01*
G01X191845Y149300D02*
X194241Y146904D01*
G01X191405Y148240D02*
X193801Y145844D01*
G01X194241Y146904D02*
X194946D01*
G01X193801Y145844D02*
X195386D01*
G01X194241Y146904D02*
X194946D01*
G01D02*
X196089Y148047D01*
G01X195386Y145844D02*
X197149Y147607D01*
G01X196089Y148047D02*
Y148752D01*
G01X197149Y147607D02*
Y149192D01*
G01X196089Y148752D02*
X192673Y152168D01*
G01X197149Y149192D02*
X193733Y152608D01*
G01X192673Y152168D02*
Y153910D01*
G01X193733Y152608D02*
Y153470D01*
G01X192673Y153910D02*
X256182Y217419D01*
G01X193733Y153470D02*
X223893Y183630D01*
G01X192673Y153910D02*
X256182Y217419D01*
G01X192673Y153910D02*
X256182Y217419D01*
G01X192673Y153910D02*
X256182Y217419D01*
G01X192673Y153910D02*
X256182Y217419D01*
G01X192673Y153910D02*
X256182Y217419D01*
G01X192673Y153910D02*
X256182Y217419D01*
G01X192673Y153910D02*
X256182Y217419D01*
G01X192673Y153910D02*
X256182Y217419D01*
G01X192673Y153910D02*
X256182Y217419D01*
G01X192673Y153910D02*
X256182Y217419D01*
G01X192673Y153910D02*
X256182Y217419D01*
G01X192673Y153910D02*
X256182Y217419D01*
G01X192673Y153910D02*
X256182Y217419D01*
G01X234325Y137901D02*
X212422Y115998D01*
G01X235385Y137461D02*
X213482Y115558D01*
G01D02*
Y105818D01*
G01Y103568D02*
Y102220D01*
G01Y99980D02*
Y99220D01*
G01Y96980D02*
Y96220D01*
G01X181812Y95088D02*
Y124221D01*
G01X182872Y94648D02*
Y123781D01*
G01X181812Y124221D02*
X191680Y134089D01*
G01X182872Y123781D02*
X192740Y133649D01*
G01X191680Y134089D02*
Y134951D01*
G01X192740Y133649D02*
Y135391D01*
G01X191680Y134951D02*
X188856Y137775D01*
G01X192740Y135391D02*
X189916Y138215D01*
G01X188856Y137775D02*
Y139514D01*
G01X189916Y138215D02*
Y139074D01*
G01X188856Y139514D02*
X190466Y141124D01*
G01X189916Y139074D02*
X190906Y140064D01*
G01X188856Y139514D02*
X190466Y141124D01*
G01D02*
X192203D01*
G01X190906Y140064D02*
X191763D01*
G01X192203Y141124D02*
X195028Y138299D01*
G01X191763Y140064D02*
X194588Y137239D01*
G01X195028Y138299D02*
X195890D01*
G01X194588Y137239D02*
X196330D01*
G01X195028Y138299D02*
X195890D01*
G01D02*
X201612Y144021D01*
G01X196330Y137239D02*
X202672Y143581D01*
G01X201612Y144021D02*
Y151612D01*
G01X202672Y143581D02*
Y152052D01*
G01X201612Y151612D02*
X199812Y153412D01*
G01X202672Y152052D02*
X200872Y153852D01*
G01X199812Y153412D02*
Y155617D01*
G01X200872Y153852D02*
Y155174D01*
G01X199814Y155616D02*
X271643Y227445D01*
G01X200872Y155174D02*
X269175Y223477D01*
G01X199814Y155616D02*
X271643Y227445D01*
G01X256412Y154591D02*
X217522Y115701D01*
G01X257472Y154148D02*
X218582Y115258D01*
G01X176671Y95720D02*
Y96480D01*
G01Y98720D02*
Y99480D01*
G01Y101720D02*
Y103048D01*
G01D02*
X179072Y105449D01*
G01X175611Y103488D02*
X178012Y105889D01*
G01X179072Y105449D02*
Y125430D01*
G01X178012Y105889D02*
Y125870D01*
G01X179072Y125430D02*
X186192Y132550D01*
G01X178012Y125870D02*
X185132Y132990D01*
G01X186192Y132550D02*
Y145929D01*
G01X185132Y132990D02*
Y146369D01*
G01X186192Y145929D02*
X188503Y148240D01*
G01X185132Y146369D02*
X188063Y149300D01*
G01X188503Y148240D02*
X191405D01*
G01X188063Y149300D02*
X191845D01*
G01X191405Y148240D02*
X193801Y145844D01*
G01X191845Y149300D02*
X194241Y146904D01*
G01X193801Y145844D02*
X195386D01*
G01D02*
X197149Y147607D01*
G01X194241Y146904D02*
X194946D01*
G01X195386Y145844D02*
X197149Y147607D01*
G01X194946Y146904D02*
X196089Y148047D01*
G01X197149Y147607D02*
Y149192D01*
G01X196089Y148047D02*
Y148752D01*
G01X197149Y149192D02*
X193733Y152608D01*
G01X196089Y148752D02*
X192673Y152168D01*
G01X193733Y152608D02*
Y153470D01*
G01X192673Y152168D02*
Y153910D01*
G01X193733Y153470D02*
X223893Y183630D01*
G01X192673Y153910D02*
X256182Y217419D01*
G01X235385Y137461D02*
X213482Y115558D01*
G01X234325Y137901D02*
X212422Y115998D01*
G01X213482Y115558D02*
Y105818D01*
G01Y103568D02*
Y102220D01*
G01Y99980D02*
Y99220D01*
G01Y96980D02*
Y96220D01*
G01X176671Y95720D02*
Y96480D01*
G01Y98720D02*
Y99480D01*
G01Y101720D02*
Y103048D01*
G01X175611Y103488D02*
X178012Y105889D01*
G01X176671Y103048D02*
X179072Y105449D01*
G01X178012Y105889D02*
Y125870D01*
G01X179072Y105449D02*
Y125430D01*
G01X178012Y125870D02*
X185132Y132990D01*
G01X179072Y125430D02*
X186192Y132550D01*
G01X185132Y132990D02*
Y146369D01*
G01X186192Y132550D02*
Y145929D01*
G01X185132Y146369D02*
X188063Y149300D01*
G01X186192Y145929D02*
X188503Y148240D01*
G01X188063Y149300D02*
X191845D01*
G01X188503Y148240D02*
X191405D01*
G01X191845Y149300D02*
X194241Y146904D01*
G01X191405Y148240D02*
X193801Y145844D01*
G01X194241Y146904D02*
X194946D01*
G01X193801Y145844D02*
X195386D01*
G01X194241Y146904D02*
X194946D01*
G01D02*
X196089Y148047D01*
G01X195386Y145844D02*
X197149Y147607D01*
G01X196089Y148047D02*
Y148752D01*
G01X197149Y147607D02*
Y149192D01*
G01X196089Y148752D02*
X192673Y152168D01*
G01X197149Y149192D02*
X193733Y152608D01*
G01X192673Y152168D02*
Y153910D01*
G01X193733Y152608D02*
Y153470D01*
G01X192673Y153910D02*
X256182Y217419D01*
G01X193733Y153470D02*
X223893Y183630D01*
G01X192673Y153910D02*
X256182Y217419D01*
G01X192673Y153910D02*
X256182Y217419D01*
G01X192673Y153910D02*
X256182Y217419D01*
G01X192673Y153910D02*
X256182Y217419D01*
G01X192673Y153910D02*
X256182Y217419D01*
G01X192673Y153910D02*
X256182Y217419D01*
G01X192673Y153910D02*
X256182Y217419D01*
G01X192673Y153910D02*
X256182Y217419D01*
G01X192673Y153910D02*
X256182Y217419D01*
G01X192673Y153910D02*
X256182Y217419D01*
G01X192673Y153910D02*
X256182Y217419D01*
G01X192673Y153910D02*
X256182Y217419D01*
G01X192673Y153910D02*
X256182Y217419D01*
G01X234325Y137901D02*
X212422Y115998D01*
G01X235385Y137461D02*
X213482Y115558D01*
G01D02*
Y105818D01*
G01Y103568D02*
Y102220D01*
G01Y99980D02*
Y99220D01*
G01Y96980D02*
Y96220D01*
G01X181812Y95088D02*
Y124221D01*
G01X182872Y94648D02*
Y123781D01*
G01X181812Y124221D02*
X191680Y134089D01*
G01X182872Y123781D02*
X192740Y133649D01*
G01X191680Y134089D02*
Y134951D01*
G01X192740Y133649D02*
Y135391D01*
G01X191680Y134951D02*
X188856Y137775D01*
G01X192740Y135391D02*
X189916Y138215D01*
G01X188856Y137775D02*
Y139514D01*
G01X189916Y138215D02*
Y139074D01*
G01X188856Y139514D02*
X190466Y141124D01*
G01X189916Y139074D02*
X190906Y140064D01*
G01X188856Y139514D02*
X190466Y141124D01*
G01D02*
X192203D01*
G01X190906Y140064D02*
X191763D01*
G01X192203Y141124D02*
X195028Y138299D01*
G01X191763Y140064D02*
X194588Y137239D01*
G01X195028Y138299D02*
X195890D01*
G01X194588Y137239D02*
X196330D01*
G01X195028Y138299D02*
X195890D01*
G01D02*
X201612Y144021D01*
G01X196330Y137239D02*
X202672Y143581D01*
G01X201612Y144021D02*
Y151612D01*
G01X202672Y143581D02*
Y152052D01*
G01X201612Y151612D02*
X199812Y153412D01*
G01X202672Y152052D02*
X200872Y153852D01*
G01X199812Y153412D02*
Y155617D01*
G01X200872Y153852D02*
Y155174D01*
G01X199814Y155616D02*
X271643Y227445D01*
G01X200872Y155174D02*
X269175Y223477D01*
G01X199814Y155616D02*
X271643Y227445D01*
G01X256412Y154591D02*
X217522Y115701D01*
G01X257472Y154148D02*
X218582Y115258D01*
G01X176671Y95720D02*
Y96480D01*
G01Y98720D02*
Y99480D01*
G01Y101720D02*
Y103048D01*
G01D02*
X179072Y105449D01*
G01X175611Y103488D02*
X178012Y105889D01*
G01X179072Y105449D02*
Y125430D01*
G01X178012Y105889D02*
Y125870D01*
G01X179072Y125430D02*
X186192Y132550D01*
G01X178012Y125870D02*
X185132Y132990D01*
G01X186192Y132550D02*
Y145929D01*
G01X185132Y132990D02*
Y146369D01*
G01X186192Y145929D02*
X188503Y148240D01*
G01X185132Y146369D02*
X188063Y149300D01*
G01X188503Y148240D02*
X191405D01*
G01X188063Y149300D02*
X191845D01*
G01X191405Y148240D02*
X193801Y145844D01*
G01X191845Y149300D02*
X194241Y146904D01*
G01X193801Y145844D02*
X195386D01*
G01D02*
X197149Y147607D01*
G01X194241Y146904D02*
X194946D01*
G01X195386Y145844D02*
X197149Y147607D01*
G01X194946Y146904D02*
X196089Y148047D01*
G01X197149Y147607D02*
Y149192D01*
G01X196089Y148047D02*
Y148752D01*
G01X197149Y149192D02*
X193733Y152608D01*
G01X196089Y148752D02*
X192673Y152168D01*
G01X193733Y152608D02*
Y153470D01*
G01X192673Y152168D02*
Y153910D01*
G01X193733Y153470D02*
X223893Y183630D01*
G01X192673Y153910D02*
X256182Y217419D01*
G01X235385Y137461D02*
X213482Y115558D01*
G01X234325Y137901D02*
X212422Y115998D01*
G01X213482Y115558D02*
Y105818D01*
G01Y103568D02*
Y102220D01*
G01Y99980D02*
Y99220D01*
G01Y96980D02*
Y96220D01*
G01X182872Y94648D02*
Y123781D01*
G01X181812Y95088D02*
Y124221D01*
G01X182872Y123781D02*
X192740Y133649D01*
G01X181812Y124221D02*
X191680Y134089D01*
G01X192740Y133649D02*
Y135391D01*
G01X191680Y134089D02*
Y134951D01*
G01X192740Y135391D02*
X189916Y138215D01*
G01X191680Y134951D02*
X188856Y137775D01*
G01X189916Y138215D02*
Y139074D01*
G01X188856Y137775D02*
Y139514D01*
G01X189916Y139074D02*
X190906Y140064D01*
G01D02*
X191763D01*
G01X188856Y139514D02*
X190466Y141124D01*
G01X190906Y140064D02*
X191763D01*
G01X190466Y141124D02*
X192203D01*
G01X191763Y140064D02*
X194588Y137239D01*
G01X192203Y141124D02*
X195028Y138299D01*
G01X194588Y137239D02*
X196330D01*
G01D02*
X202672Y143581D01*
G01X195028Y138299D02*
X195890D01*
G01X196330Y137239D02*
X202672Y143581D01*
G01X195890Y138299D02*
X201612Y144021D01*
G01X202672Y143581D02*
Y152052D01*
G01X201612Y144021D02*
Y151612D01*
G01X202672Y152052D02*
X200872Y153852D01*
G01X201612Y151612D02*
X199812Y153412D01*
G01X200872Y153852D02*
Y155174D01*
G01X199812Y153412D02*
Y155617D01*
G01X200872Y155174D02*
X269175Y223477D01*
G01X199814Y155616D02*
X271643Y227445D01*
G01X182872Y94648D02*
Y123781D01*
G01X181812Y95088D02*
Y124221D01*
G01X182872Y123781D02*
X192740Y133649D01*
G01X181812Y124221D02*
X191680Y134089D01*
G01X192740Y133649D02*
Y135391D01*
G01X191680Y134089D02*
Y134951D01*
G01X192740Y135391D02*
X189916Y138215D01*
G01X191680Y134951D02*
X188856Y137775D01*
G01X189916Y138215D02*
Y139074D01*
G01X188856Y137775D02*
Y139514D01*
G01X189916Y139074D02*
X190906Y140064D01*
G01D02*
X191763D01*
G01X188856Y139514D02*
X190466Y141124D01*
G01X190906Y140064D02*
X191763D01*
G01X190466Y141124D02*
X192203D01*
G01X191763Y140064D02*
X194588Y137239D01*
G01X192203Y141124D02*
X195028Y138299D01*
G01X194588Y137239D02*
X196330D01*
G01D02*
X202672Y143581D01*
G01X195028Y138299D02*
X195890D01*
G01X196330Y137239D02*
X202672Y143581D01*
G01X195890Y138299D02*
X201612Y144021D01*
G01X202672Y143581D02*
Y152052D01*
G01X201612Y144021D02*
Y151612D01*
G01X202672Y152052D02*
X200872Y153852D01*
G01X201612Y151612D02*
X199812Y153412D01*
G01X200872Y153852D02*
Y155174D01*
G01X199812Y153412D02*
Y155617D01*
G01X200872Y155174D02*
X269175Y223477D01*
G01X199814Y155616D02*
X271643Y227445D01*
G01X257472Y154148D02*
X218582Y115258D01*
G01X256412Y154591D02*
X217522Y115701D01*
G01X257472Y154148D02*
X218582Y115258D01*
G01X256412Y154591D02*
X217522Y115701D01*
G01X225484Y185221D02*
X226437Y186174D01*
G01X228028Y187765D02*
X228982Y188719D01*
G01X230573Y190310D02*
X231526Y191263D01*
G01X225484Y185221D02*
X226437Y186174D01*
G01X228028Y187765D02*
X228982Y188719D01*
G01X230573Y190310D02*
X231526Y191263D01*
G01X225484Y185221D02*
X226437Y186174D01*
G01X228028Y187765D02*
X228982Y188719D01*
G01X230573Y190310D02*
X231526Y191263D01*
G01X225484Y185221D02*
X226437Y186174D01*
G01X228028Y187765D02*
X228982Y188719D01*
G01X230573Y190310D02*
X231526Y191263D01*
G01X215502Y219460D02*
X218152D01*
G01X215942Y218400D02*
X218592D01*
G01X218152Y219460D02*
X243032Y244340D01*
G01X218592Y218400D02*
X244092Y243900D01*
G01X213753Y223310D02*
X215501D01*
G01X214193Y222250D02*
X215941D01*
G01X215501Y223310D02*
X256431Y264240D01*
G01X215941Y222250D02*
X218704Y225013D01*
G01X215501Y223310D02*
X256431Y264240D01*
G01X220295Y226604D02*
X221248Y227557D01*
G01X215501Y223310D02*
X256431Y264240D01*
G01X222839Y229148D02*
X223793Y230102D01*
G01X215501Y223310D02*
X256431Y264240D01*
G01X225384Y231693D02*
X226337Y232646D01*
G01X215501Y223310D02*
X256431Y264240D01*
G01X227928Y234237D02*
X228882Y235191D01*
G01X215501Y223310D02*
X256431Y264240D01*
G01X230473Y236782D02*
X231426Y237735D01*
G01X215501Y223310D02*
X256431Y264240D01*
G01X215501Y223310D02*
X256431Y264240D01*
G01X215501Y223310D02*
X256431Y264240D01*
G01X215501Y223310D02*
X256431Y264240D01*
G01X215501Y223310D02*
X256431Y264240D01*
G01X215501Y223310D02*
X256431Y264240D01*
G01X215501Y223310D02*
X256431Y264240D01*
G01X215501Y223310D02*
X256431Y264240D01*
G01X215501Y223310D02*
X256431Y264240D01*
G01X215501Y223310D02*
X256431Y264240D01*
G01X214193Y222250D02*
X215941D01*
G01X214193D02*
X215941D01*
G01X213753Y223310D02*
X215501D01*
G01X215941Y222250D02*
X218704Y225013D01*
G01X220295Y226604D02*
X221248Y227557D01*
G01X222839Y229148D02*
X223793Y230102D01*
G01X225384Y231693D02*
X226337Y232646D01*
G01X227928Y234237D02*
X228882Y235191D01*
G01X230473Y236782D02*
X231426Y237735D01*
G01X215501Y223310D02*
X256431Y264240D01*
G01X215502Y219460D02*
X218152D01*
G01X215942Y218400D02*
X218592D01*
G01X218152Y219460D02*
X243032Y244340D01*
G01X218592Y218400D02*
X244092Y243900D01*
G01X213753Y223310D02*
X215501D01*
G01X214193Y222250D02*
X215941D01*
G01X215501Y223310D02*
X256431Y264240D01*
G01X215941Y222250D02*
X218704Y225013D01*
G01X215501Y223310D02*
X256431Y264240D01*
G01X220295Y226604D02*
X221248Y227557D01*
G01X215501Y223310D02*
X256431Y264240D01*
G01X222839Y229148D02*
X223793Y230102D01*
G01X215501Y223310D02*
X256431Y264240D01*
G01X225384Y231693D02*
X226337Y232646D01*
G01X215501Y223310D02*
X256431Y264240D01*
G01X227928Y234237D02*
X228882Y235191D01*
G01X215501Y223310D02*
X256431Y264240D01*
G01X230473Y236782D02*
X231426Y237735D01*
G01X215501Y223310D02*
X256431Y264240D01*
G01X215501Y223310D02*
X256431Y264240D01*
G01X215501Y223310D02*
X256431Y264240D01*
G01X215501Y223310D02*
X256431Y264240D01*
G01X215501Y223310D02*
X256431Y264240D01*
G01X215501Y223310D02*
X256431Y264240D01*
G01X215501Y223310D02*
X256431Y264240D01*
G01X215501Y223310D02*
X256431Y264240D01*
G01X215501Y223310D02*
X256431Y264240D01*
G01X215501Y223310D02*
X256431Y264240D01*
G01X215942Y218400D02*
X218592D01*
G01X215502Y219460D02*
X218152D01*
G01X218592Y218400D02*
X244092Y243900D01*
G01X218152Y219460D02*
X243032Y244340D01*
G01X215942Y218400D02*
X218592D01*
G01X215502Y219460D02*
X218152D01*
G01X218592Y218400D02*
X244092Y243900D01*
G01X218152Y219460D02*
X243032Y244340D01*
G01X214193Y222250D02*
X215941D01*
G01X214193D02*
X215941D01*
G01X213753Y223310D02*
X215501D01*
G01X215941Y222250D02*
X218704Y225013D01*
G01X220295Y226604D02*
X221248Y227557D01*
G01X222839Y229148D02*
X223793Y230102D01*
G01X225384Y231693D02*
X226337Y232646D01*
G01X227928Y234237D02*
X228882Y235191D01*
G01X230473Y236782D02*
X231426Y237735D01*
G01X215501Y223310D02*
X256431Y264240D01*
G01X172992Y432900D02*
X221918Y383974D01*
G01X172552Y431840D02*
X220858Y383534D01*
G01X221918Y383974D02*
Y369274D01*
G01X220858Y383534D02*
Y368834D01*
G01X221918Y369274D02*
X253203Y337989D01*
G01X220858Y368834D02*
X252763Y336929D01*
G01X171451Y428740D02*
X217913Y382278D01*
G01X171891Y429800D02*
X218973Y382718D01*
G01X217913Y382278D02*
Y366749D01*
G01X218973Y382718D02*
Y367189D01*
G01X217913Y366749D02*
X251742Y332920D01*
G01X218973Y367189D02*
X252182Y333980D01*
G01X172552Y431840D02*
X220858Y383534D01*
G01X172992Y432900D02*
X221918Y383974D01*
G01X220858Y383534D02*
Y368834D01*
G01X221918Y383974D02*
Y369274D01*
G01X220858Y368834D02*
X252763Y336929D01*
G01X221918Y369274D02*
X253203Y337989D01*
G01X171891Y429800D02*
X218973Y382718D01*
G01X171451Y428740D02*
X217913Y382278D01*
G01X218973Y382718D02*
Y367189D01*
G01X217913Y382278D02*
Y366749D01*
G01X218973Y367189D02*
X252182Y333980D01*
G01X217913Y366749D02*
X251742Y332920D01*
G01X172992Y432900D02*
X221918Y383974D01*
G01X172552Y431840D02*
X220858Y383534D01*
G01X221918Y383974D02*
Y369274D01*
G01X220858Y383534D02*
Y368834D01*
G01X221918Y369274D02*
X253203Y337989D01*
G01X220858Y368834D02*
X252763Y336929D01*
G01X171451Y428740D02*
X217913Y382278D01*
G01X171891Y429800D02*
X218973Y382718D01*
G01X217913Y382278D02*
Y366749D01*
G01X218973Y382718D02*
Y367189D01*
G01X217913Y366749D02*
X251742Y332920D01*
G01X218973Y367189D02*
X252182Y333980D01*
G01X172552Y431840D02*
X220858Y383534D01*
G01X172992Y432900D02*
X221918Y383974D01*
G01X220858Y383534D02*
Y368834D01*
G01X221918Y383974D02*
Y369274D01*
G01X220858Y368834D02*
X252763Y336929D01*
G01X221918Y369274D02*
X253203Y337989D01*
G01X171891Y429800D02*
X218973Y382718D01*
G01X171451Y428740D02*
X217913Y382278D01*
G01X218973Y382718D02*
Y367189D01*
G01X217913Y382278D02*
Y366749D01*
G01X218973Y367189D02*
X252182Y333980D01*
G01X217913Y366749D02*
X251742Y332920D01*
G01X241792Y390004D02*
X221592Y410204D01*
G01X222652Y410644D02*
X242852Y390444D01*
G01X222652Y410644D02*
X242852Y390444D01*
G01X241792Y390004D02*
X221592Y410204D01*
G01X241792Y390004D02*
X221592Y410204D01*
G01X222652Y410644D02*
X242852Y390444D01*
G01X222652Y410644D02*
X242852Y390444D01*
G01X241792Y390004D02*
X221592Y410204D01*
G01X169660Y432900D02*
X172992D01*
G01X169660D02*
X172992D01*
G01X169660D02*
X172992D01*
G01X169660D02*
X172992D01*
G01X188004Y463609D02*
X184212Y467401D01*
G01X185272Y467841D02*
X188444Y464669D01*
G01X190283Y463609D02*
X188004D01*
G01X188444Y464669D02*
X190723D01*
G01X191432Y462460D02*
X190283Y463609D01*
G01X190723Y464669D02*
X192492Y462900D01*
G01X191432Y460958D02*
Y462460D01*
G01X192492Y462900D02*
Y460518D01*
G01X189843Y459369D02*
X191432Y460958D01*
G01X192492Y460518D02*
X190283Y458309D01*
G01X187632Y459369D02*
X189843D01*
G01X190283Y458309D02*
X188072D01*
G01X186028Y457765D02*
X187632Y459369D01*
G01X188072Y458309D02*
X187088Y457325D01*
G01X186028Y455432D02*
Y457765D01*
G01X187088Y457325D02*
Y455872D01*
G01X221592Y419868D02*
X186028Y455432D01*
G01X187088Y455872D02*
X222652Y420308D01*
G01X221592Y410204D02*
Y419868D01*
G01X222652Y420308D02*
Y410644D01*
G01Y420308D02*
Y410644D01*
G01X221592Y410204D02*
Y419868D01*
G01X187088Y455872D02*
X222652Y420308D01*
G01X221592Y419868D02*
X186028Y455432D01*
G01X187088Y457325D02*
Y455872D01*
G01X186028Y455432D02*
Y457765D01*
G01X188072Y458309D02*
X187088Y457325D01*
G01X186028Y457765D02*
X187632Y459369D01*
G01X190283Y458309D02*
X188072D01*
G01X187632Y459369D02*
X189843D01*
G01X192492Y460518D02*
X190283Y458309D01*
G01X189843Y459369D02*
X191432Y460958D01*
G01X192492Y462900D02*
Y460518D01*
G01X191432Y460958D02*
Y462460D01*
G01X190723Y464669D02*
X192492Y462900D01*
G01X191432Y462460D02*
X190283Y463609D01*
G01X188444Y464669D02*
X190723D01*
G01X190283Y463609D02*
X188004D01*
G01X185272Y467841D02*
X188444Y464669D01*
G01X188004Y463609D02*
X184212Y467401D01*
G01X226152Y412041D02*
X246352Y391841D01*
G01X245292Y391401D02*
X225092Y411601D01*
G01X226152Y422408D02*
Y412041D01*
G01X225092Y411601D02*
Y421968D01*
G01X208691Y439869D02*
X226152Y422408D01*
G01X225092Y421968D02*
X207631Y439429D01*
G01X208691Y441098D02*
Y439869D01*
G01X207631Y439429D02*
Y441541D01*
G01X211753Y444159D02*
X208691Y441098D01*
G01X207631Y441541D02*
X210693Y444602D01*
G01X211753Y446269D02*
Y444159D01*
G01X210693Y444602D02*
Y445826D01*
G01X209360Y448662D02*
X211753Y446269D01*
G01X210693Y445826D02*
X208917Y447602D01*
G01X204189Y445601D02*
X207251Y448662D01*
G01D02*
X209360D01*
G01X208917Y447602D02*
X207691D01*
G01X202962Y445601D02*
X204189D01*
G01D02*
X207251Y448662D01*
G01X207691Y447602D02*
X204629Y444541D01*
G01X202962Y445601D02*
X204189D01*
G01X204629Y444541D02*
X202519D01*
G01X201191Y447372D02*
X202962Y445601D01*
G01X202519Y444541D02*
X200131Y446929D01*
G01X201191Y448598D02*
Y447372D01*
G01X200131Y446929D02*
Y449041D01*
G01X204253Y451659D02*
X201191Y448598D01*
G01X200131Y449041D02*
X203193Y452102D01*
G01X204253Y453769D02*
Y451659D01*
G01X203193Y452102D02*
Y453326D01*
G01X201860Y456162D02*
X204253Y453769D01*
G01X203193Y453326D02*
X201417Y455102D01*
G01X196967Y453380D02*
X199749Y456162D01*
G01D02*
X201860D01*
G01X201417Y455102D02*
X200192D01*
G01X196967Y453380D02*
X199749Y456162D01*
G01X200192Y455102D02*
X197410Y452320D01*
G01X195183Y453380D02*
X196967D01*
G01X197410Y452320D02*
X194740D01*
G01X193872Y454691D02*
X195183Y453380D01*
G01D02*
X196967D01*
G01X194740Y452320D02*
X192812Y454248D01*
G01X193872Y456309D02*
Y454691D01*
G01X192812Y454248D02*
Y456752D01*
G01X197872Y460309D02*
X193872Y456309D01*
G01X192812Y456752D02*
X196812Y460752D01*
G01X197872Y462652D02*
Y460309D01*
G01X196812Y460752D02*
Y462209D01*
G01X189072Y471452D02*
X197872Y462652D01*
G01X196812Y462209D02*
X188012Y471009D01*
G01X196812Y462209D02*
X188012Y471009D01*
G01X189072Y471452D02*
X197872Y462652D01*
G01X196812Y460752D02*
Y462209D01*
G01X197872Y462652D02*
Y460309D01*
G01X192812Y456752D02*
X196812Y460752D01*
G01X197872Y460309D02*
X193872Y456309D01*
G01X192812Y454248D02*
Y456752D01*
G01X193872Y456309D02*
Y454691D01*
G01X194740Y452320D02*
X192812Y454248D01*
G01X193872Y454691D02*
X195183Y453380D01*
G01X197410Y452320D02*
X194740D01*
G01D02*
X192812Y454248D01*
G01X195183Y453380D02*
X196967D01*
G01X201417Y455102D02*
X200192D01*
G01D02*
X197410Y452320D01*
G01X196967Y453380D02*
X199749Y456162D01*
G01X201417Y455102D02*
X200192D01*
G01X199749Y456162D02*
X201860D01*
G01X203193Y453326D02*
X201417Y455102D01*
G01X201860Y456162D02*
X204253Y453769D01*
G01X203193Y452102D02*
Y453326D01*
G01X204253Y453769D02*
Y451659D01*
G01X200131Y449041D02*
X203193Y452102D01*
G01X204253Y451659D02*
X201191Y448598D01*
G01X200131Y446929D02*
Y449041D01*
G01X201191Y448598D02*
Y447372D01*
G01X202519Y444541D02*
X200131Y446929D01*
G01X201191Y447372D02*
X202962Y445601D01*
G01X207691Y447602D02*
X204629Y444541D01*
G01D02*
X202519D01*
G01X202962Y445601D02*
X204189D01*
G01X208917Y447602D02*
X207691D01*
G01D02*
X204629Y444541D01*
G01X204189Y445601D02*
X207251Y448662D01*
G01X208917Y447602D02*
X207691D01*
G01X207251Y448662D02*
X209360D01*
G01X210693Y445826D02*
X208917Y447602D01*
G01X209360Y448662D02*
X211753Y446269D01*
G01X210693Y444602D02*
Y445826D01*
G01X211753Y446269D02*
Y444159D01*
G01X207631Y441541D02*
X210693Y444602D01*
G01X211753Y444159D02*
X208691Y441098D01*
G01X207631Y439429D02*
Y441541D01*
G01X208691Y441098D02*
Y439869D01*
G01X225092Y421968D02*
X207631Y439429D01*
G01X208691Y439869D02*
X226152Y422408D01*
G01X225092Y411601D02*
Y421968D01*
G01X226152Y422408D02*
Y412041D01*
G01X245292Y391401D02*
X225092Y411601D01*
G01X226152Y412041D02*
X246352Y391841D01*
G01X188004Y463609D02*
X184212Y467401D01*
G01X185272Y467841D02*
X188444Y464669D01*
G01X190283Y463609D02*
X188004D01*
G01X188444Y464669D02*
X190723D01*
G01X191432Y462460D02*
X190283Y463609D01*
G01X190723Y464669D02*
X192492Y462900D01*
G01X191432Y460958D02*
Y462460D01*
G01X192492Y462900D02*
Y460518D01*
G01X189843Y459369D02*
X191432Y460958D01*
G01X192492Y460518D02*
X190283Y458309D01*
G01X187632Y459369D02*
X189843D01*
G01X190283Y458309D02*
X188072D01*
G01X186028Y457765D02*
X187632Y459369D01*
G01X188072Y458309D02*
X187088Y457325D01*
G01X186028Y455432D02*
Y457765D01*
G01X187088Y457325D02*
Y455872D01*
G01X221592Y419868D02*
X186028Y455432D01*
G01X187088Y455872D02*
X222652Y420308D01*
G01X221592Y410204D02*
Y419868D01*
G01X222652Y420308D02*
Y410644D01*
G01X226152Y412041D02*
X246352Y391841D01*
G01X245292Y391401D02*
X225092Y411601D01*
G01X226152Y422408D02*
Y412041D01*
G01X225092Y411601D02*
Y421968D01*
G01X208691Y439869D02*
X226152Y422408D01*
G01X225092Y421968D02*
X207631Y439429D01*
G01X208691Y441098D02*
Y439869D01*
G01X207631Y439429D02*
Y441541D01*
G01X211753Y444159D02*
X208691Y441098D01*
G01X207631Y441541D02*
X210693Y444602D01*
G01X211753Y446269D02*
Y444159D01*
G01X210693Y444602D02*
Y445826D01*
G01X209360Y448662D02*
X211753Y446269D01*
G01X210693Y445826D02*
X208917Y447602D01*
G01X204189Y445601D02*
X207251Y448662D01*
G01D02*
X209360D01*
G01X208917Y447602D02*
X207691D01*
G01X202962Y445601D02*
X204189D01*
G01D02*
X207251Y448662D01*
G01X207691Y447602D02*
X204629Y444541D01*
G01X202962Y445601D02*
X204189D01*
G01X204629Y444541D02*
X202519D01*
G01X201191Y447372D02*
X202962Y445601D01*
G01X202519Y444541D02*
X200131Y446929D01*
G01X201191Y448598D02*
Y447372D01*
G01X200131Y446929D02*
Y449041D01*
G01X204253Y451659D02*
X201191Y448598D01*
G01X200131Y449041D02*
X203193Y452102D01*
G01X204253Y453769D02*
Y451659D01*
G01X203193Y452102D02*
Y453326D01*
G01X201860Y456162D02*
X204253Y453769D01*
G01X203193Y453326D02*
X201417Y455102D01*
G01X196967Y453380D02*
X199749Y456162D01*
G01D02*
X201860D01*
G01X201417Y455102D02*
X200192D01*
G01X196967Y453380D02*
X199749Y456162D01*
G01X200192Y455102D02*
X197410Y452320D01*
G01X195183Y453380D02*
X196967D01*
G01X197410Y452320D02*
X194740D01*
G01X193872Y454691D02*
X195183Y453380D01*
G01D02*
X196967D01*
G01X194740Y452320D02*
X192812Y454248D01*
G01X193872Y456309D02*
Y454691D01*
G01X192812Y454248D02*
Y456752D01*
G01X197872Y460309D02*
X193872Y456309D01*
G01X192812Y456752D02*
X196812Y460752D01*
G01X197872Y462652D02*
Y460309D01*
G01X196812Y460752D02*
Y462209D01*
G01X189072Y471452D02*
X197872Y462652D01*
G01X196812Y462209D02*
X188012Y471009D01*
G01X222652Y420308D02*
Y410644D01*
G01X221592Y410204D02*
Y419868D01*
G01X187088Y455872D02*
X222652Y420308D01*
G01X221592Y419868D02*
X186028Y455432D01*
G01X187088Y457325D02*
Y455872D01*
G01X186028Y455432D02*
Y457765D01*
G01X188072Y458309D02*
X187088Y457325D01*
G01X186028Y457765D02*
X187632Y459369D01*
G01X190283Y458309D02*
X188072D01*
G01X187632Y459369D02*
X189843D01*
G01X192492Y460518D02*
X190283Y458309D01*
G01X189843Y459369D02*
X191432Y460958D01*
G01X192492Y462900D02*
Y460518D01*
G01X191432Y460958D02*
Y462460D01*
G01X190723Y464669D02*
X192492Y462900D01*
G01X191432Y462460D02*
X190283Y463609D01*
G01X188444Y464669D02*
X190723D01*
G01X190283Y463609D02*
X188004D01*
G01X185272Y467841D02*
X188444Y464669D01*
G01X188004Y463609D02*
X184212Y467401D01*
G01X196812Y462209D02*
X188012Y471009D01*
G01X189072Y471452D02*
X197872Y462652D01*
G01X196812Y460752D02*
Y462209D01*
G01X197872Y462652D02*
Y460309D01*
G01X192812Y456752D02*
X196812Y460752D01*
G01X197872Y460309D02*
X193872Y456309D01*
G01X192812Y454248D02*
Y456752D01*
G01X193872Y456309D02*
Y454691D01*
G01X194740Y452320D02*
X192812Y454248D01*
G01X193872Y454691D02*
X195183Y453380D01*
G01X197410Y452320D02*
X194740D01*
G01D02*
X192812Y454248D01*
G01X195183Y453380D02*
X196967D01*
G01X201417Y455102D02*
X200192D01*
G01D02*
X197410Y452320D01*
G01X196967Y453380D02*
X199749Y456162D01*
G01X201417Y455102D02*
X200192D01*
G01X199749Y456162D02*
X201860D01*
G01X203193Y453326D02*
X201417Y455102D01*
G01X201860Y456162D02*
X204253Y453769D01*
G01X203193Y452102D02*
Y453326D01*
G01X204253Y453769D02*
Y451659D01*
G01X200131Y449041D02*
X203193Y452102D01*
G01X204253Y451659D02*
X201191Y448598D01*
G01X200131Y446929D02*
Y449041D01*
G01X201191Y448598D02*
Y447372D01*
G01X202519Y444541D02*
X200131Y446929D01*
G01X201191Y447372D02*
X202962Y445601D01*
G01X207691Y447602D02*
X204629Y444541D01*
G01D02*
X202519D01*
G01X202962Y445601D02*
X204189D01*
G01X208917Y447602D02*
X207691D01*
G01D02*
X204629Y444541D01*
G01X204189Y445601D02*
X207251Y448662D01*
G01X208917Y447602D02*
X207691D01*
G01X207251Y448662D02*
X209360D01*
G01X210693Y445826D02*
X208917Y447602D01*
G01X209360Y448662D02*
X211753Y446269D01*
G01X210693Y444602D02*
Y445826D01*
G01X211753Y446269D02*
Y444159D01*
G01X207631Y441541D02*
X210693Y444602D01*
G01X211753Y444159D02*
X208691Y441098D01*
G01X207631Y439429D02*
Y441541D01*
G01X208691Y441098D02*
Y439869D01*
G01X225092Y421968D02*
X207631Y439429D01*
G01X208691Y439869D02*
X226152Y422408D01*
G01X225092Y411601D02*
Y421968D01*
G01X226152Y422408D02*
Y412041D01*
G01X245292Y391401D02*
X225092Y411601D01*
G01X226152Y412041D02*
X246352Y391841D01*
G01X175611Y510710D02*
Y549608D01*
G01Y510710D02*
Y549608D01*
G01Y510710D02*
Y549608D01*
G01X176671Y541764D02*
Y511153D01*
G01X176512Y509809D02*
X175611Y510710D01*
G01X176671Y511153D02*
X177572Y510252D01*
G01X176512Y502709D02*
Y509809D01*
G01X177572Y510252D02*
Y503152D01*
G01X184212Y495009D02*
X176512Y502709D01*
G01X177572Y503152D02*
X185272Y495452D01*
G01X184212Y467401D02*
Y495009D01*
G01X185272Y495452D02*
Y467841D01*
G01Y495452D02*
Y467841D01*
G01X184212Y467401D02*
Y495009D01*
G01X177572Y503152D02*
X185272Y495452D01*
G01X184212Y495009D02*
X176512Y502709D01*
G01X177572Y510252D02*
Y503152D01*
G01X176512Y502709D02*
Y509809D01*
G01X176671Y511153D02*
X177572Y510252D01*
G01X176512Y509809D02*
X175611Y510710D01*
G01X176671Y541764D02*
Y511153D01*
G01X175611Y510710D02*
Y549608D01*
G01X189072Y497349D02*
Y471452D01*
G01X188012Y471009D02*
Y496909D01*
G01X181771Y504650D02*
X189072Y497349D01*
G01X188012Y496909D02*
X180711Y504210D01*
G01X181771Y550259D02*
Y504650D01*
G01X180711Y504210D02*
Y526103D01*
G01X181771Y550259D02*
Y504650D01*
G01Y550259D02*
Y504650D01*
G01Y550259D02*
Y504650D01*
G01Y550259D02*
Y504650D01*
G01X180711Y504210D02*
Y526103D01*
G01X181771Y550259D02*
Y504650D01*
G01X188012Y496909D02*
X180711Y504210D01*
G01X181771Y504650D02*
X189072Y497349D01*
G01X188012Y471009D02*
Y496909D01*
G01X189072Y497349D02*
Y471452D01*
G01X253812Y448889D02*
X217112Y485589D01*
G01X254872Y449329D02*
X218172Y486029D01*
G01X217112Y485589D02*
Y503609D01*
G01X218172Y486029D02*
Y504049D01*
G01X217112Y503609D02*
X212422Y508299D01*
G01X218172Y504049D02*
X213482Y508739D01*
G01X212422Y508299D02*
Y541494D01*
G01X213482Y508739D02*
Y550020D01*
G01X232377Y477360D02*
X229945Y479792D01*
G01X228650Y481653D02*
X228084D01*
G01D02*
X222078Y487659D01*
G01X231937Y476300D02*
X221018Y487219D01*
G01X222078Y487659D02*
Y506181D01*
G01X221018Y487219D02*
Y492516D01*
G01X222078Y487659D02*
Y506181D01*
G01X221018Y494756D02*
Y495756D01*
G01X222078Y487659D02*
Y506181D01*
G01X221018Y497996D02*
Y498996D01*
G01X222078Y487659D02*
Y506181D01*
G01X221018Y501236D02*
Y502236D01*
G01X222078Y487659D02*
Y506181D01*
G01X221018Y504476D02*
Y505741D01*
G01X222078Y506181D02*
X218582Y509677D01*
G01X221018Y505741D02*
X219859Y506900D01*
G01X222078Y506181D02*
X218582Y509677D01*
G01X218274Y508485D02*
X217522Y509237D01*
G01X218582Y509677D02*
Y550235D01*
G01X217522Y509237D02*
Y510553D01*
G01X218582Y509677D02*
Y550235D01*
G01X217522Y512499D02*
Y515936D01*
G01X218582Y509677D02*
Y550235D01*
G01X217522Y517724D02*
Y518987D01*
G01X218582Y509677D02*
Y550235D01*
G01X217522Y521227D02*
Y522227D01*
G01X218582Y509677D02*
Y550235D01*
G01X217522Y524467D02*
Y525467D01*
G01X218582Y509677D02*
Y550235D01*
G01Y509677D02*
Y550235D01*
G01Y509677D02*
Y550235D01*
G01Y509677D02*
Y550235D01*
G01Y509677D02*
Y550235D01*
G01Y509677D02*
Y550235D01*
G01X254872Y449329D02*
X218172Y486029D01*
G01X253812Y448889D02*
X217112Y485589D01*
G01X218172Y486029D02*
Y504049D01*
G01X217112Y485589D02*
Y503609D01*
G01X218172Y504049D02*
X213482Y508739D01*
G01X217112Y503609D02*
X212422Y508299D01*
G01X213482Y508739D02*
Y550020D01*
G01X212422Y508299D02*
Y541494D01*
G01X213482Y508739D02*
Y550020D01*
G01Y508739D02*
Y550020D01*
G01X231937Y476300D02*
X221018Y487219D01*
G01X232377Y477360D02*
X229945Y479792D01*
G01X231937Y476300D02*
X221018Y487219D01*
G01X228650Y481653D02*
X228084D01*
G01X231937Y476300D02*
X221018Y487219D01*
G01X228084Y481653D02*
X222078Y487659D01*
G01X221018Y487219D02*
Y492516D01*
G01Y494756D02*
Y495756D01*
G01Y497996D02*
Y498996D01*
G01Y501236D02*
Y502236D01*
G01Y504476D02*
Y505741D01*
G01X222078Y487659D02*
Y506181D01*
G01X221018Y505741D02*
X219859Y506900D01*
G01X218274Y508485D02*
X217522Y509237D01*
G01X222078Y506181D02*
X218582Y509677D01*
G01X217522Y509237D02*
Y510553D01*
G01Y512499D02*
Y515936D01*
G01Y517724D02*
Y518987D01*
G01Y521227D02*
Y522227D01*
G01Y524467D02*
Y525467D01*
G01X218582Y509677D02*
Y550235D01*
G01X175611Y510710D02*
Y549608D01*
G01Y510710D02*
Y549608D01*
G01Y510710D02*
Y549608D01*
G01X176671Y541764D02*
Y511153D01*
G01X176512Y509809D02*
X175611Y510710D01*
G01X176671Y511153D02*
X177572Y510252D01*
G01X176512Y502709D02*
Y509809D01*
G01X177572Y510252D02*
Y503152D01*
G01X184212Y495009D02*
X176512Y502709D01*
G01X177572Y503152D02*
X185272Y495452D01*
G01X184212Y467401D02*
Y495009D01*
G01X185272Y495452D02*
Y467841D01*
G01X253812Y448889D02*
X217112Y485589D01*
G01X254872Y449329D02*
X218172Y486029D01*
G01X217112Y485589D02*
Y503609D01*
G01X218172Y486029D02*
Y504049D01*
G01X217112Y503609D02*
X212422Y508299D01*
G01X218172Y504049D02*
X213482Y508739D01*
G01X212422Y508299D02*
Y541494D01*
G01X213482Y508739D02*
Y550020D01*
G01X189072Y497349D02*
Y471452D01*
G01X188012Y471009D02*
Y496909D01*
G01X181771Y504650D02*
X189072Y497349D01*
G01X188012Y496909D02*
X180711Y504210D01*
G01X181771Y550259D02*
Y504650D01*
G01X180711Y504210D02*
Y526103D01*
G01X181771Y550259D02*
Y504650D01*
G01Y550259D02*
Y504650D01*
G01Y550259D02*
Y504650D01*
G01Y550259D02*
Y504650D01*
G01X232377Y477360D02*
X229945Y479792D01*
G01X228650Y481653D02*
X228084D01*
G01D02*
X222078Y487659D01*
G01X231937Y476300D02*
X221018Y487219D01*
G01X222078Y487659D02*
Y506181D01*
G01X221018Y487219D02*
Y492516D01*
G01X222078Y487659D02*
Y506181D01*
G01X221018Y494756D02*
Y495756D01*
G01X222078Y487659D02*
Y506181D01*
G01X221018Y497996D02*
Y498996D01*
G01X222078Y487659D02*
Y506181D01*
G01X221018Y501236D02*
Y502236D01*
G01X222078Y487659D02*
Y506181D01*
G01X221018Y504476D02*
Y505741D01*
G01X222078Y506181D02*
X218582Y509677D01*
G01X221018Y505741D02*
X219859Y506900D01*
G01X222078Y506181D02*
X218582Y509677D01*
G01X218274Y508485D02*
X217522Y509237D01*
G01X218582Y509677D02*
Y550235D01*
G01X217522Y509237D02*
Y510553D01*
G01X218582Y509677D02*
Y550235D01*
G01X217522Y512499D02*
Y515936D01*
G01X218582Y509677D02*
Y550235D01*
G01X217522Y517724D02*
Y518987D01*
G01X218582Y509677D02*
Y550235D01*
G01X217522Y521227D02*
Y522227D01*
G01X218582Y509677D02*
Y550235D01*
G01X217522Y524467D02*
Y525467D01*
G01X218582Y509677D02*
Y550235D01*
G01Y509677D02*
Y550235D01*
G01Y509677D02*
Y550235D01*
G01Y509677D02*
Y550235D01*
G01Y509677D02*
Y550235D01*
G01Y509677D02*
Y550235D01*
G01X185272Y495452D02*
Y467841D01*
G01X184212Y467401D02*
Y495009D01*
G01X177572Y503152D02*
X185272Y495452D01*
G01X184212Y495009D02*
X176512Y502709D01*
G01X177572Y510252D02*
Y503152D01*
G01X176512Y502709D02*
Y509809D01*
G01X176671Y511153D02*
X177572Y510252D01*
G01X176512Y509809D02*
X175611Y510710D01*
G01X176671Y541764D02*
Y511153D01*
G01X175611Y510710D02*
Y549608D01*
G01X254872Y449329D02*
X218172Y486029D01*
G01X253812Y448889D02*
X217112Y485589D01*
G01X218172Y486029D02*
Y504049D01*
G01X217112Y485589D02*
Y503609D01*
G01X218172Y504049D02*
X213482Y508739D01*
G01X217112Y503609D02*
X212422Y508299D01*
G01X213482Y508739D02*
Y550020D01*
G01X212422Y508299D02*
Y541494D01*
G01X213482Y508739D02*
Y550020D01*
G01Y508739D02*
Y550020D01*
G01X180711Y504210D02*
Y526103D01*
G01X181771Y550259D02*
Y504650D01*
G01X188012Y496909D02*
X180711Y504210D01*
G01X181771Y504650D02*
X189072Y497349D01*
G01X188012Y471009D02*
Y496909D01*
G01X189072Y497349D02*
Y471452D01*
G01X231937Y476300D02*
X221018Y487219D01*
G01X232377Y477360D02*
X229945Y479792D01*
G01X231937Y476300D02*
X221018Y487219D01*
G01X228650Y481653D02*
X228084D01*
G01X231937Y476300D02*
X221018Y487219D01*
G01X228084Y481653D02*
X222078Y487659D01*
G01X221018Y487219D02*
Y492516D01*
G01Y494756D02*
Y495756D01*
G01Y497996D02*
Y498996D01*
G01Y501236D02*
Y502236D01*
G01Y504476D02*
Y505741D01*
G01X222078Y487659D02*
Y506181D01*
G01X221018Y505741D02*
X219859Y506900D01*
G01X218274Y508485D02*
X217522Y509237D01*
G01X222078Y506181D02*
X218582Y509677D01*
G01X217522Y509237D02*
Y510553D01*
G01Y512499D02*
Y515936D01*
G01Y517724D02*
Y518987D01*
G01Y521227D02*
Y522227D01*
G01Y524467D02*
Y525467D01*
G01X218582Y509677D02*
Y550235D01*
G01X171603Y552200D02*
Y570211D01*
G01X172663Y564560D02*
Y563140D01*
G01X171603Y552200D02*
Y570211D01*
G01X172663Y559460D02*
Y558090D01*
G01X175611Y549608D02*
X174719Y550500D01*
G01X173620Y553100D02*
X176671Y550049D01*
G01D02*
Y546445D01*
G01Y544545D02*
Y543452D01*
G01X172663Y564560D02*
Y563140D01*
G01Y559460D02*
Y558090D01*
G01X171603Y552200D02*
Y570211D01*
G01X176671Y550049D02*
Y546445D01*
G01Y544545D02*
Y543452D01*
G01X173620Y553100D02*
X176671Y550049D01*
G01X175611Y549608D02*
X174719Y550500D01*
G01X177216Y558371D02*
X177887Y557700D01*
G01X176986Y557100D02*
X176156Y557930D01*
G01X177216Y564029D02*
Y563138D01*
G01Y559648D02*
Y558371D01*
G01X176156Y557930D02*
Y564470D01*
G01X177987Y564800D02*
X177216Y564029D01*
G01X176156Y564470D02*
X176986Y565300D01*
G01X180711Y527893D02*
Y538279D01*
G01Y540307D02*
Y541374D01*
G01Y543614D02*
Y544614D01*
G01Y546854D02*
Y549648D01*
G01X176156Y564470D02*
X176986Y565300D01*
G01X177987Y564800D02*
X177216Y564029D01*
G01X176156Y557930D02*
Y564470D01*
G01X177216Y564029D02*
Y563138D01*
G01X176156Y557930D02*
Y564470D01*
G01X177216Y559648D02*
Y558371D01*
G01X176986Y557100D02*
X176156Y557930D01*
G01X177216Y558371D02*
X177887Y557700D01*
G01X180711Y527893D02*
Y538279D01*
G01Y540307D02*
Y541374D01*
G01Y543614D02*
Y544614D01*
G01Y546854D02*
Y549648D01*
G01X208414Y552200D02*
Y570211D01*
G01X209474Y558090D02*
Y559460D01*
G01X208414Y552200D02*
Y570211D01*
G01X209474Y563140D02*
Y564560D01*
G01X212422Y543546D02*
Y544719D01*
G01Y546827D02*
Y549580D01*
G01D02*
X211502Y550500D01*
G01X213482Y550020D02*
X210402Y553100D01*
G01X214698Y557700D02*
X214027Y558371D01*
G01X213797Y557100D02*
X212967Y557930D01*
G01X214027Y558371D02*
Y559648D01*
G01Y563138D02*
Y564029D01*
G01X212967Y557930D02*
Y564470D01*
G01X214027Y564029D02*
X214798Y564800D01*
G01X212967Y564470D02*
X213797Y565300D01*
G01X217522Y527707D02*
Y529337D01*
G01Y531209D02*
Y534496D01*
G01Y536326D02*
Y538160D01*
G01Y540400D02*
Y541400D01*
G01Y543640D02*
Y544640D01*
G01Y546880D02*
Y549795D01*
G01X218582Y550235D02*
X215503Y553314D01*
G01X217522Y549795D02*
X216603Y550714D01*
G01X209474Y558090D02*
Y559460D01*
G01Y563140D02*
Y564560D01*
G01X208414Y552200D02*
Y570211D01*
G01X212422Y543546D02*
Y544719D01*
G01Y546827D02*
Y549580D01*
G01X213482Y550020D02*
X210402Y553100D01*
G01X212422Y549580D02*
X211502Y550500D01*
G01X213797Y557100D02*
X212967Y557930D01*
G01X214698Y557700D02*
X214027Y558371D01*
G01X212967Y557930D02*
Y564470D01*
G01X214027Y558371D02*
Y559648D01*
G01X212967Y557930D02*
Y564470D01*
G01X214027Y563138D02*
Y564029D01*
G01X212967Y564470D02*
X213797Y565300D01*
G01X214027Y564029D02*
X214798Y564800D01*
G01X217522Y527707D02*
Y529337D01*
G01Y531209D02*
Y534496D01*
G01Y536326D02*
Y538160D01*
G01Y540400D02*
Y541400D01*
G01Y543640D02*
Y544640D01*
G01Y546880D02*
Y549795D01*
G01D02*
X216603Y550714D01*
G01X218582Y550235D02*
X215503Y553314D01*
G01X171603Y552200D02*
Y570211D01*
G01X172663Y564560D02*
Y563140D01*
G01X171603Y552200D02*
Y570211D01*
G01X172663Y559460D02*
Y558090D01*
G01X175611Y549608D02*
X174719Y550500D01*
G01X173620Y553100D02*
X176671Y550049D01*
G01D02*
Y546445D01*
G01Y544545D02*
Y543452D01*
G01X208414Y552200D02*
Y570211D01*
G01X209474Y558090D02*
Y559460D01*
G01X208414Y552200D02*
Y570211D01*
G01X209474Y563140D02*
Y564560D01*
G01X212422Y543546D02*
Y544719D01*
G01Y546827D02*
Y549580D01*
G01D02*
X211502Y550500D01*
G01X213482Y550020D02*
X210402Y553100D01*
G01X177216Y558371D02*
X177887Y557700D01*
G01X176986Y557100D02*
X176156Y557930D01*
G01X177216Y564029D02*
Y563138D01*
G01Y559648D02*
Y558371D01*
G01X176156Y557930D02*
Y564470D01*
G01X177987Y564800D02*
X177216Y564029D01*
G01X176156Y564470D02*
X176986Y565300D01*
G01X180711Y527893D02*
Y538279D01*
G01Y540307D02*
Y541374D01*
G01Y543614D02*
Y544614D01*
G01Y546854D02*
Y549648D01*
G01X214698Y557700D02*
X214027Y558371D01*
G01X213797Y557100D02*
X212967Y557930D01*
G01X214027Y558371D02*
Y559648D01*
G01Y563138D02*
Y564029D01*
G01X212967Y557930D02*
Y564470D01*
G01X214027Y564029D02*
X214798Y564800D01*
G01X212967Y564470D02*
X213797Y565300D01*
G01X217522Y527707D02*
Y529337D01*
G01Y531209D02*
Y534496D01*
G01Y536326D02*
Y538160D01*
G01Y540400D02*
Y541400D01*
G01Y543640D02*
Y544640D01*
G01Y546880D02*
Y549795D01*
G01X218582Y550235D02*
X215503Y553314D01*
G01X217522Y549795D02*
X216603Y550714D01*
G01X172663Y564560D02*
Y563140D01*
G01Y559460D02*
Y558090D01*
G01X171603Y552200D02*
Y570211D01*
G01X176671Y550049D02*
Y546445D01*
G01Y544545D02*
Y543452D01*
G01X173620Y553100D02*
X176671Y550049D01*
G01X175611Y549608D02*
X174719Y550500D01*
G01X209474Y558090D02*
Y559460D01*
G01Y563140D02*
Y564560D01*
G01X208414Y552200D02*
Y570211D01*
G01X212422Y543546D02*
Y544719D01*
G01Y546827D02*
Y549580D01*
G01X213482Y550020D02*
X210402Y553100D01*
G01X212422Y549580D02*
X211502Y550500D01*
G01X176156Y564470D02*
X176986Y565300D01*
G01X177987Y564800D02*
X177216Y564029D01*
G01X176156Y557930D02*
Y564470D01*
G01X177216Y564029D02*
Y563138D01*
G01X176156Y557930D02*
Y564470D01*
G01X177216Y559648D02*
Y558371D01*
G01X176986Y557100D02*
X176156Y557930D01*
G01X177216Y558371D02*
X177887Y557700D01*
G01X180711Y527893D02*
Y538279D01*
G01Y540307D02*
Y541374D01*
G01Y543614D02*
Y544614D01*
G01Y546854D02*
Y549648D01*
G01X213797Y557100D02*
X212967Y557930D01*
G01X214698Y557700D02*
X214027Y558371D01*
G01X212967Y557930D02*
Y564470D01*
G01X214027Y558371D02*
Y559648D01*
G01X212967Y557930D02*
Y564470D01*
G01X214027Y563138D02*
Y564029D01*
G01X212967Y564470D02*
X213797Y565300D01*
G01X214027Y564029D02*
X214798Y564800D01*
G01X217522Y527707D02*
Y529337D01*
G01Y531209D02*
Y534496D01*
G01Y536326D02*
Y538160D01*
G01Y540400D02*
Y541400D01*
G01Y543640D02*
Y544640D01*
G01Y546880D02*
Y549795D01*
G01D02*
X216603Y550714D01*
G01X218582Y550235D02*
X215503Y553314D01*
G01X248032Y32580D02*
X248548D01*
G01X248009Y31520D02*
X248991D01*
G01X248032Y32580D02*
X248548D01*
G01D02*
X249259Y33291D01*
G01X248991Y31520D02*
X250319Y32848D01*
G01X248009Y31520D02*
X248991D01*
G01D02*
X250319Y32848D01*
G01X248032Y32580D02*
X248548D01*
G01X248991Y31520D02*
X250319Y32848D01*
G01X248548Y32580D02*
X249259Y33291D01*
G01X255505Y33732D02*
X252313Y30540D01*
G01X286044Y117732D02*
Y25885D01*
G01Y117732D02*
Y25885D01*
G01Y117732D02*
Y25885D01*
G01X287104Y55680D02*
Y25442D01*
G01X286044Y25885D02*
X282170Y22011D01*
G01X287104Y25442D02*
X283230Y21568D01*
G01X282170Y22011D02*
Y13554D01*
G01X283230Y21568D02*
Y19620D01*
G01X291144Y116842D02*
Y24505D01*
G01X292204Y116402D02*
Y24062D01*
G01X291144Y24505D02*
X287870Y21231D01*
G01X292204Y24062D02*
X291488Y23346D01*
G01X291144Y24505D02*
X287870Y21231D01*
G01X290780Y21762D02*
X289904D01*
G01X291144Y24505D02*
X287870Y21231D01*
G01X289904Y21762D02*
X288930Y20788D01*
G01X287870Y21231D02*
Y18479D01*
G01X288930Y20788D02*
Y19920D01*
G01X287104Y55680D02*
Y25442D01*
G01X286044Y117732D02*
Y25885D01*
G01X287104Y25442D02*
X283230Y21568D01*
G01X286044Y25885D02*
X282170Y22011D01*
G01X283230Y21568D02*
Y19620D01*
G01X282170Y22011D02*
Y13554D01*
G01X292204Y116402D02*
Y24062D01*
G01X291144Y116842D02*
Y24505D01*
G01X292204Y24062D02*
X291488Y23346D01*
G01X290780Y21762D02*
X289904D01*
G01D02*
X288930Y20788D01*
G01X291144Y24505D02*
X287870Y21231D01*
G01X288930Y20788D02*
Y19920D01*
G01X287870Y21231D02*
Y18479D01*
G01X248032Y32580D02*
X248548D01*
G01X248009Y31520D02*
X248991D01*
G01X248032Y32580D02*
X248548D01*
G01D02*
X249259Y33291D01*
G01X248991Y31520D02*
X250319Y32848D01*
G01X255505Y33732D02*
X252313Y30540D01*
G01X255505Y33732D02*
X252313Y30540D01*
G01X255505Y33732D02*
X252313Y30540D01*
G01X255505Y33732D02*
X252313Y30540D01*
G01X248009Y31520D02*
X248991D01*
G01D02*
X250319Y32848D01*
G01X248032Y32580D02*
X248548D01*
G01X248991Y31520D02*
X250319Y32848D01*
G01X248548Y32580D02*
X249259Y33291D01*
G01X255505Y33732D02*
X252313Y30540D01*
G01X247170Y57320D02*
Y60190D01*
G01X248230Y56781D02*
Y59747D01*
G01X247170Y60190D02*
X249170Y62190D01*
G01X248230Y59747D02*
X250230Y61747D01*
G01X249170Y62190D02*
Y105934D01*
G01X250230Y61747D02*
Y107497D01*
G01X249259Y33291D02*
Y36580D01*
G01Y40920D02*
Y41880D01*
G01Y46020D02*
Y48553D01*
G01X250319Y32848D02*
Y48994D01*
G01X249259Y48553D02*
X248312Y49500D01*
G01X250319Y48994D02*
X247213Y52100D01*
G01X248230Y56781D02*
Y59747D01*
G01X247170Y57320D02*
Y60190D01*
G01X248230Y59747D02*
X250230Y61747D01*
G01X247170Y60190D02*
X249170Y62190D01*
G01X250230Y61747D02*
Y107497D01*
G01X249170Y62190D02*
Y105934D01*
G01X250319Y32848D02*
Y48994D01*
G01X249259Y33291D02*
Y36580D01*
G01X250319Y32848D02*
Y48994D01*
G01X249259Y40920D02*
Y41880D01*
G01X250319Y32848D02*
Y48994D01*
G01X249259Y46020D02*
Y48553D01*
G01X250319Y48994D02*
X247213Y52100D01*
G01X249259Y48553D02*
X248312Y49500D01*
G01X254270Y106722D02*
Y60092D01*
G01X255330Y108263D02*
Y59649D01*
G01X254270Y60092D02*
X252370Y58192D01*
G01X255330Y59649D02*
X253430Y57749D01*
G01X252370Y58192D02*
Y57520D01*
G01X253430Y57749D02*
Y56620D01*
G01X252313Y49715D02*
X253411D01*
G01D02*
X254445Y48681D01*
G01X252313Y52314D02*
X255505Y49122D01*
G01X254445Y48681D02*
Y45906D01*
G01Y42080D02*
Y40707D01*
G01Y36793D02*
Y34172D01*
G01X255505Y49122D02*
Y33732D01*
G01X254445Y34172D02*
X253422Y33149D01*
G01D02*
X252313D01*
G01X287104Y117292D02*
Y60920D01*
G01Y58680D02*
Y57920D01*
G01Y117292D02*
Y60920D01*
G01Y58680D02*
Y57920D01*
G01X247170Y57320D02*
Y60190D01*
G01X248230Y56781D02*
Y59747D01*
G01X247170Y60190D02*
X249170Y62190D01*
G01X248230Y59747D02*
X250230Y61747D01*
G01X249170Y62190D02*
Y105934D01*
G01X250230Y61747D02*
Y107497D01*
G01X249259Y33291D02*
Y36580D01*
G01Y40920D02*
Y41880D01*
G01Y46020D02*
Y48553D01*
G01X250319Y32848D02*
Y48994D01*
G01X249259Y48553D02*
X248312Y49500D01*
G01X250319Y48994D02*
X247213Y52100D01*
G01X252313Y52314D02*
X255505Y49122D01*
G01X252313Y49715D02*
X253411D01*
G01X252313Y52314D02*
X255505Y49122D01*
G01X253411Y49715D02*
X254445Y48681D01*
G01X255505Y49122D02*
Y33732D01*
G01X254445Y48681D02*
Y45906D01*
G01X255505Y49122D02*
Y33732D01*
G01X254445Y42080D02*
Y40707D01*
G01X255505Y49122D02*
Y33732D01*
G01X254445Y36793D02*
Y34172D01*
G01D02*
X253422Y33149D01*
G01D02*
X252313D01*
G01X255330Y108263D02*
Y59649D01*
G01X254270Y106722D02*
Y60092D01*
G01X255330Y59649D02*
X253430Y57749D01*
G01X254270Y60092D02*
X252370Y58192D01*
G01X253430Y57749D02*
Y56620D01*
G01X252370Y58192D02*
Y57520D01*
G01X252313Y52314D02*
X255505Y49122D01*
G01X252313Y49715D02*
X253411D01*
G01X252313Y52314D02*
X255505Y49122D01*
G01X253411Y49715D02*
X254445Y48681D01*
G01X255505Y49122D02*
Y33732D01*
G01X254445Y48681D02*
Y45906D01*
G01X255505Y49122D02*
Y33732D01*
G01X254445Y42080D02*
Y40707D01*
G01X255505Y49122D02*
Y33732D01*
G01X254445Y36793D02*
Y34172D01*
G01D02*
X253422Y33149D01*
G01D02*
X252313D01*
G01X255330Y108263D02*
Y59649D01*
G01X254270Y106722D02*
Y60092D01*
G01X255330Y59649D02*
X253430Y57749D01*
G01X254270Y60092D02*
X252370Y58192D01*
G01X253430Y57749D02*
Y56620D01*
G01X252370Y58192D02*
Y57520D01*
G01X248230Y56781D02*
Y59747D01*
G01X247170Y57320D02*
Y60190D01*
G01X248230Y59747D02*
X250230Y61747D01*
G01X247170Y60190D02*
X249170Y62190D01*
G01X250230Y61747D02*
Y107497D01*
G01X249170Y62190D02*
Y105934D01*
G01X250319Y32848D02*
Y48994D01*
G01X249259Y33291D02*
Y36580D01*
G01X250319Y32848D02*
Y48994D01*
G01X249259Y40920D02*
Y41880D01*
G01X250319Y32848D02*
Y48994D01*
G01X249259Y46020D02*
Y48553D01*
G01X250319Y48994D02*
X247213Y52100D01*
G01X249259Y48553D02*
X248312Y49500D01*
G01X254270Y106722D02*
Y60092D01*
G01X255330Y108263D02*
Y59649D01*
G01X254270Y60092D02*
X252370Y58192D01*
G01X255330Y59649D02*
X253430Y57749D01*
G01X252370Y58192D02*
Y57520D01*
G01X253430Y57749D02*
Y56620D01*
G01X252313Y49715D02*
X253411D01*
G01D02*
X254445Y48681D01*
G01X252313Y52314D02*
X255505Y49122D01*
G01X254445Y48681D02*
Y45906D01*
G01Y42080D02*
Y40707D01*
G01Y36793D02*
Y34172D01*
G01X255505Y49122D02*
Y33732D01*
G01X254445Y34172D02*
X253422Y33149D01*
G01D02*
X252313D01*
G01X252612Y169591D02*
Y156191D01*
G01Y169591D02*
Y156191D01*
G01Y169591D02*
Y156191D01*
G01Y169591D02*
Y156191D01*
G01X253672Y158352D02*
Y155748D01*
G01X252612Y156191D02*
X252034Y155613D01*
G01X253672Y155748D02*
X252477Y154553D01*
G01X252034Y155613D02*
X249072D01*
G01X252477Y154553D02*
X249515D01*
G01X249072Y155613D02*
X247059Y153600D01*
G01X249515Y154553D02*
X248119Y153157D01*
G01X247059Y153600D02*
Y150638D01*
G01X248119Y153157D02*
Y150195D01*
G01X247059Y150638D02*
X245667Y149246D01*
G01X248119Y150195D02*
X246110Y148186D01*
G01X245667Y149246D02*
X242705D01*
G01X246110Y148186D02*
X243148D01*
G01X242705Y149246D02*
X240692Y147233D01*
G01X243148Y148186D02*
X241752Y146790D01*
G01X240692Y147233D02*
Y144271D01*
G01X241752Y146790D02*
Y143828D01*
G01X240692Y144271D02*
X239300Y142879D01*
G01X241752Y143828D02*
X239743Y141819D01*
G01X239300Y142879D02*
X236338D01*
G01X239743Y141819D02*
X236781D01*
G01X236338Y142879D02*
X236030Y142571D01*
G01Y142568D02*
X234325Y140863D01*
G01X236781Y141819D02*
X235385Y140423D01*
G01X234325Y140863D02*
Y137901D01*
G01X235385Y140423D02*
Y137461D01*
G01X256412Y167891D02*
Y154591D01*
G01X257472Y167448D02*
Y154148D01*
G01X253672Y158352D02*
Y155748D01*
G01X252612Y169591D02*
Y156191D01*
G01X253672Y155748D02*
X252477Y154553D01*
G01X252612Y156191D02*
X252034Y155613D01*
G01X252477Y154553D02*
X249515D01*
G01X252034Y155613D02*
X249072D01*
G01X249515Y154553D02*
X248119Y153157D01*
G01X249072Y155613D02*
X247059Y153600D01*
G01X248119Y153157D02*
Y150195D01*
G01X247059Y153600D02*
Y150638D01*
G01X248119Y150195D02*
X246110Y148186D01*
G01X247059Y150638D02*
X245667Y149246D01*
G01X246110Y148186D02*
X243148D01*
G01X245667Y149246D02*
X242705D01*
G01X243148Y148186D02*
X241752Y146790D01*
G01X242705Y149246D02*
X240692Y147233D01*
G01X241752Y146790D02*
Y143828D01*
G01X240692Y147233D02*
Y144271D01*
G01X241752Y143828D02*
X239743Y141819D01*
G01X240692Y144271D02*
X239300Y142879D01*
G01X239743Y141819D02*
X236781D01*
G01X239300Y142879D02*
X236338D01*
G01X236781Y141819D02*
X235385Y140423D01*
G01X236338Y142879D02*
X236030Y142571D01*
G01X236781Y141819D02*
X235385Y140423D01*
G01X236030Y142568D02*
X234325Y140863D01*
G01X235385Y140423D02*
Y137461D01*
G01X234325Y140863D02*
Y137901D01*
G01X252612Y169591D02*
Y156191D01*
G01Y169591D02*
Y156191D01*
G01Y169591D02*
Y156191D01*
G01Y169591D02*
Y156191D01*
G01X253672Y158352D02*
Y155748D01*
G01X252612Y156191D02*
X252034Y155613D01*
G01X253672Y155748D02*
X252477Y154553D01*
G01X252034Y155613D02*
X249072D01*
G01X252477Y154553D02*
X249515D01*
G01X249072Y155613D02*
X247059Y153600D01*
G01X249515Y154553D02*
X248119Y153157D01*
G01X247059Y153600D02*
Y150638D01*
G01X248119Y153157D02*
Y150195D01*
G01X247059Y150638D02*
X245667Y149246D01*
G01X248119Y150195D02*
X246110Y148186D01*
G01X245667Y149246D02*
X242705D01*
G01X246110Y148186D02*
X243148D01*
G01X242705Y149246D02*
X240692Y147233D01*
G01X243148Y148186D02*
X241752Y146790D01*
G01X240692Y147233D02*
Y144271D01*
G01X241752Y146790D02*
Y143828D01*
G01X240692Y144271D02*
X239300Y142879D01*
G01X241752Y143828D02*
X239743Y141819D01*
G01X239300Y142879D02*
X236338D01*
G01X239743Y141819D02*
X236781D01*
G01X236338Y142879D02*
X236030Y142571D01*
G01Y142568D02*
X234325Y140863D01*
G01X236781Y141819D02*
X235385Y140423D01*
G01X234325Y140863D02*
Y137901D01*
G01X235385Y140423D02*
Y137461D01*
G01X256412Y167891D02*
Y154591D01*
G01X257472Y167448D02*
Y154148D01*
G01X253672Y158352D02*
Y155748D01*
G01X252612Y169591D02*
Y156191D01*
G01X253672Y155748D02*
X252477Y154553D01*
G01X252612Y156191D02*
X252034Y155613D01*
G01X252477Y154553D02*
X249515D01*
G01X252034Y155613D02*
X249072D01*
G01X249515Y154553D02*
X248119Y153157D01*
G01X249072Y155613D02*
X247059Y153600D01*
G01X248119Y153157D02*
Y150195D01*
G01X247059Y153600D02*
Y150638D01*
G01X248119Y150195D02*
X246110Y148186D01*
G01X247059Y150638D02*
X245667Y149246D01*
G01X246110Y148186D02*
X243148D01*
G01X245667Y149246D02*
X242705D01*
G01X243148Y148186D02*
X241752Y146790D01*
G01X242705Y149246D02*
X240692Y147233D01*
G01X241752Y146790D02*
Y143828D01*
G01X240692Y147233D02*
Y144271D01*
G01X241752Y143828D02*
X239743Y141819D01*
G01X240692Y144271D02*
X239300Y142879D01*
G01X239743Y141819D02*
X236781D01*
G01X239300Y142879D02*
X236338D01*
G01X236781Y141819D02*
X235385Y140423D01*
G01X236338Y142879D02*
X236030Y142571D01*
G01X236781Y141819D02*
X235385Y140423D01*
G01X236030Y142568D02*
X234325Y140863D01*
G01X235385Y140423D02*
Y137461D01*
G01X234325Y140863D02*
Y137901D01*
G01X257472Y167448D02*
Y154148D01*
G01X256412Y167891D02*
Y154591D01*
G01X257472Y167448D02*
Y154148D01*
G01X256412Y167891D02*
Y154591D01*
G01X296520Y137010D02*
X292684D01*
G01D02*
X291592Y135918D01*
G01X293124Y135950D02*
X292652Y135478D01*
G01X291592Y135918D02*
Y133292D01*
G01X292652Y135478D02*
Y133732D01*
G01X291592Y133292D02*
X292684Y132200D01*
G01X292652Y133732D02*
X293124Y133260D01*
G01X292684Y132200D02*
X296520D01*
G01X296992Y128680D02*
X286044Y117732D01*
G01X298052Y128240D02*
X287104Y117292D01*
G01X301332Y127030D02*
X291144Y116842D01*
G01X302392Y126590D02*
X292204Y116402D01*
G01X296520Y137010D02*
X292684D01*
G01X293124Y135950D02*
X292652Y135478D01*
G01X292684Y137010D02*
X291592Y135918D01*
G01X292652Y135478D02*
Y133732D01*
G01X291592Y135918D02*
Y133292D01*
G01X292652Y133732D02*
X293124Y133260D01*
G01X291592Y133292D02*
X292684Y132200D01*
G01D02*
X296520D01*
G01X298052Y128240D02*
X287104Y117292D01*
G01X296992Y128680D02*
X286044Y117732D01*
G01X302392Y126590D02*
X292204Y116402D01*
G01X301332Y127030D02*
X291144Y116842D01*
G01X233117Y192854D02*
X234071Y193808D01*
G01X235662Y195399D02*
X236615Y196352D01*
G01X238206Y197943D02*
X239160Y198897D01*
G01X240751Y200488D02*
X241704Y201441D01*
G01X243295Y203032D02*
X244249Y203986D01*
G01X245840Y205577D02*
X246793Y206530D01*
G01X248384Y208121D02*
X249338Y209075D01*
G01X250929Y210666D02*
X251882Y211619D01*
G01X253473Y213210D02*
X254682Y214419D01*
G01X256273Y216010D02*
X257242Y216979D01*
G01X256182Y217419D02*
Y221005D01*
G01X257242Y216979D02*
Y220565D01*
G01X268213Y188065D02*
X265532Y185384D01*
G01X268964Y187316D02*
X266592Y184944D01*
G01X265532Y185384D02*
Y182508D01*
G01X266592Y184944D02*
Y182068D01*
G01X265529Y182508D02*
X252612Y169591D01*
G01X266592Y182068D02*
X265638Y181114D01*
G01X265529Y182508D02*
X252612Y169591D01*
G01X264683Y179523D02*
X264047D01*
G01X265529Y182508D02*
X252612Y169591D01*
G01X264047Y179523D02*
X263094Y178570D01*
G01X265529Y182508D02*
X252612Y169591D01*
G01X262139Y176979D02*
X261503D01*
G01X265529Y182508D02*
X252612Y169591D01*
G01X261503Y176979D02*
X260549Y176025D01*
G01X265529Y182508D02*
X252612Y169591D01*
G01X259594Y174434D02*
X258958D01*
G01X265529Y182508D02*
X252612Y169591D01*
G01X258958Y174434D02*
X258005Y173481D01*
G01X265529Y182508D02*
X252612Y169591D01*
G01X257050Y171890D02*
X256414D01*
G01X265529Y182508D02*
X252612Y169591D01*
G01X256414Y171890D02*
X253672Y169148D01*
G01D02*
Y167799D01*
G01Y165549D02*
Y164201D01*
G01Y161951D02*
Y160602D01*
G01X272769Y185959D02*
X269542Y182732D01*
G01X273519Y185209D02*
X270602Y182292D01*
G01X269542Y182732D02*
Y181018D01*
G01X270602Y182292D02*
Y180578D01*
G01X269542Y181018D02*
X256414Y167890D01*
G01X270602Y180578D02*
X269648Y179624D01*
G01X269542Y181018D02*
X256414Y167890D01*
G01X268693Y178033D02*
X268057D01*
G01X269542Y181018D02*
X256414Y167890D01*
G01X268057Y178033D02*
X267104Y177080D01*
G01X269542Y181018D02*
X256414Y167890D01*
G01X266149Y175489D02*
X265513D01*
G01X269542Y181018D02*
X256414Y167890D01*
G01X265513Y175489D02*
X264559Y174535D01*
G01X269542Y181018D02*
X256414Y167890D01*
G01X263486Y172944D02*
X262968D01*
G01X269542Y181018D02*
X256414Y167890D01*
G01X262968Y172944D02*
X257472Y167448D01*
G01X233117Y192854D02*
X234071Y193808D01*
G01X235662Y195399D02*
X236615Y196352D01*
G01X238206Y197943D02*
X239160Y198897D01*
G01X240751Y200488D02*
X241704Y201441D01*
G01X243295Y203032D02*
X244249Y203986D01*
G01X245840Y205577D02*
X246793Y206530D01*
G01X248384Y208121D02*
X249338Y209075D01*
G01X250929Y210666D02*
X251882Y211619D01*
G01X253473Y213210D02*
X254682Y214419D01*
G01X256273Y216010D02*
X257242Y216979D01*
G01D02*
Y220565D01*
G01X256182Y217419D02*
Y221005D01*
G01X268964Y187316D02*
X266592Y184944D01*
G01X268213Y188065D02*
X265532Y185384D01*
G01X266592Y184944D02*
Y182068D01*
G01X265532Y185384D02*
Y182508D01*
G01X266592Y182068D02*
X265638Y181114D01*
G01X264683Y179523D02*
X264047D01*
G01D02*
X263094Y178570D01*
G01X262139Y176979D02*
X261503D01*
G01D02*
X260549Y176025D01*
G01X259594Y174434D02*
X258958D01*
G01D02*
X258005Y173481D01*
G01X257050Y171890D02*
X256414D01*
G01D02*
X253672Y169148D01*
G01X265529Y182508D02*
X252612Y169591D01*
G01X253672Y169148D02*
Y167799D01*
G01Y165549D02*
Y164201D01*
G01Y161951D02*
Y160602D01*
G01X233117Y192854D02*
X234071Y193808D01*
G01X235662Y195399D02*
X236615Y196352D01*
G01X238206Y197943D02*
X239160Y198897D01*
G01X240751Y200488D02*
X241704Y201441D01*
G01X243295Y203032D02*
X244249Y203986D01*
G01X245840Y205577D02*
X246793Y206530D01*
G01X248384Y208121D02*
X249338Y209075D01*
G01X250929Y210666D02*
X251882Y211619D01*
G01X253473Y213210D02*
X254682Y214419D01*
G01X256273Y216010D02*
X257242Y216979D01*
G01X256182Y217419D02*
Y221005D01*
G01X257242Y216979D02*
Y220565D01*
G01X268213Y188065D02*
X265532Y185384D01*
G01X268964Y187316D02*
X266592Y184944D01*
G01X265532Y185384D02*
Y182508D01*
G01X266592Y184944D02*
Y182068D01*
G01X265529Y182508D02*
X252612Y169591D01*
G01X266592Y182068D02*
X265638Y181114D01*
G01X265529Y182508D02*
X252612Y169591D01*
G01X264683Y179523D02*
X264047D01*
G01X265529Y182508D02*
X252612Y169591D01*
G01X264047Y179523D02*
X263094Y178570D01*
G01X265529Y182508D02*
X252612Y169591D01*
G01X262139Y176979D02*
X261503D01*
G01X265529Y182508D02*
X252612Y169591D01*
G01X261503Y176979D02*
X260549Y176025D01*
G01X265529Y182508D02*
X252612Y169591D01*
G01X259594Y174434D02*
X258958D01*
G01X265529Y182508D02*
X252612Y169591D01*
G01X258958Y174434D02*
X258005Y173481D01*
G01X265529Y182508D02*
X252612Y169591D01*
G01X257050Y171890D02*
X256414D01*
G01X265529Y182508D02*
X252612Y169591D01*
G01X256414Y171890D02*
X253672Y169148D01*
G01D02*
Y167799D01*
G01Y165549D02*
Y164201D01*
G01Y161951D02*
Y160602D01*
G01X272769Y185959D02*
X269542Y182732D01*
G01X273519Y185209D02*
X270602Y182292D01*
G01X269542Y182732D02*
Y181018D01*
G01X270602Y182292D02*
Y180578D01*
G01X269542Y181018D02*
X256414Y167890D01*
G01X270602Y180578D02*
X269648Y179624D01*
G01X269542Y181018D02*
X256414Y167890D01*
G01X268693Y178033D02*
X268057D01*
G01X269542Y181018D02*
X256414Y167890D01*
G01X268057Y178033D02*
X267104Y177080D01*
G01X269542Y181018D02*
X256414Y167890D01*
G01X266149Y175489D02*
X265513D01*
G01X269542Y181018D02*
X256414Y167890D01*
G01X265513Y175489D02*
X264559Y174535D01*
G01X269542Y181018D02*
X256414Y167890D01*
G01X263486Y172944D02*
X262968D01*
G01X269542Y181018D02*
X256414Y167890D01*
G01X262968Y172944D02*
X257472Y167448D01*
G01X233117Y192854D02*
X234071Y193808D01*
G01X235662Y195399D02*
X236615Y196352D01*
G01X238206Y197943D02*
X239160Y198897D01*
G01X240751Y200488D02*
X241704Y201441D01*
G01X243295Y203032D02*
X244249Y203986D01*
G01X245840Y205577D02*
X246793Y206530D01*
G01X248384Y208121D02*
X249338Y209075D01*
G01X250929Y210666D02*
X251882Y211619D01*
G01X253473Y213210D02*
X254682Y214419D01*
G01X256273Y216010D02*
X257242Y216979D01*
G01D02*
Y220565D01*
G01X256182Y217419D02*
Y221005D01*
G01X268964Y187316D02*
X266592Y184944D01*
G01X268213Y188065D02*
X265532Y185384D01*
G01X266592Y184944D02*
Y182068D01*
G01X265532Y185384D02*
Y182508D01*
G01X266592Y182068D02*
X265638Y181114D01*
G01X264683Y179523D02*
X264047D01*
G01D02*
X263094Y178570D01*
G01X262139Y176979D02*
X261503D01*
G01D02*
X260549Y176025D01*
G01X259594Y174434D02*
X258958D01*
G01D02*
X258005Y173481D01*
G01X257050Y171890D02*
X256414D01*
G01D02*
X253672Y169148D01*
G01X265529Y182508D02*
X252612Y169591D01*
G01X253672Y169148D02*
Y167799D01*
G01Y165549D02*
Y164201D01*
G01Y161951D02*
Y160602D01*
G01X273519Y185209D02*
X270602Y182292D01*
G01X272769Y185959D02*
X269542Y182732D01*
G01X270602Y182292D02*
Y180578D01*
G01X269542Y182732D02*
Y181018D01*
G01X270602Y180578D02*
X269648Y179624D01*
G01X268693Y178033D02*
X268057D01*
G01D02*
X267104Y177080D01*
G01X266149Y175489D02*
X265513D01*
G01D02*
X264559Y174535D01*
G01X263486Y172944D02*
X262968D01*
G01D02*
X257472Y167448D01*
G01X269542Y181018D02*
X256414Y167890D01*
G01X273519Y185209D02*
X270602Y182292D01*
G01X272769Y185959D02*
X269542Y182732D01*
G01X270602Y182292D02*
Y180578D01*
G01X269542Y182732D02*
Y181018D01*
G01X270602Y180578D02*
X269648Y179624D01*
G01X268693Y178033D02*
X268057D01*
G01D02*
X267104Y177080D01*
G01X266149Y175489D02*
X265513D01*
G01D02*
X264559Y174535D01*
G01X263486Y172944D02*
X262968D01*
G01D02*
X257472Y167448D01*
G01X269542Y181018D02*
X256414Y167890D01*
G01X243032Y244340D02*
Y245670D01*
G01X244092Y243900D02*
Y245230D01*
G01X243032Y245670D02*
X257702Y260340D01*
G01X244092Y245230D02*
X245420Y246558D01*
G01X243032Y245670D02*
X257702Y260340D01*
G01X247011Y248149D02*
X247965Y249103D01*
G01X243032Y245670D02*
X257702Y260340D01*
G01X249556Y250694D02*
X250509Y251647D01*
G01X243032Y245670D02*
X257702Y260340D01*
G01X252100Y253238D02*
X253053Y254191D01*
G01X243032Y245670D02*
X257702Y260340D01*
G01X254644Y255782D02*
X255598Y256736D01*
G01X243032Y245670D02*
X257702Y260340D01*
G01X257189Y258327D02*
X258142Y259280D01*
G01X257702Y260340D02*
X261755D01*
G01X258142Y259280D02*
X261755D01*
G01X233017Y239326D02*
X233971Y240280D01*
G01X235562Y241871D02*
X236515Y242824D01*
G01X238106Y244415D02*
X239060Y245369D01*
G01X240651Y246960D02*
X241604Y247913D01*
G01X243195Y249504D02*
X244149Y250458D01*
G01X245740Y252049D02*
X246693Y253002D01*
G01X248284Y254593D02*
X249238Y255547D01*
G01X250829Y257138D02*
X251782Y258091D01*
G01X253373Y259682D02*
X254327Y260636D01*
G01X255918Y262227D02*
X256871Y263180D01*
G01X256431Y264240D02*
X258392D01*
G01X256871Y263180D02*
X258392D01*
G01X233017Y239326D02*
X233971Y240280D01*
G01X235562Y241871D02*
X236515Y242824D01*
G01X238106Y244415D02*
X239060Y245369D01*
G01X240651Y246960D02*
X241604Y247913D01*
G01X243195Y249504D02*
X244149Y250458D01*
G01X245740Y252049D02*
X246693Y253002D01*
G01X248284Y254593D02*
X249238Y255547D01*
G01X250829Y257138D02*
X251782Y258091D01*
G01X253373Y259682D02*
X254327Y260636D01*
G01X255918Y262227D02*
X256871Y263180D01*
G01D02*
X258392D01*
G01X256431Y264240D02*
X258392D01*
G01X243032Y244340D02*
Y245670D01*
G01X244092Y243900D02*
Y245230D01*
G01X243032Y245670D02*
X257702Y260340D01*
G01X244092Y245230D02*
X245420Y246558D01*
G01X243032Y245670D02*
X257702Y260340D01*
G01X247011Y248149D02*
X247965Y249103D01*
G01X243032Y245670D02*
X257702Y260340D01*
G01X249556Y250694D02*
X250509Y251647D01*
G01X243032Y245670D02*
X257702Y260340D01*
G01X252100Y253238D02*
X253053Y254191D01*
G01X243032Y245670D02*
X257702Y260340D01*
G01X254644Y255782D02*
X255598Y256736D01*
G01X243032Y245670D02*
X257702Y260340D01*
G01X257189Y258327D02*
X258142Y259280D01*
G01X257702Y260340D02*
X261755D01*
G01X258142Y259280D02*
X261755D01*
G01X233017Y239326D02*
X233971Y240280D01*
G01X235562Y241871D02*
X236515Y242824D01*
G01X238106Y244415D02*
X239060Y245369D01*
G01X240651Y246960D02*
X241604Y247913D01*
G01X243195Y249504D02*
X244149Y250458D01*
G01X245740Y252049D02*
X246693Y253002D01*
G01X248284Y254593D02*
X249238Y255547D01*
G01X250829Y257138D02*
X251782Y258091D01*
G01X253373Y259682D02*
X254327Y260636D01*
G01X255918Y262227D02*
X256871Y263180D01*
G01X256431Y264240D02*
X258392D01*
G01X256871Y263180D02*
X258392D01*
G01X244092Y243900D02*
Y245230D01*
G01X243032Y244340D02*
Y245670D01*
G01X244092Y245230D02*
X245420Y246558D01*
G01X247011Y248149D02*
X247965Y249103D01*
G01X249556Y250694D02*
X250509Y251647D01*
G01X252100Y253238D02*
X253053Y254191D01*
G01X254644Y255782D02*
X255598Y256736D01*
G01X257189Y258327D02*
X258142Y259280D01*
G01X243032Y245670D02*
X257702Y260340D01*
G01X258142Y259280D02*
X261755D01*
G01X257702Y260340D02*
X261755D01*
G01X244092Y243900D02*
Y245230D01*
G01X243032Y244340D02*
Y245670D01*
G01X244092Y245230D02*
X245420Y246558D01*
G01X247011Y248149D02*
X247965Y249103D01*
G01X249556Y250694D02*
X250509Y251647D01*
G01X252100Y253238D02*
X253053Y254191D01*
G01X254644Y255782D02*
X255598Y256736D01*
G01X257189Y258327D02*
X258142Y259280D01*
G01X243032Y245670D02*
X257702Y260340D01*
G01X258142Y259280D02*
X261755D01*
G01X257702Y260340D02*
X261755D01*
G01X233017Y239326D02*
X233971Y240280D01*
G01X235562Y241871D02*
X236515Y242824D01*
G01X238106Y244415D02*
X239060Y245369D01*
G01X240651Y246960D02*
X241604Y247913D01*
G01X243195Y249504D02*
X244149Y250458D01*
G01X245740Y252049D02*
X246693Y253002D01*
G01X248284Y254593D02*
X249238Y255547D01*
G01X250829Y257138D02*
X251782Y258091D01*
G01X253373Y259682D02*
X254327Y260636D01*
G01X255918Y262227D02*
X256871Y263180D01*
G01D02*
X258392D01*
G01X256431Y264240D02*
X258392D01*
G01X256182Y221005D02*
X259534Y224357D01*
G01X257242Y220565D02*
X260284Y223607D01*
G01X270766Y225068D02*
X272703Y227005D01*
G01X271643Y227445D02*
Y230644D01*
G01X272703Y227005D02*
Y230644D01*
G01X257242Y220565D02*
X260284Y223607D01*
G01X256182Y221005D02*
X259534Y224357D01*
G01X256182Y221005D02*
X259534Y224357D01*
G01X257242Y220565D02*
X260284Y223607D01*
G01X270766Y225068D02*
X272703Y227005D01*
G01X271643Y227445D02*
Y230644D01*
G01X272703Y227005D02*
Y230644D01*
G01X257242Y220565D02*
X260284Y223607D01*
G01X256182Y221005D02*
X259534Y224357D01*
G01X270766Y225068D02*
X272703Y227005D01*
G01D02*
Y230644D01*
G01X271643Y227445D02*
Y230644D01*
G01X270766Y225068D02*
X272703Y227005D01*
G01D02*
Y230644D01*
G01X271643Y227445D02*
Y230644D01*
G01X253203Y337989D02*
X255384D01*
G01X252763Y336929D02*
X255384D01*
G01X251742Y332920D02*
X260505D01*
G01X252182Y333980D02*
X260505D01*
G01X252763Y336929D02*
X255384D01*
G01X253203Y337989D02*
X255384D01*
G01X252182Y333980D02*
X260505D01*
G01X251742Y332920D02*
X260505D01*
G01X253203Y337989D02*
X255384D01*
G01X252763Y336929D02*
X255384D01*
G01X251742Y332920D02*
X260505D01*
G01X252182Y333980D02*
X260505D01*
G01X252763Y336929D02*
X255384D01*
G01X253203Y337989D02*
X255384D01*
G01X252182Y333980D02*
X260505D01*
G01X251742Y332920D02*
X260505D01*
G01X241792Y384535D02*
Y390004D01*
G01X242852Y390444D02*
Y384975D01*
G01X261653Y364674D02*
X241792Y384535D01*
G01X242852Y384975D02*
X252625Y375202D01*
G01X261653Y364674D02*
X241792Y384535D01*
G01X252627Y375202D02*
X262404Y365426D01*
G01X242852Y384975D02*
X252625Y375202D01*
G01X252627D02*
X262404Y365426D01*
G01X261653Y364674D02*
X241792Y384535D01*
G01X242852Y390444D02*
Y384975D01*
G01X241792Y384535D02*
Y390004D01*
G01X246352Y386865D02*
X249652Y383565D01*
G01Y383564D02*
X260747Y372469D01*
G01X259997Y371718D02*
X245292Y386423D01*
G01X246352Y391841D02*
Y386865D01*
G01X245292Y386423D02*
Y391401D01*
G01Y386423D02*
Y391401D01*
G01X246352Y391841D02*
Y386865D01*
G01X259997Y371718D02*
X245292Y386423D01*
G01X246352Y386865D02*
X249652Y383565D01*
G01X259997Y371718D02*
X245292Y386423D01*
G01X249652Y383564D02*
X260747Y372469D01*
G01X241792Y384535D02*
Y390004D01*
G01X242852Y390444D02*
Y384975D01*
G01X261653Y364674D02*
X241792Y384535D01*
G01X242852Y384975D02*
X252625Y375202D01*
G01X261653Y364674D02*
X241792Y384535D01*
G01X252627Y375202D02*
X262404Y365426D01*
G01X246352Y386865D02*
X249652Y383565D01*
G01Y383564D02*
X260747Y372469D01*
G01X259997Y371718D02*
X245292Y386423D01*
G01X246352Y391841D02*
Y386865D01*
G01X245292Y386423D02*
Y391401D01*
G01X242852Y384975D02*
X252625Y375202D01*
G01X252627D02*
X262404Y365426D01*
G01X261653Y364674D02*
X241792Y384535D01*
G01X242852Y390444D02*
Y384975D01*
G01X241792Y384535D02*
Y390004D01*
G01X245292Y386423D02*
Y391401D01*
G01X246352Y391841D02*
Y386865D01*
G01X259997Y371718D02*
X245292Y386423D01*
G01X246352Y386865D02*
X249652Y383565D01*
G01X259997Y371718D02*
X245292Y386423D01*
G01X249652Y383564D02*
X260747Y372469D01*
G01X268913Y408533D02*
X266792Y410654D01*
G01X269663Y409283D02*
X267852Y411094D01*
G01X266792Y410654D02*
Y417129D01*
G01X267852Y411094D02*
Y417572D01*
G01X266792Y417129D02*
X253812Y430109D01*
G01X267852Y417572D02*
X254872Y430552D01*
G01X253812Y430109D02*
Y448889D01*
G01X254872Y430552D02*
Y449329D01*
G01X274243Y410063D02*
X273009Y411297D01*
G01X273493Y409313D02*
X271949Y410857D01*
G01X273009Y411297D02*
Y417955D01*
G01X271949Y410857D02*
Y417515D01*
G01X273009Y417955D02*
X258672Y432292D01*
G01X271949Y417515D02*
X257615Y431849D01*
G01X258672Y432292D02*
Y451065D01*
G01X257612Y431849D02*
Y450625D01*
G01X258672Y451065D02*
X246606Y463131D01*
G01X257612Y450625D02*
X245546Y462691D01*
G01X246606Y463131D02*
Y468009D01*
G01X245546Y462691D02*
Y467569D01*
G01X269663Y409283D02*
X267852Y411094D01*
G01X268913Y408533D02*
X266792Y410654D01*
G01X267852Y411094D02*
Y417572D01*
G01X266792Y410654D02*
Y417129D01*
G01X267852Y417572D02*
X254872Y430552D01*
G01X266792Y417129D02*
X253812Y430109D01*
G01X254872Y430552D02*
Y449329D01*
G01X253812Y430109D02*
Y448889D01*
G01X273493Y409313D02*
X271949Y410857D01*
G01X274243Y410063D02*
X273009Y411297D01*
G01X271949Y410857D02*
Y417515D01*
G01X273009Y411297D02*
Y417955D01*
G01X271949Y417515D02*
X257615Y431849D01*
G01X273009Y417955D02*
X258672Y432292D01*
G01X257612Y431849D02*
Y450625D01*
G01X258672Y432292D02*
Y451065D01*
G01X257612Y450625D02*
X245546Y462691D01*
G01X258672Y451065D02*
X246606Y463131D01*
G01X245546Y462691D02*
Y467569D01*
G01X246606Y463131D02*
Y468009D01*
G01X268913Y408533D02*
X266792Y410654D01*
G01X269663Y409283D02*
X267852Y411094D01*
G01X266792Y410654D02*
Y417129D01*
G01X267852Y411094D02*
Y417572D01*
G01X266792Y417129D02*
X253812Y430109D01*
G01X267852Y417572D02*
X254872Y430552D01*
G01X253812Y430109D02*
Y448889D01*
G01X254872Y430552D02*
Y449329D01*
G01X274243Y410063D02*
X273009Y411297D01*
G01X273493Y409313D02*
X271949Y410857D01*
G01X273009Y411297D02*
Y417955D01*
G01X271949Y410857D02*
Y417515D01*
G01X273009Y417955D02*
X258672Y432292D01*
G01X271949Y417515D02*
X257615Y431849D01*
G01X258672Y432292D02*
Y451065D01*
G01X257612Y431849D02*
Y450625D01*
G01X258672Y451065D02*
X246606Y463131D01*
G01X257612Y450625D02*
X245546Y462691D01*
G01X246606Y463131D02*
Y468009D01*
G01X245546Y462691D02*
Y467569D01*
G01X269663Y409283D02*
X267852Y411094D01*
G01X268913Y408533D02*
X266792Y410654D01*
G01X267852Y411094D02*
Y417572D01*
G01X266792Y410654D02*
Y417129D01*
G01X267852Y417572D02*
X254872Y430552D01*
G01X266792Y417129D02*
X253812Y430109D01*
G01X254872Y430552D02*
Y449329D01*
G01X253812Y430109D02*
Y448889D01*
G01X273493Y409313D02*
X271949Y410857D01*
G01X274243Y410063D02*
X273009Y411297D01*
G01X271949Y410857D02*
Y417515D01*
G01X273009Y411297D02*
Y417955D01*
G01X271949Y417515D02*
X257615Y431849D01*
G01X273009Y417955D02*
X258672Y432292D01*
G01X257612Y431849D02*
Y450625D01*
G01X258672Y432292D02*
Y451065D01*
G01X257612Y450625D02*
X245546Y462691D01*
G01X258672Y451065D02*
X246606Y463131D01*
G01X245546Y462691D02*
Y467569D01*
G01X246606Y463131D02*
Y468009D01*
G01X315175Y413361D02*
X290314Y438222D01*
G01X316235Y413801D02*
X291372Y438664D01*
G01X290312Y438222D02*
Y449609D01*
G01X291372Y438664D02*
Y450052D01*
G01X290312Y449609D02*
X283912Y456009D01*
G01X291372Y450052D02*
X288126Y453298D01*
G01X290312Y449609D02*
X283912Y456009D01*
G01X286266Y455158D02*
X284972Y456452D01*
G01X283912Y456009D02*
Y485449D01*
G01X284972Y456452D02*
Y461378D01*
G01X283912Y456009D02*
Y485449D01*
G01X284972Y464008D02*
Y485009D01*
G01X293960Y456556D02*
X291344D01*
G01X293520Y455496D02*
X290904D01*
G01X291344Y456556D02*
X290472Y457428D01*
G01X290904Y455496D02*
X289412Y456988D01*
G01X290472Y457428D02*
Y459124D01*
G01X289412Y456988D02*
Y459564D01*
G01X290472Y459124D02*
X291344Y459996D01*
G01X289412Y459564D02*
X290904Y461056D01*
G01X291344Y459996D02*
X293509D01*
G01X290904Y461056D02*
X293069D01*
G01D02*
X293569Y461556D01*
G01X293069Y464720D02*
X289504D01*
G01D02*
X287812Y466412D01*
G01X316235Y413801D02*
X291372Y438664D01*
G01X315175Y413361D02*
X290314Y438222D01*
G01X291372Y438664D02*
Y450052D01*
G01X290312Y438222D02*
Y449609D01*
G01X291372Y450052D02*
X288126Y453298D01*
G01X286266Y455158D02*
X284972Y456452D01*
G01X290312Y449609D02*
X283912Y456009D01*
G01X284972Y456452D02*
Y461378D01*
G01Y464008D02*
Y485009D01*
G01X283912Y456009D02*
Y485449D01*
G01X293520Y455496D02*
X290904D01*
G01X293960Y456556D02*
X291344D01*
G01X290904Y455496D02*
X289412Y456988D01*
G01X291344Y456556D02*
X290472Y457428D01*
G01X289412Y456988D02*
Y459564D01*
G01X290472Y457428D02*
Y459124D01*
G01X289412Y459564D02*
X290904Y461056D01*
G01X290472Y459124D02*
X291344Y459996D01*
G01X290904Y461056D02*
X293069D01*
G01X291344Y459996D02*
X293509D01*
G01X293069Y461056D02*
X293569Y461556D01*
G01X293069Y464720D02*
X289504D01*
G01D02*
X287812Y466412D01*
G01X246606Y468009D02*
X244468Y470147D01*
G01X245546Y467569D02*
X244028Y469087D01*
G01X244468Y470147D02*
X242342D01*
G01X244028Y469087D02*
X242782D01*
G01X242342Y470147D02*
X241580Y469385D01*
G01D02*
X240355D01*
G01X242782Y469087D02*
X242020Y468325D01*
G01X241580Y469385D02*
X240355D01*
G01X242020Y468325D02*
X239912D01*
G01X240355Y469385D02*
X238585Y471155D01*
G01X239912Y468325D02*
X237525Y470712D01*
G01X238585Y471155D02*
Y472383D01*
G01X237525Y470712D02*
Y472826D01*
G01X238585Y472383D02*
X239895Y473693D01*
G01X237525Y472826D02*
X238835Y474136D01*
G01X239895Y473693D02*
Y475804D01*
G01X238835Y474136D02*
Y475361D01*
G01X239895Y475804D02*
X237502Y478197D01*
G01X238835Y475361D02*
X237059Y477137D01*
G01X237502Y478197D02*
X235395D01*
G01X237059Y477137D02*
X235835D01*
G01X235395Y478197D02*
X234558Y477360D01*
G01X235835Y477137D02*
X234998Y476300D01*
G01X234558Y477360D02*
X232377D01*
G01X234998Y476300D02*
X231937D01*
G01X245546Y467569D02*
X244028Y469087D01*
G01X246606Y468009D02*
X244468Y470147D01*
G01X244028Y469087D02*
X242782D01*
G01X244468Y470147D02*
X242342D01*
G01X242782Y469087D02*
X242020Y468325D01*
G01X242342Y470147D02*
X241580Y469385D01*
G01X242782Y469087D02*
X242020Y468325D01*
G01D02*
X239912D01*
G01X241580Y469385D02*
X240355D01*
G01X239912Y468325D02*
X237525Y470712D01*
G01X240355Y469385D02*
X238585Y471155D01*
G01X237525Y470712D02*
Y472826D01*
G01X238585Y471155D02*
Y472383D01*
G01X237525Y472826D02*
X238835Y474136D01*
G01X238585Y472383D02*
X239895Y473693D01*
G01X238835Y474136D02*
Y475361D01*
G01X239895Y473693D02*
Y475804D01*
G01X238835Y475361D02*
X237059Y477137D01*
G01X239895Y475804D02*
X237502Y478197D01*
G01X237059Y477137D02*
X235835D01*
G01X237502Y478197D02*
X235395D01*
G01X235835Y477137D02*
X234998Y476300D01*
G01X235395Y478197D02*
X234558Y477360D01*
G01X234998Y476300D02*
X231937D01*
G01X234558Y477360D02*
X232377D01*
G01X246606Y468009D02*
X244468Y470147D01*
G01X245546Y467569D02*
X244028Y469087D01*
G01X244468Y470147D02*
X242342D01*
G01X244028Y469087D02*
X242782D01*
G01X242342Y470147D02*
X241580Y469385D01*
G01D02*
X240355D01*
G01X242782Y469087D02*
X242020Y468325D01*
G01X241580Y469385D02*
X240355D01*
G01X242020Y468325D02*
X239912D01*
G01X240355Y469385D02*
X238585Y471155D01*
G01X239912Y468325D02*
X237525Y470712D01*
G01X238585Y471155D02*
Y472383D01*
G01X237525Y470712D02*
Y472826D01*
G01X238585Y472383D02*
X239895Y473693D01*
G01X237525Y472826D02*
X238835Y474136D01*
G01X239895Y473693D02*
Y475804D01*
G01X238835Y474136D02*
Y475361D01*
G01X239895Y475804D02*
X237502Y478197D01*
G01X238835Y475361D02*
X237059Y477137D01*
G01X237502Y478197D02*
X235395D01*
G01X237059Y477137D02*
X235835D01*
G01X235395Y478197D02*
X234558Y477360D01*
G01X235835Y477137D02*
X234998Y476300D01*
G01X234558Y477360D02*
X232377D01*
G01X234998Y476300D02*
X231937D01*
G01X245546Y467569D02*
X244028Y469087D01*
G01X246606Y468009D02*
X244468Y470147D01*
G01X244028Y469087D02*
X242782D01*
G01X244468Y470147D02*
X242342D01*
G01X242782Y469087D02*
X242020Y468325D01*
G01X242342Y470147D02*
X241580Y469385D01*
G01X242782Y469087D02*
X242020Y468325D01*
G01D02*
X239912D01*
G01X241580Y469385D02*
X240355D01*
G01X239912Y468325D02*
X237525Y470712D01*
G01X240355Y469385D02*
X238585Y471155D01*
G01X237525Y470712D02*
Y472826D01*
G01X238585Y471155D02*
Y472383D01*
G01X237525Y472826D02*
X238835Y474136D01*
G01X238585Y472383D02*
X239895Y473693D01*
G01X238835Y474136D02*
Y475361D01*
G01X239895Y473693D02*
Y475804D01*
G01X238835Y475361D02*
X237059Y477137D01*
G01X239895Y475804D02*
X237502Y478197D01*
G01X237059Y477137D02*
X235835D01*
G01X237502Y478197D02*
X235395D01*
G01X235835Y477137D02*
X234998Y476300D01*
G01X235395Y478197D02*
X234558Y477360D01*
G01X234998Y476300D02*
X231937D01*
G01X234558Y477360D02*
X232377D01*
G01X283912Y485449D02*
X286044Y487581D01*
G01X284972Y485009D02*
X287104Y487141D01*
G01X286044Y487581D02*
Y559472D01*
G01X287104Y487141D02*
Y587820D01*
G01X293569Y464220D02*
X293069Y464720D01*
G01X293509Y465780D02*
X289944D01*
G01D02*
X288872Y466852D01*
G01D02*
Y483409D01*
G01X287812Y466412D02*
Y483852D01*
G01X288872Y483409D02*
X292204Y486741D01*
G01X287812Y483852D02*
X291144Y487184D01*
G01X292204Y486741D02*
Y588034D01*
G01X291144Y487184D02*
Y519146D01*
G01X292204Y486741D02*
Y588034D01*
G01X291144Y521386D02*
Y522386D01*
G01X292204Y486741D02*
Y588034D01*
G01X291144Y524626D02*
Y525626D01*
G01X292204Y486741D02*
Y588034D01*
G01Y486741D02*
Y588034D01*
G01Y486741D02*
Y588034D01*
G01Y486741D02*
Y588034D01*
G01Y486741D02*
Y588034D01*
G01Y486741D02*
Y588034D01*
G01Y486741D02*
Y588034D01*
G01Y486741D02*
Y588034D01*
G01Y486741D02*
Y588034D01*
G01Y486741D02*
Y588034D01*
G01Y486741D02*
Y588034D01*
G01X284972Y485009D02*
X287104Y487141D01*
G01X283912Y485449D02*
X286044Y487581D01*
G01X287104Y487141D02*
Y587820D01*
G01X286044Y487581D02*
Y559472D01*
G01X287104Y487141D02*
Y587820D01*
G01Y487141D02*
Y587820D01*
G01Y487141D02*
Y587820D01*
G01Y487141D02*
Y587820D01*
G01Y487141D02*
Y587820D01*
G01X293569Y464220D02*
X293069Y464720D01*
G01X293509Y465780D02*
X289944D01*
G01D02*
X288872Y466852D01*
G01X287812Y466412D02*
Y483852D01*
G01X288872Y466852D02*
Y483409D01*
G01X287812Y483852D02*
X291144Y487184D01*
G01X288872Y483409D02*
X292204Y486741D01*
G01X291144Y487184D02*
Y519146D01*
G01Y521386D02*
Y522386D01*
G01Y524626D02*
Y525626D01*
G01X292204Y486741D02*
Y588034D01*
G01X249233Y507888D02*
Y549459D01*
G01X250293Y549899D02*
Y507677D01*
G01X245486Y498841D02*
X249233Y507888D01*
G01X250293Y507677D02*
X247992Y502122D01*
G01X255393Y502501D02*
X254092Y501200D01*
G01X250586Y499194D02*
X254333Y502941D01*
G01X255393Y521500D02*
Y502501D01*
G01X254333Y502941D02*
Y521060D01*
G01X253892Y523001D02*
X255393Y521500D01*
G01X254333Y521060D02*
X252832Y522561D01*
G01X253892Y525200D02*
Y523001D01*
G01X252832Y522561D02*
Y525640D01*
G01X255393Y526701D02*
X253892Y525200D01*
G01X252832Y525640D02*
X254333Y527141D01*
G01X250293Y507677D02*
X247992Y502122D01*
G01X245486Y498841D02*
X249233Y507888D01*
G01X250293Y549899D02*
Y507677D01*
G01X249233Y507888D02*
Y549459D01*
G01X252832Y525640D02*
X254333Y527141D01*
G01X255393Y526701D02*
X253892Y525200D01*
G01X252832Y522561D02*
Y525640D01*
G01X253892Y525200D02*
Y523001D01*
G01X254333Y521060D02*
X252832Y522561D01*
G01X253892Y523001D02*
X255393Y521500D01*
G01X254333Y502941D02*
Y521060D01*
G01X255393Y521500D02*
Y502501D01*
G01X250586Y499194D02*
X254333Y502941D01*
G01X255393Y502501D02*
X254092Y501200D01*
G01X249233Y507888D02*
Y549459D01*
G01X250293Y549899D02*
Y507677D01*
G01X245486Y498841D02*
X249233Y507888D01*
G01X250293Y507677D02*
X247992Y502122D01*
G01X255393Y502501D02*
X254092Y501200D01*
G01X250586Y499194D02*
X254333Y502941D01*
G01X255393Y521500D02*
Y502501D01*
G01X254333Y502941D02*
Y521060D01*
G01X253892Y523001D02*
X255393Y521500D01*
G01X254333Y521060D02*
X252832Y522561D01*
G01X253892Y525200D02*
Y523001D01*
G01X252832Y522561D02*
Y525640D01*
G01X255393Y526701D02*
X253892Y525200D01*
G01X252832Y525640D02*
X254333Y527141D01*
G01X250293Y507677D02*
X247992Y502122D01*
G01X245486Y498841D02*
X249233Y507888D01*
G01X250293Y549899D02*
Y507677D01*
G01X249233Y507888D02*
Y549459D01*
G01X252832Y525640D02*
X254333Y527141D01*
G01X255393Y526701D02*
X253892Y525200D01*
G01X252832Y522561D02*
Y525640D01*
G01X253892Y525200D02*
Y523001D01*
G01X254333Y521060D02*
X252832Y522561D01*
G01X253892Y523001D02*
X255393Y521500D01*
G01X254333Y502941D02*
Y521060D01*
G01X255393Y521500D02*
Y502501D01*
G01X250586Y499194D02*
X254333Y502941D01*
G01X255393Y502501D02*
X254092Y501200D01*
G01X286044Y561500D02*
Y562659D01*
G01Y564765D02*
Y575895D01*
G01Y577711D02*
Y578923D01*
G01Y581163D02*
Y582163D01*
G01Y584403D02*
Y587380D01*
G01D02*
X285124Y588300D01*
G01X287104Y587820D02*
X284024Y590900D01*
G01X291144Y527866D02*
Y538293D01*
G01Y540533D02*
Y541533D01*
G01Y543773D02*
Y544773D01*
G01Y547013D02*
Y556987D01*
G01Y559227D02*
Y560227D01*
G01Y562467D02*
Y563626D01*
G01Y565574D02*
Y572284D01*
G01Y574154D02*
Y576292D01*
G01Y578054D02*
Y579293D01*
G01Y581533D02*
Y582533D01*
G01Y584773D02*
Y587594D01*
G01X292204Y588034D02*
X289124Y591114D01*
G01X291144Y587594D02*
X290224Y588514D01*
G01X286044Y561500D02*
Y562659D01*
G01Y564765D02*
Y575895D01*
G01Y577711D02*
Y578923D01*
G01Y581163D02*
Y582163D01*
G01Y584403D02*
Y587380D01*
G01X287104Y587820D02*
X284024Y590900D01*
G01X286044Y587380D02*
X285124Y588300D01*
G01X291144Y527866D02*
Y538293D01*
G01Y540533D02*
Y541533D01*
G01Y543773D02*
Y544773D01*
G01Y547013D02*
Y556987D01*
G01Y559227D02*
Y560227D01*
G01Y562467D02*
Y563626D01*
G01Y565574D02*
Y572284D01*
G01Y574154D02*
Y576292D01*
G01Y578054D02*
Y579293D01*
G01Y581533D02*
Y582533D01*
G01Y584773D02*
Y587594D01*
G01D02*
X290224Y588514D01*
G01X292204Y588034D02*
X289124Y591114D01*
G01X245225Y552200D02*
Y570211D01*
G01X246285Y564560D02*
Y563140D01*
G01X245225Y552200D02*
Y570211D01*
G01X246285Y559460D02*
Y558090D01*
G01X249233Y549459D02*
X248192Y550500D01*
G01X247213Y552979D02*
X250293Y549899D01*
G01X250838Y558371D02*
X251509Y557700D01*
G01X250608Y557100D02*
X249778Y557930D01*
G01X250838Y564029D02*
Y563138D01*
G01Y559648D02*
Y558371D01*
G01X249778Y557930D02*
Y564470D01*
G01X251609Y564800D02*
X250838Y564029D01*
G01X249778Y564470D02*
X250608Y565300D01*
G01X255393Y550235D02*
Y526701D01*
G01X254333Y527141D02*
Y548695D01*
G01X246285Y564560D02*
Y563140D01*
G01Y559460D02*
Y558090D01*
G01X245225Y552200D02*
Y570211D01*
G01X247213Y552979D02*
X250293Y549899D01*
G01X249233Y549459D02*
X248192Y550500D01*
G01X249778Y564470D02*
X250608Y565300D01*
G01X251609Y564800D02*
X250838Y564029D01*
G01X249778Y557930D02*
Y564470D01*
G01X250838Y564029D02*
Y563138D01*
G01X249778Y557930D02*
Y564470D01*
G01X250838Y559648D02*
Y558371D01*
G01X250608Y557100D02*
X249778Y557930D01*
G01X250838Y558371D02*
X251509Y557700D01*
G01X254333Y527141D02*
Y548695D01*
G01X255393Y550235D02*
Y526701D01*
G01X245225Y552200D02*
Y570211D01*
G01X246285Y564560D02*
Y563140D01*
G01X245225Y552200D02*
Y570211D01*
G01X246285Y559460D02*
Y558090D01*
G01X249233Y549459D02*
X248192Y550500D01*
G01X247213Y552979D02*
X250293Y549899D01*
G01X250838Y558371D02*
X251509Y557700D01*
G01X250608Y557100D02*
X249778Y557930D01*
G01X250838Y564029D02*
Y563138D01*
G01Y559648D02*
Y558371D01*
G01X249778Y557930D02*
Y564470D01*
G01X251609Y564800D02*
X250838Y564029D01*
G01X249778Y564470D02*
X250608Y565300D01*
G01X255393Y550235D02*
Y526701D01*
G01X254333Y527141D02*
Y548695D01*
G01X246285Y564560D02*
Y563140D01*
G01Y559460D02*
Y558090D01*
G01X245225Y552200D02*
Y570211D01*
G01X247213Y552979D02*
X250293Y549899D01*
G01X249233Y549459D02*
X248192Y550500D01*
G01X249778Y564470D02*
X250608Y565300D01*
G01X251609Y564800D02*
X250838Y564029D01*
G01X249778Y557930D02*
Y564470D01*
G01X250838Y564029D02*
Y563138D01*
G01X249778Y557930D02*
Y564470D01*
G01X250838Y559648D02*
Y558371D01*
G01X250608Y557100D02*
X249778Y557930D01*
G01X250838Y558371D02*
X251509Y557700D01*
G01X254333Y527141D02*
Y548695D01*
G01X255393Y550235D02*
Y526701D01*
G01X296992Y172400D02*
Y137482D01*
G01X298052Y171960D02*
Y137042D01*
G01X296992Y137482D02*
X296520Y137010D01*
G01X298052Y137042D02*
X296960Y135950D01*
G01D02*
X293124D01*
G01Y133260D02*
X296960D01*
G01X296520Y132200D02*
X296992Y131728D01*
G01X296960Y133260D02*
X298052Y132168D01*
G01X296992Y131728D02*
Y128680D01*
G01X298052Y132168D02*
Y128240D01*
G01X301332Y170492D02*
Y127030D01*
G01X302392Y170052D02*
Y126590D01*
G01X298052Y171960D02*
Y137042D01*
G01X296992Y172400D02*
Y137482D01*
G01X298052Y137042D02*
X296960Y135950D01*
G01X296992Y137482D02*
X296520Y137010D01*
G01X296960Y135950D02*
X293124D01*
G01Y133260D02*
X296960D01*
G01D02*
X298052Y132168D01*
G01X296520Y132200D02*
X296992Y131728D01*
G01X298052Y132168D02*
Y128240D01*
G01X296992Y131728D02*
Y128680D01*
G01X302392Y170052D02*
Y126590D01*
G01X301332Y170492D02*
Y127030D01*
G01X313913Y194250D02*
Y189321D01*
G01X314973Y194250D02*
Y193050D01*
G01X313913Y194250D02*
Y189321D01*
G01X314973Y191150D02*
Y188881D01*
G01X313913Y189321D02*
X296992Y172400D01*
G01X314973Y188881D02*
X314337Y188245D01*
G01X313913Y189321D02*
X296992Y172400D01*
G01X312993Y186901D02*
X312289Y186197D01*
G01X313913Y189321D02*
X296992Y172400D01*
G01X310945Y184853D02*
X310309Y184217D01*
G01X313913Y189321D02*
X296992Y172400D01*
G01X308965Y182873D02*
X308329Y182237D01*
G01X313913Y189321D02*
X296992Y172400D01*
G01X306985Y180893D02*
X306314Y180222D01*
G01X313913Y189321D02*
X296992Y172400D01*
G01X304970Y178878D02*
X304334Y178242D01*
G01X313913Y189321D02*
X296992Y172400D01*
G01X302990Y176898D02*
X302354Y176262D01*
G01X313913Y189321D02*
X296992Y172400D01*
G01X301010Y174918D02*
X300374Y174282D01*
G01X313913Y189321D02*
X296992Y172400D01*
G01X299030Y172938D02*
X298052Y171960D01*
G01X319381Y196613D02*
Y185839D01*
G01X320441Y196613D02*
Y185399D01*
G01X319381Y185839D02*
X318652Y185110D01*
G01X320441Y185399D02*
X319092Y184050D01*
G01X318652Y185110D02*
X315950D01*
G01X319092Y184050D02*
X316390D01*
G01X315950Y185110D02*
X301332Y170492D01*
G01X316390Y184050D02*
X302392Y170052D01*
G01X314973Y194250D02*
Y193050D01*
G01Y191150D02*
Y188881D01*
G01X313913Y194250D02*
Y189321D01*
G01X314973Y188881D02*
X314337Y188245D01*
G01X312993Y186901D02*
X312289Y186197D01*
G01X310945Y184853D02*
X310309Y184217D01*
G01X308965Y182873D02*
X308329Y182237D01*
G01X306985Y180893D02*
X306314Y180222D01*
G01X304970Y178878D02*
X304334Y178242D01*
G01X302990Y176898D02*
X302354Y176262D01*
G01X301010Y174918D02*
X300374Y174282D01*
G01X299030Y172938D02*
X298052Y171960D01*
G01X313913Y189321D02*
X296992Y172400D01*
G01X320441Y196613D02*
Y185399D01*
G01X319381Y196613D02*
Y185839D01*
G01X320441Y185399D02*
X319092Y184050D01*
G01X319381Y185839D02*
X318652Y185110D01*
G01X319092Y184050D02*
X316390D01*
G01X318652Y185110D02*
X315950D01*
G01X316390Y184050D02*
X302392Y170052D01*
G01X315950Y185110D02*
X301332Y170492D01*
G01X315175Y405512D02*
Y413361D01*
G01X316235Y405512D02*
Y413801D01*
G01X320238Y409187D02*
Y415262D01*
G01X319178Y409187D02*
Y414822D01*
G01X320238Y415262D02*
X295501Y439998D01*
G01X319178Y414822D02*
X294441Y439558D01*
G01X295501Y439998D02*
Y455015D01*
G01X294441Y439558D02*
Y454575D01*
G01X295501Y455015D02*
X293960Y456556D01*
G01X294441Y454575D02*
X293520Y455496D01*
G01X293509Y459996D02*
X294629Y461116D01*
G01D02*
Y464660D01*
G01X293569Y461556D02*
Y464220D01*
G01X294629Y464660D02*
X293509Y465780D01*
G01X316235Y405512D02*
Y413801D01*
G01X315175Y405512D02*
Y413361D01*
G01X319178Y409187D02*
Y414822D01*
G01X320238Y409187D02*
Y415262D01*
G01X319178Y414822D02*
X294441Y439558D01*
G01X320238Y415262D02*
X295501Y439998D01*
G01X294441Y439558D02*
Y454575D01*
G01X295501Y439998D02*
Y455015D01*
G01X294441Y454575D02*
X293520Y455496D01*
G01X295501Y455015D02*
X293960Y456556D01*
G01X293509Y459996D02*
X294629Y461116D01*
G01X293569Y461556D02*
Y464220D01*
G01X294629Y461116D02*
Y464660D01*
G01D02*
X293509Y465780D01*
G01X377532Y40325D02*
X369986Y32779D01*
G01X378592Y39885D02*
X370426Y31719D01*
G01X369986Y32779D02*
X364142D01*
G01X370426Y31719D02*
X364582D01*
G01X364142Y32779D02*
X362286Y30923D01*
G01X364582Y31719D02*
X363346Y30483D01*
G01X362286Y30923D02*
Y29082D01*
G01X363346Y30483D02*
Y29233D01*
G01X378592Y39885D02*
X370426Y31719D01*
G01X377532Y40325D02*
X369986Y32779D01*
G01X370426Y31719D02*
X364582D01*
G01X369986Y32779D02*
X364142D01*
G01X364582Y31719D02*
X363346Y30483D01*
G01X364142Y32779D02*
X362286Y30923D01*
G01X363346Y30483D02*
Y29233D01*
G01X362286Y30923D02*
Y29082D01*
G01X380612Y103286D02*
Y80380D01*
G01X381672Y103726D02*
Y80820D01*
G01X380612Y80380D02*
X382732Y78260D01*
G01X381672Y80820D02*
X383792Y78700D01*
G01X382732Y78260D02*
Y54340D01*
G01X383792Y78700D02*
Y53900D01*
G01X382732Y54340D02*
X380612Y52220D01*
G01X383792Y53900D02*
X381672Y51780D01*
G01X380612Y52220D02*
Y46432D01*
G01X381672Y51780D02*
Y45992D01*
G01X380612Y46432D02*
X377532Y43352D01*
G01X381672Y45992D02*
X378592Y42912D01*
G01X377532Y43352D02*
Y40325D01*
G01X378592Y42912D02*
Y39885D01*
G01X381672Y103726D02*
Y80820D01*
G01X380612Y103286D02*
Y80380D01*
G01X381672Y80820D02*
X383792Y78700D01*
G01X380612Y80380D02*
X382732Y78260D01*
G01X383792Y78700D02*
Y53900D01*
G01X382732Y78260D02*
Y54340D01*
G01X383792Y53900D02*
X381672Y51780D01*
G01X382732Y54340D02*
X380612Y52220D01*
G01X381672Y51780D02*
Y45992D01*
G01X380612Y52220D02*
Y46432D01*
G01X381672Y45992D02*
X378592Y42912D01*
G01X380612Y46432D02*
X377532Y43352D01*
G01X378592Y42912D02*
Y39885D01*
G01X377532Y43352D02*
Y40325D01*
G01X368671Y102147D02*
X360730Y94206D01*
G01X359670Y94646D02*
Y91384D01*
G01X360730Y94206D02*
Y90944D01*
G01X359592Y91306D02*
Y85831D01*
G01X360652Y90866D02*
Y86271D01*
G01X359592Y85831D02*
X361892Y83531D01*
G01X360652Y86271D02*
X362952Y83971D01*
G01X361892Y83531D02*
Y82151D01*
G01X362952Y83971D02*
Y82591D01*
G01X361892Y82151D02*
X363122Y80921D01*
G01X362952Y82591D02*
X363562Y81981D01*
G01X363122Y80921D02*
X366590D01*
G01X363562Y81981D02*
X367030D01*
G01X366590Y80921D02*
X367229Y80282D01*
G01X367030Y81981D02*
X368289Y80722D01*
G01X367229Y80282D02*
Y78892D01*
G01X368289Y80722D02*
Y78452D01*
G01X367229Y78892D02*
X366648Y78311D01*
G01X368289Y78452D02*
X367088Y77251D01*
G01X366648Y78311D02*
X363122D01*
G01X367088Y77251D02*
X363562D01*
G01X363122Y78311D02*
X361892Y77081D01*
G01X363562Y77251D02*
X362952Y76641D01*
G01X361892Y77081D02*
Y71736D01*
G01X362952Y76641D02*
Y72176D01*
G01X361892Y71736D02*
X364328Y69300D01*
G01X362952Y72176D02*
X364768Y70360D01*
G01X364328Y69300D02*
X367032D01*
G01X364768Y70360D02*
X367472D01*
G01X367032Y69300D02*
X368788Y67544D01*
G01X367472Y70360D02*
X369848Y67984D01*
G01X368788Y67544D02*
Y63286D01*
G01X369848Y67984D02*
Y62846D01*
G01X368788Y63286D02*
X366818Y61316D01*
G01X369848Y62846D02*
X367258Y60256D01*
G01X366818Y61316D02*
X364851D01*
G01X367258Y60256D02*
X365291D01*
G01X364851Y61316D02*
X362386Y58851D01*
G01X365291Y60256D02*
X363446Y58411D01*
G01X362386Y58851D02*
Y56010D01*
G01X363446Y58411D02*
Y55961D01*
G01X377312Y101413D02*
Y50192D01*
G01X378372Y101853D02*
Y49752D01*
G01X377312Y50192D02*
X372784Y45664D01*
G01X378372Y49752D02*
X373844Y45224D01*
G01X372784Y45664D02*
Y43039D01*
G01X373844Y45224D02*
Y42599D01*
G01X372784Y43039D02*
X371315Y41570D01*
G01X373844Y42599D02*
X371755Y40510D01*
G01X371315Y41570D02*
X369321D01*
G01X371755Y40510D02*
X368881D01*
G01X369321Y41570D02*
X368821Y42070D01*
G01X368881Y40510D02*
X367761Y41630D01*
G01X368821Y42070D02*
Y43035D01*
G01X367761Y41630D02*
Y42595D01*
G01X368821Y43035D02*
X367465Y44391D01*
G01X367761Y42595D02*
X367025Y43331D01*
G01X367465Y44391D02*
X364101D01*
G01X367025Y43331D02*
X364541D01*
G01X364101Y44391D02*
X362286Y42576D01*
G01X364541Y43331D02*
X363346Y42136D01*
G01X362286Y42576D02*
Y37010D01*
G01X363346Y42136D02*
Y37161D01*
G01X371212Y102892D02*
Y71880D01*
G01X372272Y102452D02*
Y72320D01*
G01X371212Y71880D02*
X373412Y69680D01*
G01X372272Y72320D02*
X374472Y70120D01*
G01X373412Y69680D02*
Y57931D01*
G01X374472Y70120D02*
Y57491D01*
G01X373412Y57931D02*
X367941Y52460D01*
G01X374472Y57491D02*
X368381Y51400D01*
G01X367941Y52460D02*
X365951D01*
G01X368381Y51400D02*
X366391D01*
G01X365951Y52460D02*
X362286Y48795D01*
G01X366391Y51400D02*
X363346Y48355D01*
G01X362286Y48795D02*
Y47682D01*
G01X363346Y48355D02*
Y47833D01*
G01X368671Y102147D02*
X360730Y94206D01*
G01D02*
Y90944D01*
G01X359670Y94646D02*
Y91384D01*
G01X360652Y90866D02*
Y86271D01*
G01X359592Y91306D02*
Y85831D01*
G01X360652Y86271D02*
X362952Y83971D01*
G01X359592Y85831D02*
X361892Y83531D01*
G01X362952Y83971D02*
Y82591D01*
G01X361892Y83531D02*
Y82151D01*
G01X362952Y82591D02*
X363562Y81981D01*
G01X361892Y82151D02*
X363122Y80921D01*
G01X363562Y81981D02*
X367030D01*
G01X363122Y80921D02*
X366590D01*
G01X367030Y81981D02*
X368289Y80722D01*
G01X366590Y80921D02*
X367229Y80282D01*
G01X368289Y80722D02*
Y78452D01*
G01X367229Y80282D02*
Y78892D01*
G01X368289Y78452D02*
X367088Y77251D01*
G01X367229Y78892D02*
X366648Y78311D01*
G01X367088Y77251D02*
X363562D01*
G01X366648Y78311D02*
X363122D01*
G01X363562Y77251D02*
X362952Y76641D01*
G01X363122Y78311D02*
X361892Y77081D01*
G01X362952Y76641D02*
Y72176D01*
G01X361892Y77081D02*
Y71736D01*
G01X362952Y72176D02*
X364768Y70360D01*
G01X361892Y71736D02*
X364328Y69300D01*
G01X364768Y70360D02*
X367472D01*
G01X364328Y69300D02*
X367032D01*
G01X367472Y70360D02*
X369848Y67984D01*
G01X367032Y69300D02*
X368788Y67544D01*
G01X369848Y67984D02*
Y62846D01*
G01X368788Y67544D02*
Y63286D01*
G01X369848Y62846D02*
X367258Y60256D01*
G01X368788Y63286D02*
X366818Y61316D01*
G01X367258Y60256D02*
X365291D01*
G01X366818Y61316D02*
X364851D01*
G01X365291Y60256D02*
X363446Y58411D01*
G01X364851Y61316D02*
X362386Y58851D01*
G01X363446Y58411D02*
Y55961D01*
G01X362386Y58851D02*
Y56010D01*
G01X378372Y101853D02*
Y49752D01*
G01X377312Y101413D02*
Y50192D01*
G01X378372Y49752D02*
X373844Y45224D01*
G01X377312Y50192D02*
X372784Y45664D01*
G01X373844Y45224D02*
Y42599D01*
G01X372784Y45664D02*
Y43039D01*
G01X373844Y42599D02*
X371755Y40510D01*
G01X372784Y43039D02*
X371315Y41570D01*
G01X371755Y40510D02*
X368881D01*
G01X371315Y41570D02*
X369321D01*
G01X368881Y40510D02*
X367761Y41630D01*
G01X369321Y41570D02*
X368821Y42070D01*
G01X367761Y41630D02*
Y42595D01*
G01X368821Y42070D02*
Y43035D01*
G01X367761Y42595D02*
X367025Y43331D01*
G01X368821Y43035D02*
X367465Y44391D01*
G01X367025Y43331D02*
X364541D01*
G01X367465Y44391D02*
X364101D01*
G01X364541Y43331D02*
X363346Y42136D01*
G01X364101Y44391D02*
X362286Y42576D01*
G01X363346Y42136D02*
Y37161D01*
G01X362286Y42576D02*
Y37010D01*
G01X372272Y102452D02*
Y72320D01*
G01X371212Y102892D02*
Y71880D01*
G01X372272Y72320D02*
X374472Y70120D01*
G01X371212Y71880D02*
X373412Y69680D01*
G01X374472Y70120D02*
Y57491D01*
G01X373412Y69680D02*
Y57931D01*
G01X374472Y57491D02*
X368381Y51400D01*
G01X373412Y57931D02*
X367941Y52460D01*
G01X368381Y51400D02*
X366391D01*
G01X367941Y52460D02*
X365951D01*
G01X366391Y51400D02*
X363346Y48355D01*
G01X365951Y52460D02*
X362286Y48795D01*
G01X363346Y48355D02*
Y47833D01*
G01X362286Y48795D02*
Y47682D01*
G01X379822Y191170D02*
Y104076D01*
G01X380882Y191050D02*
Y104516D01*
G01X379822Y104076D02*
X380612Y103286D01*
G01X380882Y104516D02*
X381672Y103726D01*
G01X380882Y191050D02*
Y104516D01*
G01X379822Y191170D02*
Y104076D01*
G01X380882Y104516D02*
X381672Y103726D01*
G01X379822Y104076D02*
X380612Y103286D01*
G01X370286Y188926D02*
Y106866D01*
G01X371346Y189046D02*
Y106423D01*
G01X370286Y106866D02*
X367611Y104191D01*
G01X371346Y106423D02*
X369702Y104779D01*
G01X370286Y106866D02*
X367611Y104191D01*
G01X369699Y104779D02*
X368671Y103751D01*
G01X367611Y104191D02*
Y102587D01*
G01X368671Y103751D02*
Y102147D01*
G01X367611Y102587D02*
X359670Y94646D01*
G01X376886Y188926D02*
Y101839D01*
G01X377946Y189046D02*
Y102279D01*
G01X376886Y101839D02*
X377312Y101413D01*
G01X377946Y102279D02*
X378372Y101853D01*
G01X373586Y188726D02*
Y105266D01*
G01X374646Y188846D02*
Y104826D01*
G01X373586Y105266D02*
X371212Y102892D01*
G01X374646Y104826D02*
X372272Y102452D01*
G01X371346Y189046D02*
Y106423D01*
G01X370286Y188926D02*
Y106866D01*
G01X371346Y106423D02*
X369702Y104779D01*
G01X369699D02*
X368671Y103751D01*
G01X370286Y106866D02*
X367611Y104191D01*
G01X368671Y103751D02*
Y102147D01*
G01X367611Y104191D02*
Y102587D01*
G01D02*
X359670Y94646D01*
G01X377946Y189046D02*
Y102279D01*
G01X376886Y188926D02*
Y101839D01*
G01X377946Y102279D02*
X378372Y101853D01*
G01X376886Y101839D02*
X377312Y101413D01*
G01X374646Y188846D02*
Y104826D01*
G01X373586Y188726D02*
Y105266D01*
G01X374646Y104826D02*
X372272Y102452D01*
G01X373586Y105266D02*
X371212Y102892D01*
G01X376304Y409402D02*
Y504529D01*
G01X375244Y504969D02*
Y409402D01*
G01X373272Y409466D02*
Y519779D01*
G01X372212Y409466D02*
Y520219D01*
G01X379726Y409186D02*
Y499157D01*
G01X378666Y409306D02*
Y485929D01*
G01X379726Y409186D02*
Y499157D01*
G01Y409186D02*
Y499157D01*
G01Y409186D02*
Y499157D01*
G01X369970Y516404D02*
Y409511D01*
G01X368910Y409472D02*
Y502296D01*
G01X369970Y516404D02*
Y409511D01*
G01Y516404D02*
Y409511D01*
G01Y516404D02*
Y409511D01*
G01X375244Y504969D02*
Y409402D01*
G01X376304D02*
Y504529D01*
G01X372212Y409466D02*
Y520219D01*
G01X373272Y409466D02*
Y519779D01*
G01X378666Y409306D02*
Y485929D01*
G01X379726Y409186D02*
Y499157D01*
G01X368910Y409472D02*
Y502296D01*
G01X369970Y516404D02*
Y409511D01*
G01X379672Y515598D02*
Y550100D01*
G01Y515598D02*
Y550100D01*
G01Y515598D02*
Y550100D01*
G01Y515598D02*
Y550100D01*
G01X378612Y525328D02*
Y523498D01*
G01X379672Y515598D02*
Y550100D01*
G01X378612Y520772D02*
Y516038D01*
G01X377898Y513824D02*
X379672Y515598D01*
G01X378612Y516038D02*
X377458Y514884D01*
G01X377042Y513824D02*
X377898D01*
G01X377458Y514884D02*
X376602D01*
G01X376542Y513324D02*
X377042Y513824D01*
G01X376602Y514884D02*
X375482Y513764D01*
G01X376542Y511714D02*
Y513324D01*
G01X375482Y513764D02*
Y511274D01*
G01X377042Y511214D02*
X376542Y511714D01*
G01X375482Y511274D02*
X376602Y510154D01*
G01X377951Y511214D02*
X377042D01*
G01X376602Y510154D02*
X377511D01*
G01X379379Y509786D02*
X377951Y511214D01*
G01X377511Y510154D02*
X378319Y509346D01*
G01X379379Y507604D02*
Y509786D01*
G01X378319Y509346D02*
Y508044D01*
G01X376304Y504529D02*
X379379Y507604D01*
G01X378319Y508044D02*
X375244Y504969D01*
G01X373272Y519779D02*
X374996Y521503D01*
G01X372212Y520219D02*
X373936Y521943D01*
G01X374996Y521503D02*
Y556768D01*
G01X373936Y521943D02*
Y524433D01*
G01X374996Y521503D02*
Y556768D01*
G01Y521503D02*
Y556768D01*
G01Y521503D02*
Y556768D01*
G01Y521503D02*
Y556768D01*
G01Y521503D02*
Y556768D01*
G01Y521503D02*
Y556768D01*
G01Y521503D02*
Y556768D01*
G01X378666Y488655D02*
Y490485D01*
G01Y493211D02*
Y495041D01*
G01Y497767D02*
Y499597D01*
G01X379726Y499157D02*
X382876Y502307D01*
G01X378666Y499597D02*
X381816Y502747D01*
G01X382876Y502307D02*
Y556600D01*
G01X381816Y502747D02*
Y504613D01*
G01X382876Y502307D02*
Y556600D01*
G01X381816Y507267D02*
Y511551D01*
G01X382876Y502307D02*
Y556600D01*
G01X381816Y514135D02*
Y551730D01*
G01X382876Y502307D02*
Y556600D01*
G01X368910Y505022D02*
Y506852D01*
G01Y509578D02*
Y511408D01*
G01Y514134D02*
Y515964D01*
G01X367993Y518381D02*
X369970Y516404D01*
G01X368910Y515964D02*
X367553Y517321D01*
G01X365307Y518381D02*
X367993D01*
G01X367553Y517321D02*
X364867D01*
G01X364493Y519195D02*
X365307Y518381D01*
G01X364867Y517321D02*
X363433Y518755D01*
G01X364493Y521610D02*
Y519195D01*
G01X363433Y518755D02*
Y522050D01*
G01X365198Y522315D02*
X364493Y521610D01*
G01X363433Y522050D02*
X364758Y523375D01*
G01X369684Y522315D02*
X365198D01*
G01X364758Y523375D02*
X365663D01*
G01X369684Y522315D02*
X365198D01*
G01X368333Y523375D02*
X369244D01*
G01X371172Y523803D02*
X369684Y522315D01*
G01X369244Y523375D02*
X370112Y524243D01*
G01X371172Y538890D02*
Y523803D01*
G01X370112Y524243D02*
Y525540D01*
G01X371172Y538890D02*
Y523803D01*
G01Y538890D02*
Y523803D01*
G01Y538890D02*
Y523803D01*
G01X378319Y508044D02*
X375244Y504969D01*
G01X376304Y504529D02*
X379379Y507604D01*
G01X378319Y509346D02*
Y508044D01*
G01X379379Y507604D02*
Y509786D01*
G01X377511Y510154D02*
X378319Y509346D01*
G01X379379Y509786D02*
X377951Y511214D01*
G01X376602Y510154D02*
X377511D01*
G01X377951Y511214D02*
X377042D01*
G01X375482Y511274D02*
X376602Y510154D01*
G01X377042Y511214D02*
X376542Y511714D01*
G01X375482Y513764D02*
Y511274D01*
G01X376542Y511714D02*
Y513324D01*
G01X376602Y514884D02*
X375482Y513764D01*
G01X376542Y513324D02*
X377042Y513824D01*
G01X377458Y514884D02*
X376602D01*
G01X377042Y513824D02*
X377898D01*
G01X378612Y516038D02*
X377458Y514884D01*
G01X377898Y513824D02*
X379672Y515598D01*
G01X378612Y525328D02*
Y523498D01*
G01Y520772D02*
Y516038D01*
G01X379672Y515598D02*
Y550100D01*
G01X372212Y520219D02*
X373936Y521943D01*
G01X373272Y519779D02*
X374996Y521503D01*
G01X373936Y521943D02*
Y524433D01*
G01X374996Y521503D02*
Y556768D01*
G01X378666Y488655D02*
Y490485D01*
G01Y493211D02*
Y495041D01*
G01Y497767D02*
Y499597D01*
G01D02*
X381816Y502747D01*
G01X379726Y499157D02*
X382876Y502307D01*
G01X381816Y502747D02*
Y504613D01*
G01Y507267D02*
Y511551D01*
G01Y514135D02*
Y551730D01*
G01X382876Y502307D02*
Y556600D01*
G01X370112Y524243D02*
Y525540D01*
G01X371172Y538890D02*
Y523803D01*
G01X369244Y523375D02*
X370112Y524243D01*
G01X371172Y523803D02*
X369684Y522315D01*
G01X364758Y523375D02*
X365663D01*
G01X368333D02*
X369244D01*
G01X369684Y522315D02*
X365198D01*
G01X363433Y522050D02*
X364758Y523375D01*
G01X365198Y522315D02*
X364493Y521610D01*
G01X363433Y518755D02*
Y522050D01*
G01X364493Y521610D02*
Y519195D01*
G01X364867Y517321D02*
X363433Y518755D01*
G01X364493Y519195D02*
X365307Y518381D01*
G01X367553Y517321D02*
X364867D01*
G01X365307Y518381D02*
X367993D01*
G01X368910Y515964D02*
X367553Y517321D01*
G01X367993Y518381D02*
X369970Y516404D01*
G01X368910Y505022D02*
Y506852D01*
G01Y509578D02*
Y511408D01*
G01Y514134D02*
Y515964D01*
G01X362273Y570187D02*
Y567869D01*
G01X363333Y568046D02*
Y569747D01*
G01X363766Y571680D02*
X362273Y570187D01*
G01X363333Y569747D02*
X364206Y570620D01*
G01X371484Y571680D02*
X363766D01*
G01X364206Y570620D02*
X366254D01*
G01X371484Y571680D02*
X363766D01*
G01X368978Y570620D02*
X371044D01*
G01X378792Y564372D02*
X371484Y571680D01*
G01X371044Y570620D02*
X371833Y569831D01*
G01X378792Y564372D02*
X371484Y571680D01*
G01X373734Y567930D02*
X375017Y566647D01*
G01X378792Y564372D02*
X371484Y571680D01*
G01X376939Y564725D02*
X377732Y563932D01*
G01X378792Y550980D02*
Y564372D01*
G01X377732Y563932D02*
Y562102D01*
G01X378792Y550980D02*
Y564372D01*
G01X377732Y559376D02*
Y557546D01*
G01X378792Y550980D02*
Y564372D01*
G01X377732Y554820D02*
Y550540D01*
G01X379672Y550100D02*
X378792Y550980D01*
G01X377732Y550540D02*
X378612Y549660D01*
G01D02*
Y537166D01*
G01Y534440D02*
Y532610D01*
G01Y529884D02*
Y528054D01*
G01X373936Y527159D02*
Y528989D01*
G01Y531715D02*
Y533545D01*
G01Y536271D02*
Y538101D01*
G01Y540827D02*
Y542657D01*
G01Y545383D02*
Y547213D01*
G01Y549939D02*
Y551769D01*
G01Y554495D02*
Y556325D01*
G01X374996Y556768D02*
X371184Y560580D01*
G01X373936Y556325D02*
X373116Y557145D01*
G01X374996Y556768D02*
X371184Y560580D01*
G01X373116Y557145D02*
X372603Y557146D01*
G01X374996Y556768D02*
X371184Y560580D01*
G01X371473Y558788D02*
X370741Y559520D01*
G01X371184Y560580D02*
X364007D01*
G01X370741Y559520D02*
X369283D01*
G01X371184Y560580D02*
X364007D01*
G01X366561Y559520D02*
X364447D01*
G01X364007Y560580D02*
X362235Y558808D01*
G01X364447Y559520D02*
X363295Y558368D01*
G01X362235Y558808D02*
Y556859D01*
G01X363295Y558368D02*
Y557112D01*
G01X381816Y554384D02*
Y556160D01*
G01X382876Y556600D02*
X381692Y557784D01*
G01X381816Y556160D02*
X380632Y557344D01*
G01X381692Y557784D02*
Y570072D01*
G01X380632Y557344D02*
Y565502D01*
G01X381692Y557784D02*
Y570072D01*
G01X380632Y567978D02*
Y569629D01*
G01X381692Y570072D02*
X371984Y579780D01*
G01X380632Y569629D02*
X377985Y572276D01*
G01X381692Y570072D02*
X371984Y579780D01*
G01X376057Y574204D02*
X374763Y575498D01*
G01X381692Y570072D02*
X371984Y579780D01*
G01X372835Y577426D02*
X371541Y578720D01*
G01X371984Y579780D02*
X364357D01*
G01X371541Y578720D02*
X369353D01*
G01X371984Y579780D02*
X364357D01*
G01X366627Y578720D02*
X364797D01*
G01X364357Y579780D02*
X362444Y577867D01*
G01X364797Y578720D02*
X363504Y577427D01*
G01X362444Y577867D02*
Y575968D01*
G01X363504Y577427D02*
Y575803D01*
G01X370112Y528264D02*
Y529840D01*
G01Y532566D02*
Y534396D01*
G01Y537122D02*
Y538450D01*
G01X369942Y540120D02*
X371172Y538890D01*
G01X370112Y538450D02*
X369502Y539060D01*
G01X364941Y540120D02*
X369942D01*
G01X369502Y539060D02*
X368447D01*
G01X364941Y540120D02*
X369942D01*
G01X365723Y539060D02*
X364501D01*
G01X364295Y540766D02*
X364941Y540120D01*
G01X364501Y539060D02*
X363235Y540326D01*
G01X364295Y542156D02*
Y540766D01*
G01X363235Y540326D02*
Y542596D01*
G01X364869Y542730D02*
X364295Y542156D01*
G01X363235Y542596D02*
X364429Y543790D01*
G01X369942Y542730D02*
X364869D01*
G01X364429Y543790D02*
X365668D01*
G01X369942Y542730D02*
X364869D01*
G01X368390Y543790D02*
X369502D01*
G01X371172Y543960D02*
X369942Y542730D01*
G01X369502Y543790D02*
X370112Y544400D01*
G01X371172Y548620D02*
Y543960D01*
G01X370112Y544400D02*
Y548180D01*
G01X367292Y552500D02*
X371172Y548620D01*
G01X370112Y548180D02*
X366852Y551440D01*
G01X363588Y552500D02*
X367292D01*
G01X366852Y551440D02*
X364028D01*
G01X362012Y550924D02*
X363588Y552500D01*
G01X364028Y551440D02*
X363072Y550484D01*
G01X362012Y548408D02*
Y550924D01*
G01X363072Y550484D02*
Y549107D01*
G01X378612Y549660D02*
Y537166D01*
G01Y534440D02*
Y532610D01*
G01Y529884D02*
Y528054D01*
G01X377732Y550540D02*
X378612Y549660D01*
G01X379672Y550100D02*
X378792Y550980D01*
G01X377732Y563932D02*
Y562102D01*
G01Y559376D02*
Y557546D01*
G01Y554820D02*
Y550540D01*
G01X378792Y550980D02*
Y564372D01*
G01X371044Y570620D02*
X371833Y569831D01*
G01X373734Y567930D02*
X375017Y566647D01*
G01X376939Y564725D02*
X377732Y563932D01*
G01X378792Y564372D02*
X371484Y571680D01*
G01X364206Y570620D02*
X366254D01*
G01X368978D02*
X371044D01*
G01X371484Y571680D02*
X363766D01*
G01X363333Y569747D02*
X364206Y570620D01*
G01X363766Y571680D02*
X362273Y570187D01*
G01X363333Y568046D02*
Y569747D01*
G01X362273Y570187D02*
Y567869D01*
G01X373936Y527159D02*
Y528989D01*
G01Y531715D02*
Y533545D01*
G01Y536271D02*
Y538101D01*
G01Y540827D02*
Y542657D01*
G01Y545383D02*
Y547213D01*
G01Y549939D02*
Y551769D01*
G01Y554495D02*
Y556325D01*
G01D02*
X373116Y557145D01*
G01D02*
X372603Y557146D01*
G01X371473Y558788D02*
X370741Y559520D01*
G01X374996Y556768D02*
X371184Y560580D01*
G01X370741Y559520D02*
X369283D01*
G01X366561D02*
X364447D01*
G01X371184Y560580D02*
X364007D01*
G01X364447Y559520D02*
X363295Y558368D01*
G01X364007Y560580D02*
X362235Y558808D01*
G01X363295Y558368D02*
Y557112D01*
G01X362235Y558808D02*
Y556859D01*
G01X381816Y554384D02*
Y556160D01*
G01D02*
X380632Y557344D01*
G01X382876Y556600D02*
X381692Y557784D01*
G01X380632Y557344D02*
Y565502D01*
G01Y567978D02*
Y569629D01*
G01X381692Y557784D02*
Y570072D01*
G01X380632Y569629D02*
X377985Y572276D01*
G01X376057Y574204D02*
X374763Y575498D01*
G01X372835Y577426D02*
X371541Y578720D01*
G01X381692Y570072D02*
X371984Y579780D01*
G01X371541Y578720D02*
X369353D01*
G01X366627D02*
X364797D01*
G01X371984Y579780D02*
X364357D01*
G01X364797Y578720D02*
X363504Y577427D01*
G01X364357Y579780D02*
X362444Y577867D01*
G01X363504Y577427D02*
Y575803D01*
G01X362444Y577867D02*
Y575968D01*
G01X363072Y550484D02*
Y549107D01*
G01X362012Y548408D02*
Y550924D01*
G01X364028Y551440D02*
X363072Y550484D01*
G01X362012Y550924D02*
X363588Y552500D01*
G01X366852Y551440D02*
X364028D01*
G01X363588Y552500D02*
X367292D01*
G01X370112Y548180D02*
X366852Y551440D01*
G01X367292Y552500D02*
X371172Y548620D01*
G01X370112Y544400D02*
Y548180D01*
G01X371172Y548620D02*
Y543960D01*
G01X369502Y543790D02*
X370112Y544400D01*
G01X371172Y543960D02*
X369942Y542730D01*
G01X364429Y543790D02*
X365668D01*
G01X368390D02*
X369502D01*
G01X369942Y542730D02*
X364869D01*
G01X363235Y542596D02*
X364429Y543790D01*
G01X364869Y542730D02*
X364295Y542156D01*
G01X363235Y540326D02*
Y542596D01*
G01X364295Y542156D02*
Y540766D01*
G01X364501Y539060D02*
X363235Y540326D01*
G01X364295Y540766D02*
X364941Y540120D01*
G01X369502Y539060D02*
X368447D01*
G01X365723D02*
X364501D01*
G01X364941Y540120D02*
X369942D01*
G01X370112Y538450D02*
X369502Y539060D01*
G01X369942Y540120D02*
X371172Y538890D01*
G01X370112Y528264D02*
Y529840D01*
G01Y532566D02*
Y534396D01*
G01Y537122D02*
Y538450D01*
G01X466778Y33291D02*
X466067Y32580D01*
G01X467838Y32848D02*
X466510Y31520D01*
G01X466067Y32580D02*
X465551D01*
G01X466510Y31520D02*
X465528D01*
G01X467838Y32848D02*
X466510Y31520D01*
G01X466778Y33291D02*
X466067Y32580D01*
G01X466510Y31520D02*
X465528D01*
G01X466067Y32580D02*
X465551D01*
G01X473024Y33732D02*
X469832Y30540D01*
G01X466778Y33291D02*
X466067Y32580D01*
G01X467838Y32848D02*
X466510Y31520D01*
G01X466067Y32580D02*
X465551D01*
G01X466510Y31520D02*
X465528D01*
G01X473024Y33732D02*
X469832Y30540D01*
G01X473024Y33732D02*
X469832Y30540D01*
G01X473024Y33732D02*
X469832Y30540D01*
G01X473024Y33732D02*
X469832Y30540D01*
G01X467838Y32848D02*
X466510Y31520D01*
G01X466778Y33291D02*
X466067Y32580D01*
G01X466510Y31520D02*
X465528D01*
G01X466067Y32580D02*
X465551D01*
G01X473024Y33732D02*
X469832Y30540D01*
G01X466752Y97809D02*
Y63931D01*
G01X467813Y98251D02*
Y82820D01*
G01X466752Y97809D02*
Y63931D01*
G01X467813Y80580D02*
Y79820D01*
G01X466752Y97809D02*
Y63931D01*
G01X467813Y77580D02*
Y76820D01*
G01X466752Y97809D02*
Y63931D01*
G01X467812Y74579D02*
Y63488D01*
G01X466752Y63931D02*
X462878Y60057D01*
G01X467812Y63488D02*
X463938Y59614D01*
G01X462878Y60057D02*
Y51354D01*
G01X463938Y59614D02*
Y57420D01*
G01X464732Y49500D02*
X465831D01*
G01D02*
X466778Y48553D01*
G01X464732Y52100D02*
X467838Y48994D01*
G01X466778Y48553D02*
Y46020D01*
G01Y41880D02*
Y40920D01*
G01Y36580D02*
Y33291D01*
G01X467838Y48994D02*
Y32848D01*
G01X467813Y98251D02*
Y82820D01*
G01Y80580D02*
Y79820D01*
G01Y77580D02*
Y76820D01*
G01X467812Y74579D02*
Y63488D01*
G01X466752Y97809D02*
Y63931D01*
G01X467812Y63488D02*
X463938Y59614D01*
G01X466752Y63931D02*
X462878Y60057D01*
G01X463938Y59614D02*
Y57420D01*
G01X462878Y60057D02*
Y51354D01*
G01X464732Y52100D02*
X467838Y48994D01*
G01X464732Y49500D02*
X465831D01*
G01X464732Y52100D02*
X467838Y48994D01*
G01X465831Y49500D02*
X466778Y48553D01*
G01X467838Y48994D02*
Y32848D01*
G01X466778Y48553D02*
Y46020D01*
G01X467838Y48994D02*
Y32848D01*
G01X466778Y41880D02*
Y40920D01*
G01X467838Y48994D02*
Y32848D01*
G01X466778Y36580D02*
Y33291D01*
G01X471853Y105233D02*
Y63194D01*
G01X472913Y105676D02*
Y77120D01*
G01X471853Y105233D02*
Y63194D01*
G01X472913Y74880D02*
Y62751D01*
G01X471853Y63194D02*
X468078Y59419D01*
G01X472913Y62751D02*
X472019Y61857D01*
G01X471853Y63194D02*
X468078Y59419D01*
G01X470435Y60273D02*
X469138Y58976D01*
G01X468078Y59419D02*
Y51468D01*
G01X469138Y58976D02*
Y57554D01*
G01X469832Y49715D02*
X470930D01*
G01D02*
X471964Y48681D01*
G01X469832Y52314D02*
X473024Y49122D01*
G01X471964Y48681D02*
Y45906D01*
G01Y42080D02*
Y40707D01*
G01Y36793D02*
Y34172D01*
G01X473024Y49122D02*
Y33732D01*
G01X471964Y34172D02*
X470941Y33149D01*
G01D02*
X469832D01*
G01X466752Y97809D02*
Y63931D01*
G01X467813Y98251D02*
Y82820D01*
G01X466752Y97809D02*
Y63931D01*
G01X467813Y80580D02*
Y79820D01*
G01X466752Y97809D02*
Y63931D01*
G01X467813Y77580D02*
Y76820D01*
G01X466752Y97809D02*
Y63931D01*
G01X467812Y74579D02*
Y63488D01*
G01X466752Y63931D02*
X462878Y60057D01*
G01X467812Y63488D02*
X463938Y59614D01*
G01X462878Y60057D02*
Y51354D01*
G01X463938Y59614D02*
Y57420D01*
G01X464732Y49500D02*
X465831D01*
G01D02*
X466778Y48553D01*
G01X464732Y52100D02*
X467838Y48994D01*
G01X466778Y48553D02*
Y46020D01*
G01Y41880D02*
Y40920D01*
G01Y36580D02*
Y33291D01*
G01X467838Y48994D02*
Y32848D01*
G01X472913Y105676D02*
Y77120D01*
G01Y74880D02*
Y62751D01*
G01X471853Y105233D02*
Y63194D01*
G01X472913Y62751D02*
X472019Y61857D01*
G01X470435Y60273D02*
X469138Y58976D01*
G01X471853Y63194D02*
X468078Y59419D01*
G01X469138Y58976D02*
Y57554D01*
G01X468078Y59419D02*
Y51468D01*
G01X469832Y52314D02*
X473024Y49122D01*
G01X469832Y49715D02*
X470930D01*
G01X469832Y52314D02*
X473024Y49122D01*
G01X470930Y49715D02*
X471964Y48681D01*
G01X473024Y49122D02*
Y33732D01*
G01X471964Y48681D02*
Y45906D01*
G01X473024Y49122D02*
Y33732D01*
G01X471964Y42080D02*
Y40707D01*
G01X473024Y49122D02*
Y33732D01*
G01X471964Y36793D02*
Y34172D01*
G01D02*
X470941Y33149D01*
G01D02*
X469832D01*
G01X472913Y105676D02*
Y77120D01*
G01Y74880D02*
Y62751D01*
G01X471853Y105233D02*
Y63194D01*
G01X472913Y62751D02*
X472019Y61857D01*
G01X470435Y60273D02*
X469138Y58976D01*
G01X471853Y63194D02*
X468078Y59419D01*
G01X469138Y58976D02*
Y57554D01*
G01X468078Y59419D02*
Y51468D01*
G01X469832Y52314D02*
X473024Y49122D01*
G01X469832Y49715D02*
X470930D01*
G01X469832Y52314D02*
X473024Y49122D01*
G01X470930Y49715D02*
X471964Y48681D01*
G01X473024Y49122D02*
Y33732D01*
G01X471964Y48681D02*
Y45906D01*
G01X473024Y49122D02*
Y33732D01*
G01X471964Y42080D02*
Y40707D01*
G01X473024Y49122D02*
Y33732D01*
G01X471964Y36793D02*
Y34172D01*
G01D02*
X470941Y33149D01*
G01D02*
X469832D01*
G01X467813Y98251D02*
Y82820D01*
G01Y80580D02*
Y79820D01*
G01Y77580D02*
Y76820D01*
G01X467812Y74579D02*
Y63488D01*
G01X466752Y97809D02*
Y63931D01*
G01X467812Y63488D02*
X463938Y59614D01*
G01X466752Y63931D02*
X462878Y60057D01*
G01X463938Y59614D02*
Y57420D01*
G01X462878Y60057D02*
Y51354D01*
G01X464732Y52100D02*
X467838Y48994D01*
G01X464732Y49500D02*
X465831D01*
G01X464732Y52100D02*
X467838Y48994D01*
G01X465831Y49500D02*
X466778Y48553D01*
G01X467838Y48994D02*
Y32848D01*
G01X466778Y48553D02*
Y46020D01*
G01X467838Y48994D02*
Y32848D01*
G01X466778Y41880D02*
Y40920D01*
G01X467838Y48994D02*
Y32848D01*
G01X466778Y36580D02*
Y33291D01*
G01X471853Y105233D02*
Y63194D01*
G01X472913Y105676D02*
Y77120D01*
G01X471853Y105233D02*
Y63194D01*
G01X472913Y74880D02*
Y62751D01*
G01X471853Y63194D02*
X468078Y59419D01*
G01X472913Y62751D02*
X472019Y61857D01*
G01X471853Y63194D02*
X468078Y59419D01*
G01X470435Y60273D02*
X469138Y58976D01*
G01X468078Y59419D02*
Y51468D01*
G01X469138Y58976D02*
Y57554D01*
G01X469832Y49715D02*
X470930D01*
G01D02*
X471964Y48681D01*
G01X469832Y52314D02*
X473024Y49122D01*
G01X471964Y48681D02*
Y45906D01*
G01Y42080D02*
Y40707D01*
G01Y36793D02*
Y34172D01*
G01X473024Y49122D02*
Y33732D01*
G01X471964Y34172D02*
X470941Y33149D01*
G01D02*
X469832D01*
G01X427721Y179041D02*
Y147243D01*
G01Y179041D02*
Y147243D01*
G01X428781Y174959D02*
Y147683D01*
G01X427721Y147243D02*
X449712Y125252D01*
G01X428781Y147683D02*
X450772Y125692D01*
G01X449712Y125252D02*
Y121910D01*
G01X450772Y125692D02*
Y122350D01*
G01X449712Y121910D02*
X451222Y120400D01*
G01X450772Y122350D02*
X451973Y121149D01*
G01X451222Y120397D02*
X452112Y119507D01*
G01X451973Y121146D02*
X453172Y119947D01*
G01X452112Y119507D02*
Y116097D01*
G01X453172Y119947D02*
Y116537D01*
G01X452112Y116097D02*
X455003Y113206D01*
G01X453172Y116537D02*
X455443Y114266D01*
G01X455003Y113206D02*
X457985D01*
G01X455443Y114266D02*
X458425D01*
G01X457985Y113206D02*
X459326Y111865D01*
G01X458425Y114266D02*
X460386Y112305D01*
G01X459326Y111865D02*
Y110642D01*
G01X460386Y112305D02*
Y110202D01*
G01X459326Y110642D02*
X458108Y109424D01*
G01X460386Y110202D02*
X459168Y108984D01*
G01X458108Y109424D02*
Y107312D01*
G01X459168Y108984D02*
Y107752D01*
G01X458108Y107312D02*
X460495Y104925D01*
G01X459168Y107752D02*
X460935Y105985D01*
G01X460495Y104925D02*
X462609D01*
G01D02*
X464039Y106355D01*
G01X460935Y105985D02*
X462166D01*
G01X462609Y104925D02*
X464039Y106355D01*
G01X462166Y105985D02*
X463596Y107415D01*
G01X464039Y106355D02*
X465264D01*
G01X463596Y107415D02*
X465707D01*
G01X464039Y106355D02*
X465264D01*
G01D02*
X467040Y104579D01*
G01X465707Y107415D02*
X468100Y105022D01*
G01X467040Y104579D02*
Y103356D01*
G01X468100Y105022D02*
Y102912D01*
G01X467040Y103356D02*
X465608Y101924D01*
G01X468100Y102912D02*
X466668Y101481D01*
G01X465608Y101924D02*
Y98953D01*
G01X466668Y101481D02*
Y99396D01*
G01X465608Y98953D02*
X466752Y97809D01*
G01X466668Y99396D02*
X467813Y98251D01*
G01X428781Y174959D02*
Y147683D01*
G01X427721Y179041D02*
Y147243D01*
G01X428781Y147683D02*
X450772Y125692D01*
G01X427721Y147243D02*
X449712Y125252D01*
G01X450772Y125692D02*
Y122350D01*
G01X449712Y125252D02*
Y121910D01*
G01X450772Y122350D02*
X451973Y121149D01*
G01X449712Y121910D02*
X451222Y120400D01*
G01X451973Y121146D02*
X453172Y119947D01*
G01X451222Y120397D02*
X452112Y119507D01*
G01X453172Y119947D02*
Y116537D01*
G01X452112Y119507D02*
Y116097D01*
G01X453172Y116537D02*
X455443Y114266D01*
G01X452112Y116097D02*
X455003Y113206D01*
G01X455443Y114266D02*
X458425D01*
G01X455003Y113206D02*
X457985D01*
G01X458425Y114266D02*
X460386Y112305D01*
G01X457985Y113206D02*
X459326Y111865D01*
G01X460386Y112305D02*
Y110202D01*
G01X459326Y111865D02*
Y110642D01*
G01X460386Y110202D02*
X459168Y108984D01*
G01X459326Y110642D02*
X458108Y109424D01*
G01X459168Y108984D02*
Y107752D01*
G01X458108Y109424D02*
Y107312D01*
G01X459168Y107752D02*
X460935Y105985D01*
G01X458108Y107312D02*
X460495Y104925D01*
G01X460935Y105985D02*
X462166D01*
G01X460495Y104925D02*
X462609D01*
G01X460935Y105985D02*
X462166D01*
G01D02*
X463596Y107415D01*
G01X462609Y104925D02*
X464039Y106355D01*
G01X463596Y107415D02*
X465707D01*
G01D02*
X468100Y105022D01*
G01X464039Y106355D02*
X465264D01*
G01X465707Y107415D02*
X468100Y105022D01*
G01X465264Y106355D02*
X467040Y104579D01*
G01X468100Y105022D02*
Y102912D01*
G01X467040Y104579D02*
Y103356D01*
G01X468100Y102912D02*
X466668Y101481D01*
G01X467040Y103356D02*
X465608Y101924D01*
G01X466668Y101481D02*
Y99396D01*
G01X465608Y101924D02*
Y98953D01*
G01X466668Y99396D02*
X467813Y98251D01*
G01X465608Y98953D02*
X466752Y97809D01*
G01X432059Y171906D02*
Y148465D01*
G01X433119Y179495D02*
Y148905D01*
G01X432059Y148465D02*
X453912Y126612D01*
G01X433119Y148905D02*
X454972Y127052D01*
G01X453912Y126612D02*
Y123174D01*
G01X454972Y127052D02*
Y123617D01*
G01X453912Y123174D02*
X471853Y105233D01*
G01X454972Y123617D02*
X472913Y105676D01*
G01X427721Y179041D02*
Y147243D01*
G01Y179041D02*
Y147243D01*
G01X428781Y174959D02*
Y147683D01*
G01X427721Y147243D02*
X449712Y125252D01*
G01X428781Y147683D02*
X450772Y125692D01*
G01X449712Y125252D02*
Y121910D01*
G01X450772Y125692D02*
Y122350D01*
G01X449712Y121910D02*
X451222Y120400D01*
G01X450772Y122350D02*
X451973Y121149D01*
G01X451222Y120397D02*
X452112Y119507D01*
G01X451973Y121146D02*
X453172Y119947D01*
G01X452112Y119507D02*
Y116097D01*
G01X453172Y119947D02*
Y116537D01*
G01X452112Y116097D02*
X455003Y113206D01*
G01X453172Y116537D02*
X455443Y114266D01*
G01X455003Y113206D02*
X457985D01*
G01X455443Y114266D02*
X458425D01*
G01X457985Y113206D02*
X459326Y111865D01*
G01X458425Y114266D02*
X460386Y112305D01*
G01X459326Y111865D02*
Y110642D01*
G01X460386Y112305D02*
Y110202D01*
G01X459326Y110642D02*
X458108Y109424D01*
G01X460386Y110202D02*
X459168Y108984D01*
G01X458108Y109424D02*
Y107312D01*
G01X459168Y108984D02*
Y107752D01*
G01X458108Y107312D02*
X460495Y104925D01*
G01X459168Y107752D02*
X460935Y105985D01*
G01X460495Y104925D02*
X462609D01*
G01D02*
X464039Y106355D01*
G01X460935Y105985D02*
X462166D01*
G01X462609Y104925D02*
X464039Y106355D01*
G01X462166Y105985D02*
X463596Y107415D01*
G01X464039Y106355D02*
X465264D01*
G01X463596Y107415D02*
X465707D01*
G01X464039Y106355D02*
X465264D01*
G01D02*
X467040Y104579D01*
G01X465707Y107415D02*
X468100Y105022D01*
G01X467040Y104579D02*
Y103356D01*
G01X468100Y105022D02*
Y102912D01*
G01X467040Y103356D02*
X465608Y101924D01*
G01X468100Y102912D02*
X466668Y101481D01*
G01X465608Y101924D02*
Y98953D01*
G01X466668Y101481D02*
Y99396D01*
G01X465608Y98953D02*
X466752Y97809D01*
G01X466668Y99396D02*
X467813Y98251D01*
G01X433119Y179495D02*
Y148905D01*
G01Y179495D02*
Y148905D01*
G01Y179495D02*
Y148905D01*
G01X432059Y171906D02*
Y148465D01*
G01X433119Y148905D02*
X454972Y127052D01*
G01X432059Y148465D02*
X453912Y126612D01*
G01X454972Y127052D02*
Y123617D01*
G01X453912Y126612D02*
Y123174D01*
G01X454972Y123617D02*
X472913Y105676D01*
G01X453912Y123174D02*
X471853Y105233D01*
G01X433119Y179495D02*
Y148905D01*
G01Y179495D02*
Y148905D01*
G01Y179495D02*
Y148905D01*
G01X432059Y171906D02*
Y148465D01*
G01X433119Y148905D02*
X454972Y127052D01*
G01X432059Y148465D02*
X453912Y126612D01*
G01X454972Y127052D02*
Y123617D01*
G01X453912Y126612D02*
Y123174D01*
G01X454972Y123617D02*
X472913Y105676D01*
G01X453912Y123174D02*
X471853Y105233D01*
G01X428781Y174959D02*
Y147683D01*
G01X427721Y179041D02*
Y147243D01*
G01X428781Y147683D02*
X450772Y125692D01*
G01X427721Y147243D02*
X449712Y125252D01*
G01X450772Y125692D02*
Y122350D01*
G01X449712Y125252D02*
Y121910D01*
G01X450772Y122350D02*
X451973Y121149D01*
G01X449712Y121910D02*
X451222Y120400D01*
G01X451973Y121146D02*
X453172Y119947D01*
G01X451222Y120397D02*
X452112Y119507D01*
G01X453172Y119947D02*
Y116537D01*
G01X452112Y119507D02*
Y116097D01*
G01X453172Y116537D02*
X455443Y114266D01*
G01X452112Y116097D02*
X455003Y113206D01*
G01X455443Y114266D02*
X458425D01*
G01X455003Y113206D02*
X457985D01*
G01X458425Y114266D02*
X460386Y112305D01*
G01X457985Y113206D02*
X459326Y111865D01*
G01X460386Y112305D02*
Y110202D01*
G01X459326Y111865D02*
Y110642D01*
G01X460386Y110202D02*
X459168Y108984D01*
G01X459326Y110642D02*
X458108Y109424D01*
G01X459168Y108984D02*
Y107752D01*
G01X458108Y109424D02*
Y107312D01*
G01X459168Y107752D02*
X460935Y105985D01*
G01X458108Y107312D02*
X460495Y104925D01*
G01X460935Y105985D02*
X462166D01*
G01X460495Y104925D02*
X462609D01*
G01X460935Y105985D02*
X462166D01*
G01D02*
X463596Y107415D01*
G01X462609Y104925D02*
X464039Y106355D01*
G01X463596Y107415D02*
X465707D01*
G01D02*
X468100Y105022D01*
G01X464039Y106355D02*
X465264D01*
G01X465707Y107415D02*
X468100Y105022D01*
G01X465264Y106355D02*
X467040Y104579D01*
G01X468100Y105022D02*
Y102912D01*
G01X467040Y104579D02*
Y103356D01*
G01X468100Y102912D02*
X466668Y101481D01*
G01X467040Y103356D02*
X465608Y101924D01*
G01X466668Y101481D02*
Y99396D01*
G01X465608Y101924D02*
Y98953D01*
G01X466668Y99396D02*
X467813Y98251D01*
G01X465608Y98953D02*
X466752Y97809D01*
G01X432059Y171906D02*
Y148465D01*
G01X433119Y179495D02*
Y148905D01*
G01X432059Y148465D02*
X453912Y126612D01*
G01X433119Y148905D02*
X454972Y127052D01*
G01X453912Y126612D02*
Y123174D01*
G01X454972Y127052D02*
Y123617D01*
G01X453912Y123174D02*
X471853Y105233D01*
G01X454972Y123617D02*
X472913Y105676D01*
G01X496810Y128714D02*
X459795Y165729D01*
G01X497870Y129154D02*
X471699Y155325D01*
G01X496810Y128714D02*
X459795Y165729D01*
G01X496810Y128714D02*
X459795Y165729D01*
G01X496810Y128714D02*
X459795Y165729D01*
G01X496810Y128714D02*
X459795Y165729D01*
G01X496810Y128714D02*
X459795Y165729D01*
G01X496810Y128714D02*
X459795Y165729D01*
G01X496810Y128714D02*
X459795Y165729D01*
G01X496810Y128714D02*
X459795Y165729D01*
G01X496810Y128714D02*
X459795Y165729D01*
G01X496810Y128714D02*
X459795Y165729D01*
G01X508012Y122909D02*
X463704Y167217D01*
G01X509072Y123352D02*
X464764Y167660D01*
G01X497870Y129154D02*
X471699Y155325D01*
G01X496810Y128714D02*
X459795Y165729D01*
G01X509072Y123352D02*
X464764Y167660D01*
G01X508012Y122909D02*
X463704Y167217D01*
G01X428781Y179041D02*
Y176959D01*
G01Y179041D02*
Y176959D01*
G01X432059Y179495D02*
Y177155D01*
G01Y175155D02*
Y173906D01*
G01X428781Y179041D02*
Y176959D01*
G01X432059Y179495D02*
Y177155D01*
G01Y175155D02*
Y173906D01*
G01Y179495D02*
Y177155D01*
G01Y175155D02*
Y173906D01*
G01X428781Y179041D02*
Y176959D01*
G01X432059Y179495D02*
Y177155D01*
G01Y175155D02*
Y173906D01*
G01X470991Y156669D02*
X470355D01*
G01D02*
X469648Y157376D01*
G01X468940Y158720D02*
X468304D01*
G01D02*
X467373Y159651D01*
G01X466665Y160995D02*
X466029D01*
G01D02*
X465293Y161731D01*
G01X464585Y163075D02*
X463949D01*
G01D02*
X462906Y164118D01*
G01X462198Y165462D02*
X461562D01*
G01D02*
X460855Y166169D01*
G01X459795Y165729D02*
Y186124D01*
G01X460855Y166169D02*
Y170112D01*
G01X459795Y165729D02*
Y186124D01*
G01X460855Y172012D02*
Y173012D01*
G01X459795Y165729D02*
Y186124D01*
G01X460855Y174912D02*
Y175912D01*
G01X459795Y165729D02*
Y186124D01*
G01X460855Y177812D02*
Y178812D01*
G01X459795Y165729D02*
Y186124D01*
G01X460855Y180712D02*
Y182127D01*
G01X459795Y165729D02*
Y186124D01*
G01X460855Y184027D02*
Y186124D01*
G01X463704Y167217D02*
Y186124D01*
G01X464764Y167660D02*
Y186124D01*
G01X470991Y156669D02*
X470355D01*
G01D02*
X469648Y157376D01*
G01X468940Y158720D02*
X468304D01*
G01D02*
X467373Y159651D01*
G01X466665Y160995D02*
X466029D01*
G01D02*
X465293Y161731D01*
G01X464585Y163075D02*
X463949D01*
G01D02*
X462906Y164118D01*
G01X462198Y165462D02*
X461562D01*
G01D02*
X460855Y166169D01*
G01D02*
Y170112D01*
G01Y172012D02*
Y173012D01*
G01Y174912D02*
Y175912D01*
G01Y177812D02*
Y178812D01*
G01Y180712D02*
Y182127D01*
G01Y184027D02*
Y186124D01*
G01X459795Y165729D02*
Y186124D01*
G01X464764Y167660D02*
Y186124D01*
G01X463704Y167217D02*
Y186124D01*
G01X429673Y419187D02*
Y460309D01*
G01X430733Y419187D02*
Y459869D01*
G01X429673Y460309D02*
X464529Y495165D01*
G01X430733Y459869D02*
X465589Y494725D01*
G01X434183Y419537D02*
Y457862D01*
G01X433123Y419537D02*
Y458302D01*
G01X434183Y457862D02*
X468533Y492212D01*
G01X433123Y458302D02*
X461892Y487071D01*
G01X434183Y457862D02*
X468533Y492212D01*
G01X434183Y457862D02*
X468533Y492212D01*
G01X430733Y419187D02*
Y459869D01*
G01X429673Y419187D02*
Y460309D01*
G01X430733Y459869D02*
X465589Y494725D01*
G01X429673Y460309D02*
X464529Y495165D01*
G01X433123Y419537D02*
Y458302D01*
G01X434183Y419537D02*
Y457862D01*
G01X433123Y458302D02*
X461892Y487071D01*
G01X434183Y457862D02*
X468533Y492212D01*
G01X459293Y422387D02*
Y444756D01*
G01X460353Y422387D02*
Y444316D01*
G01X459293Y444756D02*
X503564Y489027D01*
G01X460353Y444316D02*
X504624Y488587D01*
G01X464053Y423137D02*
Y443403D01*
G01X462993Y423137D02*
Y443843D01*
G01X464053Y443403D02*
X502342Y481692D01*
G01X462993Y443843D02*
X501902Y482752D01*
G01X460353Y422387D02*
Y444316D01*
G01X459293Y422387D02*
Y444756D01*
G01X460353Y444316D02*
X504624Y488587D01*
G01X459293Y444756D02*
X503564Y489027D01*
G01X462993Y423137D02*
Y443843D01*
G01X464053Y423137D02*
Y443403D01*
G01X462993Y443843D02*
X501902Y482752D01*
G01X464053Y443403D02*
X502342Y481692D01*
G01X429673Y419187D02*
Y460309D01*
G01X430733Y419187D02*
Y459869D01*
G01X429673Y460309D02*
X464529Y495165D01*
G01X430733Y459869D02*
X465589Y494725D01*
G01X429673Y419187D02*
Y460309D01*
G01X430733Y419187D02*
Y459869D01*
G01X429673Y460309D02*
X464529Y495165D01*
G01X430733Y459869D02*
X465589Y494725D01*
G01X434183Y419537D02*
Y457862D01*
G01X433123Y419537D02*
Y458302D01*
G01X434183Y457862D02*
X468533Y492212D01*
G01X433123Y458302D02*
X461892Y487071D01*
G01X434183Y457862D02*
X468533Y492212D01*
G01X434183Y457862D02*
X468533Y492212D01*
G01X430733Y419187D02*
Y459869D01*
G01X429673Y419187D02*
Y460309D01*
G01X430733Y459869D02*
X465589Y494725D01*
G01X429673Y460309D02*
X464529Y495165D01*
G01X433123Y419537D02*
Y458302D01*
G01X434183Y419537D02*
Y457862D01*
G01X433123Y458302D02*
X461892Y487071D01*
G01X434183Y457862D02*
X468533Y492212D01*
G01X433123Y419537D02*
Y458302D01*
G01X434183Y419537D02*
Y457862D01*
G01X433123Y458302D02*
X461892Y487071D01*
G01X434183Y457862D02*
X468533Y492212D01*
G01X464529Y495165D02*
Y507005D01*
G01X465589Y494725D02*
Y506565D01*
G01X464529Y507005D02*
X466753Y509229D01*
G01X465589Y506565D02*
X467813Y508789D01*
G01X466753Y509229D02*
Y538696D01*
G01X467813Y508789D02*
Y550020D01*
G01X463477Y488656D02*
X464184Y489363D01*
G01X465769Y490948D02*
X467473Y492652D01*
G01X468533Y492212D02*
Y494639D01*
G01X467473Y492652D02*
Y495079D01*
G01X468533Y494639D02*
X469411Y495517D01*
G01X467473Y495079D02*
X468971Y496577D01*
G01X469411Y495517D02*
X471480D01*
G01X468971Y496577D02*
X471040D01*
G01X471480Y495517D02*
X472972Y497009D01*
G01X471040Y496577D02*
X471912Y497449D01*
G01X472972Y497009D02*
Y499585D01*
G01X471912Y497449D02*
Y499145D01*
G01X472972Y499585D02*
X471480Y501077D01*
G01X471912Y499145D02*
X471040Y500017D01*
G01X471480Y501077D02*
X469689D01*
G01X471040Y500017D02*
X469249D01*
G01X469689Y501077D02*
X468926Y501840D01*
G01X469249Y500017D02*
X467866Y501400D01*
G01X468926Y501840D02*
Y504342D01*
G01X467866Y501400D02*
Y504782D01*
G01X468926Y504342D02*
X469754Y505170D01*
G01X467866Y504782D02*
X469314Y506230D01*
G01X469754Y505170D02*
X471692D01*
G01X469314Y506230D02*
X471252D01*
G01X471692Y505170D02*
X473113Y506591D01*
G01X471252Y506230D02*
X472053Y507031D01*
G01X473113Y506591D02*
Y550034D01*
G01X472053Y507031D02*
Y508840D01*
G01X473113Y506591D02*
Y550034D01*
G01X472053Y511080D02*
Y512496D01*
G01X473113Y506591D02*
Y550034D01*
G01X472053Y514444D02*
Y515604D01*
G01X473113Y506591D02*
Y550034D01*
G01X472053Y517710D02*
Y518934D01*
G01X473113Y506591D02*
Y550034D01*
G01X472053Y521174D02*
Y522174D01*
G01X473113Y506591D02*
Y550034D01*
G01X472053Y524414D02*
Y525414D01*
G01X473113Y506591D02*
Y550034D01*
G01Y506591D02*
Y550034D01*
G01Y506591D02*
Y550034D01*
G01Y506591D02*
Y550034D01*
G01Y506591D02*
Y550034D01*
G01Y506591D02*
Y550034D01*
G01X465589Y494725D02*
Y506565D01*
G01X464529Y495165D02*
Y507005D01*
G01X465589Y506565D02*
X467813Y508789D01*
G01X464529Y507005D02*
X466753Y509229D01*
G01X467813Y508789D02*
Y550020D01*
G01X466753Y509229D02*
Y538696D01*
G01X467813Y508789D02*
Y550020D01*
G01Y508789D02*
Y550020D01*
G01Y508789D02*
Y550020D01*
G01X463477Y488656D02*
X464184Y489363D01*
G01X465769Y490948D02*
X467473Y492652D01*
G01D02*
Y495079D01*
G01X468533Y492212D02*
Y494639D01*
G01X467473Y495079D02*
X468971Y496577D01*
G01X468533Y494639D02*
X469411Y495517D01*
G01X468971Y496577D02*
X471040D01*
G01X469411Y495517D02*
X471480D01*
G01X471040Y496577D02*
X471912Y497449D01*
G01X471480Y495517D02*
X472972Y497009D01*
G01X471912Y497449D02*
Y499145D01*
G01X472972Y497009D02*
Y499585D01*
G01X471912Y499145D02*
X471040Y500017D01*
G01X472972Y499585D02*
X471480Y501077D01*
G01X471040Y500017D02*
X469249D01*
G01X471480Y501077D02*
X469689D01*
G01X469249Y500017D02*
X467866Y501400D01*
G01X469689Y501077D02*
X468926Y501840D01*
G01X467866Y501400D02*
Y504782D01*
G01X468926Y501840D02*
Y504342D01*
G01X467866Y504782D02*
X469314Y506230D01*
G01X468926Y504342D02*
X469754Y505170D01*
G01X469314Y506230D02*
X471252D01*
G01X469754Y505170D02*
X471692D01*
G01X471252Y506230D02*
X472053Y507031D01*
G01X471692Y505170D02*
X473113Y506591D01*
G01X472053Y507031D02*
Y508840D01*
G01Y511080D02*
Y512496D01*
G01Y514444D02*
Y515604D01*
G01Y517710D02*
Y518934D01*
G01Y521174D02*
Y522174D01*
G01Y524414D02*
Y525414D01*
G01X473113Y506591D02*
Y550034D01*
G01X464529Y495165D02*
Y507005D01*
G01X465589Y494725D02*
Y506565D01*
G01X464529Y507005D02*
X466753Y509229D01*
G01X465589Y506565D02*
X467813Y508789D01*
G01X466753Y509229D02*
Y538696D01*
G01X467813Y508789D02*
Y550020D01*
G01X464529Y495165D02*
Y507005D01*
G01X465589Y494725D02*
Y506565D01*
G01X464529Y507005D02*
X466753Y509229D01*
G01X465589Y506565D02*
X467813Y508789D01*
G01X466753Y509229D02*
Y538696D01*
G01X467813Y508789D02*
Y550020D01*
G01X463477Y488656D02*
X464184Y489363D01*
G01X465769Y490948D02*
X467473Y492652D01*
G01X468533Y492212D02*
Y494639D01*
G01X467473Y492652D02*
Y495079D01*
G01X468533Y494639D02*
X469411Y495517D01*
G01X467473Y495079D02*
X468971Y496577D01*
G01X469411Y495517D02*
X471480D01*
G01X468971Y496577D02*
X471040D01*
G01X471480Y495517D02*
X472972Y497009D01*
G01X471040Y496577D02*
X471912Y497449D01*
G01X472972Y497009D02*
Y499585D01*
G01X471912Y497449D02*
Y499145D01*
G01X472972Y499585D02*
X471480Y501077D01*
G01X471912Y499145D02*
X471040Y500017D01*
G01X471480Y501077D02*
X469689D01*
G01X471040Y500017D02*
X469249D01*
G01X469689Y501077D02*
X468926Y501840D01*
G01X469249Y500017D02*
X467866Y501400D01*
G01X468926Y501840D02*
Y504342D01*
G01X467866Y501400D02*
Y504782D01*
G01X468926Y504342D02*
X469754Y505170D01*
G01X467866Y504782D02*
X469314Y506230D01*
G01X469754Y505170D02*
X471692D01*
G01X469314Y506230D02*
X471252D01*
G01X471692Y505170D02*
X473113Y506591D01*
G01X471252Y506230D02*
X472053Y507031D01*
G01X473113Y506591D02*
Y550034D01*
G01X472053Y507031D02*
Y508840D01*
G01X473113Y506591D02*
Y550034D01*
G01X472053Y511080D02*
Y512496D01*
G01X473113Y506591D02*
Y550034D01*
G01X472053Y514444D02*
Y515604D01*
G01X473113Y506591D02*
Y550034D01*
G01X472053Y517710D02*
Y518934D01*
G01X473113Y506591D02*
Y550034D01*
G01X472053Y521174D02*
Y522174D01*
G01X473113Y506591D02*
Y550034D01*
G01X472053Y524414D02*
Y525414D01*
G01X473113Y506591D02*
Y550034D01*
G01Y506591D02*
Y550034D01*
G01Y506591D02*
Y550034D01*
G01Y506591D02*
Y550034D01*
G01Y506591D02*
Y550034D01*
G01Y506591D02*
Y550034D01*
G01X465589Y494725D02*
Y506565D01*
G01X464529Y495165D02*
Y507005D01*
G01X465589Y506565D02*
X467813Y508789D01*
G01X464529Y507005D02*
X466753Y509229D01*
G01X467813Y508789D02*
Y550020D01*
G01X466753Y509229D02*
Y538696D01*
G01X467813Y508789D02*
Y550020D01*
G01Y508789D02*
Y550020D01*
G01Y508789D02*
Y550020D01*
G01X463477Y488656D02*
X464184Y489363D01*
G01X465769Y490948D02*
X467473Y492652D01*
G01D02*
Y495079D01*
G01X468533Y492212D02*
Y494639D01*
G01X467473Y495079D02*
X468971Y496577D01*
G01X468533Y494639D02*
X469411Y495517D01*
G01X468971Y496577D02*
X471040D01*
G01X469411Y495517D02*
X471480D01*
G01X471040Y496577D02*
X471912Y497449D01*
G01X471480Y495517D02*
X472972Y497009D01*
G01X471912Y497449D02*
Y499145D01*
G01X472972Y497009D02*
Y499585D01*
G01X471912Y499145D02*
X471040Y500017D01*
G01X472972Y499585D02*
X471480Y501077D01*
G01X471040Y500017D02*
X469249D01*
G01X471480Y501077D02*
X469689D01*
G01X469249Y500017D02*
X467866Y501400D01*
G01X469689Y501077D02*
X468926Y501840D01*
G01X467866Y501400D02*
Y504782D01*
G01X468926Y501840D02*
Y504342D01*
G01X467866Y504782D02*
X469314Y506230D01*
G01X468926Y504342D02*
X469754Y505170D01*
G01X469314Y506230D02*
X471252D01*
G01X469754Y505170D02*
X471692D01*
G01X471252Y506230D02*
X472053Y507031D01*
G01X471692Y505170D02*
X473113Y506591D01*
G01X472053Y507031D02*
Y508840D01*
G01Y511080D02*
Y512496D01*
G01Y514444D02*
Y515604D01*
G01Y517710D02*
Y518934D01*
G01Y521174D02*
Y522174D01*
G01Y524414D02*
Y525414D01*
G01X473113Y506591D02*
Y550034D01*
G01X463477Y488656D02*
X464184Y489363D01*
G01X465769Y490948D02*
X467473Y492652D01*
G01D02*
Y495079D01*
G01X468533Y492212D02*
Y494639D01*
G01X467473Y495079D02*
X468971Y496577D01*
G01X468533Y494639D02*
X469411Y495517D01*
G01X468971Y496577D02*
X471040D01*
G01X469411Y495517D02*
X471480D01*
G01X471040Y496577D02*
X471912Y497449D01*
G01X471480Y495517D02*
X472972Y497009D01*
G01X471912Y497449D02*
Y499145D01*
G01X472972Y497009D02*
Y499585D01*
G01X471912Y499145D02*
X471040Y500017D01*
G01X472972Y499585D02*
X471480Y501077D01*
G01X471040Y500017D02*
X469249D01*
G01X471480Y501077D02*
X469689D01*
G01X469249Y500017D02*
X467866Y501400D01*
G01X469689Y501077D02*
X468926Y501840D01*
G01X467866Y501400D02*
Y504782D01*
G01X468926Y501840D02*
Y504342D01*
G01X467866Y504782D02*
X469314Y506230D01*
G01X468926Y504342D02*
X469754Y505170D01*
G01X469314Y506230D02*
X471252D01*
G01X469754Y505170D02*
X471692D01*
G01X471252Y506230D02*
X472053Y507031D01*
G01X471692Y505170D02*
X473113Y506591D01*
G01X472053Y507031D02*
Y508840D01*
G01Y511080D02*
Y512496D01*
G01Y514444D02*
Y515604D01*
G01Y517710D02*
Y518934D01*
G01Y521174D02*
Y522174D01*
G01Y524414D02*
Y525414D01*
G01X473113Y506591D02*
Y550034D01*
G01X462745Y552200D02*
Y570212D01*
G01X463805Y558090D02*
Y559460D01*
G01X462745Y552200D02*
Y570212D01*
G01X463805Y563140D02*
Y564560D01*
G01X466753Y540626D02*
Y541626D01*
G01Y543556D02*
Y544556D01*
G01Y546486D02*
Y549580D01*
G01D02*
X465833Y550500D01*
G01X467813Y550020D02*
X464733Y553100D01*
G01X469029Y557700D02*
X468358Y558371D01*
G01X468127Y557101D02*
X467298Y557930D01*
G01X468358Y558371D02*
Y559648D01*
G01Y563138D02*
Y564029D01*
G01X467298Y557930D02*
Y564470D01*
G01X468358Y564029D02*
X469129Y564800D01*
G01X467298Y564470D02*
X468127Y565299D01*
G01X472053Y527654D02*
Y529233D01*
G01Y531473D02*
Y534152D01*
G01Y536392D02*
Y537947D01*
G01Y540187D02*
Y541187D01*
G01Y543427D02*
Y544427D01*
G01Y546667D02*
Y549594D01*
G01X473113Y550034D02*
X469833Y553314D01*
G01X472053Y549594D02*
X470933Y550714D01*
G01X463805Y558090D02*
Y559460D01*
G01Y563140D02*
Y564560D01*
G01X462745Y552200D02*
Y570212D01*
G01X466753Y540626D02*
Y541626D01*
G01Y543556D02*
Y544556D01*
G01Y546486D02*
Y549580D01*
G01X467813Y550020D02*
X464733Y553100D01*
G01X466753Y549580D02*
X465833Y550500D01*
G01X468127Y557101D02*
X467298Y557930D01*
G01X469029Y557700D02*
X468358Y558371D01*
G01X467298Y557930D02*
Y564470D01*
G01X468358Y558371D02*
Y559648D01*
G01X467298Y557930D02*
Y564470D01*
G01X468358Y563138D02*
Y564029D01*
G01X467298Y564470D02*
X468127Y565299D01*
G01X468358Y564029D02*
X469129Y564800D01*
G01X472053Y527654D02*
Y529233D01*
G01Y531473D02*
Y534152D01*
G01Y536392D02*
Y537947D01*
G01Y540187D02*
Y541187D01*
G01Y543427D02*
Y544427D01*
G01Y546667D02*
Y549594D01*
G01D02*
X470933Y550714D01*
G01X473113Y550034D02*
X469833Y553314D01*
G01X462745Y552200D02*
Y570212D01*
G01X463805Y558090D02*
Y559460D01*
G01X462745Y552200D02*
Y570212D01*
G01X463805Y563140D02*
Y564560D01*
G01X466753Y540626D02*
Y541626D01*
G01Y543556D02*
Y544556D01*
G01Y546486D02*
Y549580D01*
G01D02*
X465833Y550500D01*
G01X467813Y550020D02*
X464733Y553100D01*
G01X462745Y552200D02*
Y570212D01*
G01X463805Y558090D02*
Y559460D01*
G01X462745Y552200D02*
Y570212D01*
G01X463805Y563140D02*
Y564560D01*
G01X466753Y540626D02*
Y541626D01*
G01Y543556D02*
Y544556D01*
G01Y546486D02*
Y549580D01*
G01D02*
X465833Y550500D01*
G01X467813Y550020D02*
X464733Y553100D01*
G01X469029Y557700D02*
X468358Y558371D01*
G01X468127Y557101D02*
X467298Y557930D01*
G01X468358Y558371D02*
Y559648D01*
G01Y563138D02*
Y564029D01*
G01X467298Y557930D02*
Y564470D01*
G01X468358Y564029D02*
X469129Y564800D01*
G01X467298Y564470D02*
X468127Y565299D01*
G01X472053Y527654D02*
Y529233D01*
G01Y531473D02*
Y534152D01*
G01Y536392D02*
Y537947D01*
G01Y540187D02*
Y541187D01*
G01Y543427D02*
Y544427D01*
G01Y546667D02*
Y549594D01*
G01X473113Y550034D02*
X469833Y553314D01*
G01X472053Y549594D02*
X470933Y550714D01*
G01X463805Y558090D02*
Y559460D01*
G01Y563140D02*
Y564560D01*
G01X462745Y552200D02*
Y570212D01*
G01X466753Y540626D02*
Y541626D01*
G01Y543556D02*
Y544556D01*
G01Y546486D02*
Y549580D01*
G01X467813Y550020D02*
X464733Y553100D01*
G01X466753Y549580D02*
X465833Y550500D01*
G01X468127Y557101D02*
X467298Y557930D01*
G01X469029Y557700D02*
X468358Y558371D01*
G01X467298Y557930D02*
Y564470D01*
G01X468358Y558371D02*
Y559648D01*
G01X467298Y557930D02*
Y564470D01*
G01X468358Y563138D02*
Y564029D01*
G01X467298Y564470D02*
X468127Y565299D01*
G01X468358Y564029D02*
X469129Y564800D01*
G01X472053Y527654D02*
Y529233D01*
G01Y531473D02*
Y534152D01*
G01Y536392D02*
Y537947D01*
G01Y540187D02*
Y541187D01*
G01Y543427D02*
Y544427D01*
G01Y546667D02*
Y549594D01*
G01D02*
X470933Y550714D01*
G01X473113Y550034D02*
X469833Y553314D01*
G01X468127Y557101D02*
X467298Y557930D01*
G01X469029Y557700D02*
X468358Y558371D01*
G01X467298Y557930D02*
Y564470D01*
G01X468358Y558371D02*
Y559648D01*
G01X467298Y557930D02*
Y564470D01*
G01X468358Y563138D02*
Y564029D01*
G01X467298Y564470D02*
X468127Y565299D01*
G01X468358Y564029D02*
X469129Y564800D01*
G01X472053Y527654D02*
Y529233D01*
G01Y531473D02*
Y534152D01*
G01Y536392D02*
Y537947D01*
G01Y540187D02*
Y541187D01*
G01Y543427D02*
Y544427D01*
G01Y546667D02*
Y549594D01*
G01D02*
X470933Y550714D01*
G01X473113Y550034D02*
X469833Y553314D01*
G01X573151Y-46771D02*
X511716D01*
G01X572711Y-47831D02*
X511716D01*
G01X572711D02*
X511716D01*
G01X573151Y-46771D02*
X511716D01*
G01X499690Y13554D02*
Y21131D01*
G01X500750Y19620D02*
Y20688D01*
G01X499690Y21131D02*
X503564Y25005D01*
G01X500750Y20688D02*
X504624Y24562D01*
G01X503564Y25005D02*
Y119138D01*
G01X504624Y24562D02*
Y36580D01*
G01X503564Y25005D02*
Y119138D01*
G01Y25005D02*
Y119138D01*
G01X505390Y18999D02*
Y21231D01*
G01X506450Y19920D02*
Y20788D01*
G01X505390Y21231D02*
X508829Y24670D01*
G01X506450Y20788D02*
X507424Y21762D01*
G01X505390Y21231D02*
X508829Y24670D01*
G01X507424Y21762D02*
X508300D01*
G01X505390Y21231D02*
X508829Y24670D01*
G01X509008Y23346D02*
X509889Y24227D01*
G01X508829Y24670D02*
Y113491D01*
G01X509889Y24227D02*
Y37080D01*
G01X508829Y24670D02*
Y113491D01*
G01X500750Y19620D02*
Y20688D01*
G01X499690Y13554D02*
Y21131D01*
G01X500750Y20688D02*
X504624Y24562D01*
G01X499690Y21131D02*
X503564Y25005D01*
G01X504624Y24562D02*
Y36580D01*
G01X503564Y25005D02*
Y119138D01*
G01X506450Y19920D02*
Y20788D01*
G01X505390Y18999D02*
Y21231D01*
G01X506450Y20788D02*
X507424Y21762D01*
G01D02*
X508300D01*
G01X509008Y23346D02*
X509889Y24227D01*
G01X505390Y21231D02*
X508829Y24670D01*
G01X509889Y24227D02*
Y37080D01*
G01X508829Y24670D02*
Y113491D01*
G01X540401Y33291D02*
X539690Y32580D01*
G01D02*
X539174D01*
G01X540130Y31520D02*
X539151D01*
G01X540401Y33291D02*
X539690Y32580D01*
G01X540130Y31520D02*
X539151D01*
G01X539690Y32580D02*
X539174D01*
G01X540401Y33291D02*
X539690Y32580D01*
G01D02*
X539174D01*
G01X540130Y31520D02*
X539151D01*
G01X540401Y33291D02*
X539690Y32580D01*
G01X540130Y31520D02*
X539151D01*
G01X539690Y32580D02*
X539174D01*
G01X504624Y38820D02*
Y39580D01*
G01Y41820D02*
Y118695D01*
G01X509889Y39320D02*
Y113934D01*
G01X504624Y38820D02*
Y39580D01*
G01Y41820D02*
Y118695D01*
G01X509889Y39320D02*
Y113934D01*
G01X540312Y62190D02*
X538312Y60190D01*
G01X541372Y61747D02*
X539372Y59747D01*
G01X538312Y60190D02*
Y57320D01*
G01X539372Y59747D02*
Y56781D01*
G01X539454Y49500D02*
X540401Y48553D01*
G01X538355Y52100D02*
X541461Y48994D01*
G01X541372Y61747D02*
X539372Y59747D01*
G01X540312Y62190D02*
X538312Y60190D01*
G01X539372Y59747D02*
Y56781D01*
G01X538312Y60190D02*
Y57320D01*
G01X538355Y52100D02*
X541461Y48994D01*
G01X539454Y49500D02*
X540401Y48553D01*
G01X540312Y62190D02*
X538312Y60190D01*
G01X541372Y61747D02*
X539372Y59747D01*
G01X538312Y60190D02*
Y57320D01*
G01X539372Y59747D02*
Y56781D01*
G01X539454Y49500D02*
X540401Y48553D01*
G01X538355Y52100D02*
X541461Y48994D01*
G01X541372Y61747D02*
X539372Y59747D01*
G01X540312Y62190D02*
X538312Y60190D01*
G01X539372Y59747D02*
Y56781D01*
G01X538312Y60190D02*
Y57320D01*
G01X538355Y52100D02*
X541461Y48994D01*
G01X539454Y49500D02*
X540401Y48553D01*
G01X503564Y119138D02*
X504130Y119704D01*
G01X504624Y118695D02*
X505190Y119261D01*
G01X504130Y119704D02*
Y121050D01*
G01X505190Y119261D02*
Y121490D01*
G01X504130Y121050D02*
X502475Y122705D01*
G01X505190Y121490D02*
X502915Y123765D01*
G01X502475Y122705D02*
X501130D01*
G01X502915Y123765D02*
X500690D01*
G01X501130Y122705D02*
X499103Y120678D01*
G01X500690Y123765D02*
X498663Y121738D01*
G01X501130Y122705D02*
X499103Y120678D01*
G01D02*
X497182D01*
G01X498663Y121738D02*
X497622D01*
G01X497182Y120678D02*
X494699Y123161D01*
G01X497622Y121738D02*
X495759Y123601D01*
G01X494699Y123161D02*
Y125270D01*
G01X495759Y123601D02*
Y124830D01*
G01X494699Y125270D02*
X496810Y127381D01*
G01X495759Y124830D02*
X497870Y126941D01*
G01X496810Y127381D02*
Y128714D01*
G01X497870Y126941D02*
Y129154D01*
G01X508829Y113491D02*
X508012Y114308D01*
G01X509889Y113934D02*
X509072Y114751D01*
G01X508012Y114308D02*
Y122909D01*
G01X509072Y114751D02*
Y123352D01*
G01X504624Y118695D02*
X505190Y119261D01*
G01X503564Y119138D02*
X504130Y119704D01*
G01X505190Y119261D02*
Y121490D01*
G01X504130Y119704D02*
Y121050D01*
G01X505190Y121490D02*
X502915Y123765D01*
G01X504130Y121050D02*
X502475Y122705D01*
G01X502915Y123765D02*
X500690D01*
G01X502475Y122705D02*
X501130D01*
G01X500690Y123765D02*
X498663Y121738D01*
G01D02*
X497622D01*
G01X501130Y122705D02*
X499103Y120678D01*
G01X498663Y121738D02*
X497622D01*
G01X499103Y120678D02*
X497182D01*
G01X497622Y121738D02*
X495759Y123601D01*
G01X497182Y120678D02*
X494699Y123161D01*
G01X495759Y123601D02*
Y124830D01*
G01X494699Y123161D02*
Y125270D01*
G01X495759Y124830D02*
X497870Y126941D01*
G01X494699Y125270D02*
X496810Y127381D01*
G01X497870Y126941D02*
Y129154D01*
G01X496810Y127381D02*
Y128714D01*
G01X509889Y113934D02*
X509072Y114751D01*
G01X508829Y113491D02*
X508012Y114308D01*
G01X509072Y114751D02*
Y123352D01*
G01X508012Y114308D02*
Y122909D01*
G01X512409Y181800D02*
X557744Y136465D01*
G01X512849Y182860D02*
X558804Y136905D01*
G01X512849Y182860D02*
X558804Y136905D01*
G01X512409Y181800D02*
X557744Y136465D01*
G01X512409Y181800D02*
X557744Y136465D01*
G01X512849Y182860D02*
X558804Y136905D01*
G01X512849Y182860D02*
X558804Y136905D01*
G01X512409Y181800D02*
X557744Y136465D01*
G01X485812Y199020D02*
X503032Y181800D01*
G01X486561Y199771D02*
X487268Y199064D01*
G01X485812Y199020D02*
X503032Y181800D01*
G01X488612Y197720D02*
X489378Y196954D01*
G01X485812Y199020D02*
X503032Y181800D01*
G01X490722Y195610D02*
X491429Y194903D01*
G01X485812Y199020D02*
X503032Y181800D01*
G01X492773Y193559D02*
X493570Y192762D01*
G01X485812Y199020D02*
X503032Y181800D01*
G01X494915Y191417D02*
X495780Y190552D01*
G01X485812Y199020D02*
X503032Y181800D01*
G01X497124Y189208D02*
X497831Y188501D01*
G01X485812Y199020D02*
X503032Y181800D01*
G01X499175Y187157D02*
X500119Y186213D01*
G01X485812Y199020D02*
X503032Y181800D01*
G01X501463Y184869D02*
X503472Y182860D01*
G01X503032Y181800D02*
X512409D01*
G01X503472Y182860D02*
X512849D01*
G01X486561Y199771D02*
X487268Y199064D01*
G01X488612Y197720D02*
X489378Y196954D01*
G01X490722Y195610D02*
X491429Y194903D01*
G01X492773Y193559D02*
X493570Y192762D01*
G01X494915Y191417D02*
X495780Y190552D01*
G01X497124Y189208D02*
X497831Y188501D01*
G01X499175Y187157D02*
X500119Y186213D01*
G01X501463Y184869D02*
X503472Y182860D01*
G01X485812Y199020D02*
X503032Y181800D01*
G01X503472Y182860D02*
X512849D01*
G01X503032Y181800D02*
X512409D01*
G01X489652Y203840D02*
X507687Y185805D01*
G01X488903Y203089D02*
X489624Y202368D01*
G01X489652Y203840D02*
X507687Y185805D01*
G01X490969Y201023D02*
X492159Y199833D01*
G01X489652Y203840D02*
X507687Y185805D01*
G01X493504Y198488D02*
X494369Y197623D01*
G01X489652Y203840D02*
X507687Y185805D01*
G01X495713Y196279D02*
X507247Y184745D01*
G01X507687Y185805D02*
X515304D01*
G01X507247Y184745D02*
X514864D01*
G01X515304Y185805D02*
X570172Y130937D01*
G01X514864Y184745D02*
X569112Y130497D01*
G01X488903Y203089D02*
X489624Y202368D01*
G01X490969Y201023D02*
X492159Y199833D01*
G01X493504Y198488D02*
X494369Y197623D01*
G01X495713Y196279D02*
X507247Y184745D01*
G01X489652Y203840D02*
X507687Y185805D01*
G01X507247Y184745D02*
X514864D01*
G01X507687Y185805D02*
X515304D01*
G01X514864Y184745D02*
X569112Y130497D01*
G01X515304Y185805D02*
X570172Y130937D01*
G01X485812Y199020D02*
X503032Y181800D01*
G01X486561Y199771D02*
X487268Y199064D01*
G01X485812Y199020D02*
X503032Y181800D01*
G01X488612Y197720D02*
X489378Y196954D01*
G01X485812Y199020D02*
X503032Y181800D01*
G01X490722Y195610D02*
X491429Y194903D01*
G01X485812Y199020D02*
X503032Y181800D01*
G01X492773Y193559D02*
X493570Y192762D01*
G01X485812Y199020D02*
X503032Y181800D01*
G01X494915Y191417D02*
X495780Y190552D01*
G01X485812Y199020D02*
X503032Y181800D01*
G01X497124Y189208D02*
X497831Y188501D01*
G01X485812Y199020D02*
X503032Y181800D01*
G01X499175Y187157D02*
X500119Y186213D01*
G01X485812Y199020D02*
X503032Y181800D01*
G01X501463Y184869D02*
X503472Y182860D01*
G01X503032Y181800D02*
X512409D01*
G01X503472Y182860D02*
X512849D01*
G01X488903Y203089D02*
X489624Y202368D01*
G01X490969Y201023D02*
X492159Y199833D01*
G01X493504Y198488D02*
X494369Y197623D01*
G01X495713Y196279D02*
X507247Y184745D01*
G01X489652Y203840D02*
X507687Y185805D01*
G01X507247Y184745D02*
X514864D01*
G01X507687Y185805D02*
X515304D01*
G01X514864Y184745D02*
X569112Y130497D01*
G01X515304Y185805D02*
X570172Y130937D01*
G01X486561Y199771D02*
X487268Y199064D01*
G01X488612Y197720D02*
X489378Y196954D01*
G01X490722Y195610D02*
X491429Y194903D01*
G01X492773Y193559D02*
X493570Y192762D01*
G01X494915Y191417D02*
X495780Y190552D01*
G01X497124Y189208D02*
X497831Y188501D01*
G01X499175Y187157D02*
X500119Y186213D01*
G01X501463Y184869D02*
X503472Y182860D01*
G01X485812Y199020D02*
X503032Y181800D01*
G01X503472Y182860D02*
X512849D01*
G01X503032Y181800D02*
X512409D01*
G01X489652Y203840D02*
X507687Y185805D01*
G01X488903Y203089D02*
X489624Y202368D01*
G01X489652Y203840D02*
X507687Y185805D01*
G01X490969Y201023D02*
X492159Y199833D01*
G01X489652Y203840D02*
X507687Y185805D01*
G01X493504Y198488D02*
X494369Y197623D01*
G01X489652Y203840D02*
X507687Y185805D01*
G01X495713Y196279D02*
X507247Y184745D01*
G01X507687Y185805D02*
X515304D01*
G01X507247Y184745D02*
X514864D01*
G01X515304Y185805D02*
X570172Y130937D01*
G01X514864Y184745D02*
X569112Y130497D01*
G01X491207Y422445D02*
X494562Y425800D01*
G01X491958Y421696D02*
X495002Y424740D01*
G01X494562Y425800D02*
X508222D01*
G01X495002Y424740D02*
X508662D01*
G01X508222Y425800D02*
X577186Y494764D01*
G01X508662Y424740D02*
X578246Y494324D01*
G01X500179Y421345D02*
X509934D01*
G01X500179Y422405D02*
X509494D01*
G01X509934Y421345D02*
X562167Y473578D01*
G01X509494Y422405D02*
X561727Y474638D01*
G01X491958Y421696D02*
X495002Y424740D01*
G01X491207Y422445D02*
X494562Y425800D01*
G01X495002Y424740D02*
X508662D01*
G01X494562Y425800D02*
X508222D01*
G01X508662Y424740D02*
X578246Y494324D01*
G01X508222Y425800D02*
X577186Y494764D01*
G01X500179Y422405D02*
X509494D01*
G01X500179Y421345D02*
X509934D01*
G01X509494Y422405D02*
X561727Y474638D01*
G01X509934Y421345D02*
X562167Y473578D01*
G01X491207Y422445D02*
X494562Y425800D01*
G01X491958Y421696D02*
X495002Y424740D01*
G01X494562Y425800D02*
X508222D01*
G01X495002Y424740D02*
X508662D01*
G01X508222Y425800D02*
X577186Y494764D01*
G01X508662Y424740D02*
X578246Y494324D01*
G01X500179Y421345D02*
X509934D01*
G01X500179Y422405D02*
X509494D01*
G01X509934Y421345D02*
X562167Y473578D01*
G01X509494Y422405D02*
X561727Y474638D01*
G01X491958Y421696D02*
X495002Y424740D01*
G01X491207Y422445D02*
X494562Y425800D01*
G01X495002Y424740D02*
X508662D01*
G01X494562Y425800D02*
X508222D01*
G01X508662Y424740D02*
X578246Y494324D01*
G01X508222Y425800D02*
X577186Y494764D01*
G01X500179Y422405D02*
X509494D01*
G01X500179Y421345D02*
X509934D01*
G01X509494Y422405D02*
X561727Y474638D01*
G01X509934Y421345D02*
X562167Y473578D01*
G01X503564Y489027D02*
Y575949D01*
G01X504624Y488587D02*
Y587820D01*
G01X502342Y481692D02*
X503923D01*
G01X501902Y482752D02*
X504363D01*
G01X503923Y481692D02*
X505344Y480271D01*
G01X504363Y482752D02*
X505784Y481331D01*
G01X505344Y480271D02*
X507275D01*
G01X505784Y481331D02*
X506835D01*
G01X507275Y480271D02*
X509155Y482151D01*
G01X506835Y481331D02*
X508095Y482591D01*
G01X509155Y482151D02*
Y483736D01*
G01X508095Y482591D02*
Y483296D01*
G01X509155Y483736D02*
X506994Y485897D01*
G01X508095Y483296D02*
X505934Y485457D01*
G01X506994Y485897D02*
Y486802D01*
G01X505934Y485457D02*
Y487242D01*
G01X506994Y486802D02*
X509724Y489532D01*
G01X505934Y487242D02*
X508664Y489972D01*
G01X509724Y489532D02*
Y588034D01*
G01X508664Y489972D02*
Y518908D01*
G01X509724Y489532D02*
Y588034D01*
G01X508664Y521148D02*
Y522148D01*
G01X509724Y489532D02*
Y588034D01*
G01X508664Y524388D02*
Y525388D01*
G01X509724Y489532D02*
Y588034D01*
G01Y489532D02*
Y588034D01*
G01Y489532D02*
Y588034D01*
G01Y489532D02*
Y588034D01*
G01Y489532D02*
Y588034D01*
G01Y489532D02*
Y588034D01*
G01Y489532D02*
Y588034D01*
G01Y489532D02*
Y588034D01*
G01Y489532D02*
Y588034D01*
G01Y489532D02*
Y588034D01*
G01Y489532D02*
Y588034D01*
G01X504624Y488587D02*
Y587820D01*
G01X503564Y489027D02*
Y575949D01*
G01X504624Y488587D02*
Y587820D01*
G01Y488587D02*
Y587820D01*
G01Y488587D02*
Y587820D01*
G01X501902Y482752D02*
X504363D01*
G01X502342Y481692D02*
X503923D01*
G01X504363Y482752D02*
X505784Y481331D01*
G01X503923Y481692D02*
X505344Y480271D01*
G01X505784Y481331D02*
X506835D01*
G01X505344Y480271D02*
X507275D01*
G01X506835Y481331D02*
X508095Y482591D01*
G01X507275Y480271D02*
X509155Y482151D01*
G01X508095Y482591D02*
Y483296D01*
G01X509155Y482151D02*
Y483736D01*
G01X508095Y483296D02*
X505934Y485457D01*
G01X509155Y483736D02*
X506994Y485897D01*
G01X505934Y485457D02*
Y487242D01*
G01X506994Y485897D02*
Y486802D01*
G01X505934Y487242D02*
X508664Y489972D01*
G01X506994Y486802D02*
X509724Y489532D01*
G01X508664Y489972D02*
Y518908D01*
G01Y521148D02*
Y522148D01*
G01Y524388D02*
Y525388D01*
G01X509724Y489532D02*
Y588034D01*
G01X538132Y501040D02*
Y504286D01*
G01X539192Y500600D02*
Y503846D01*
G01X538132Y504286D02*
X540375Y506529D01*
G01X539192Y503846D02*
X541435Y506089D01*
G01X539192Y500600D02*
Y503846D01*
G01X538132Y501040D02*
Y504286D01*
G01X539192Y503846D02*
X541435Y506089D01*
G01X538132Y504286D02*
X540375Y506529D01*
G01X503564Y577659D02*
Y579070D01*
G01Y580964D02*
Y582137D01*
G01Y584377D02*
Y587380D01*
G01D02*
X502644Y588300D01*
G01X504624Y587820D02*
X501544Y590900D01*
G01X508664Y527628D02*
Y537842D01*
G01Y540082D02*
Y541082D01*
G01Y543322D02*
Y544322D01*
G01Y546562D02*
Y551124D01*
G01Y552860D02*
Y556881D01*
G01Y559121D02*
Y560121D01*
G01Y562361D02*
Y563361D01*
G01Y565601D02*
Y575921D01*
G01Y578161D02*
Y579161D01*
G01Y581401D02*
Y582401D01*
G01Y584641D02*
Y587594D01*
G01X509724Y588034D02*
X506644Y591114D01*
G01X508664Y587594D02*
X507744Y588514D01*
G01X503564Y577659D02*
Y579070D01*
G01Y580964D02*
Y582137D01*
G01Y584377D02*
Y587380D01*
G01X504624Y587820D02*
X501544Y590900D01*
G01X503564Y587380D02*
X502644Y588300D01*
G01X508664Y527628D02*
Y537842D01*
G01Y540082D02*
Y541082D01*
G01Y543322D02*
Y544322D01*
G01Y546562D02*
Y551124D01*
G01Y552860D02*
Y556881D01*
G01Y559121D02*
Y560121D01*
G01Y562361D02*
Y563361D01*
G01Y565601D02*
Y575921D01*
G01Y578161D02*
Y579161D01*
G01Y581401D02*
Y582401D01*
G01Y584641D02*
Y587594D01*
G01D02*
X507744Y588514D01*
G01X509724Y588034D02*
X506644Y591114D01*
G01X777569Y-42660D02*
X583560D01*
G01X777569Y-43720D02*
X583560D01*
G01Y-42660D02*
G03Y-47440I0J-2390D01*
G01Y-43720D02*
G03Y-46380I0J-1330D01*
G01Y-47440D02*
X777172D01*
G01X583560Y-46380D02*
X777172D01*
G01Y-50100D02*
X576480D01*
G01X777172Y-51160D02*
X576040D01*
G01X576480Y-50100D02*
X573151Y-46771D01*
G01X576040Y-51160D02*
X572711Y-47831D01*
G01X777569Y-43720D02*
X583560D01*
G01X777569Y-42660D02*
X583560D01*
G01Y-43720D02*
G03Y-46380I0J-1330D01*
G01Y-42660D02*
G03Y-47440I0J-2390D01*
G01Y-46380D02*
X777172D01*
G01X583560Y-47440D02*
X777172D01*
G01Y-51160D02*
X576040D01*
G01X777172Y-50100D02*
X576480D01*
G01X576040Y-51160D02*
X572711Y-47831D01*
G01X576480Y-50100D02*
X573151Y-46771D01*
G01X577212Y33291D02*
X576501Y32580D01*
G01D02*
X575985D01*
G01X578272Y32848D02*
X576944Y31520D01*
G01X576501Y32580D02*
X575985D01*
G01X576944Y31520D02*
X575962D01*
G01X578272Y32848D02*
X576944Y31520D01*
G01X577212Y33291D02*
X576501Y32580D01*
G01X578272Y32848D02*
X576944Y31520D01*
G01D02*
X575962D01*
G01X576501Y32580D02*
X575985D01*
G01X583458Y33732D02*
X580266Y30540D01*
G01X583458Y33732D02*
X580266Y30540D01*
G01X583458Y33732D02*
X580266Y30540D01*
G01X541461Y32851D02*
X540130Y31520D01*
G01X541461Y32851D02*
X540130Y31520D01*
G01X541461Y32851D02*
X540130Y31520D01*
G01X541461Y32851D02*
X540130Y31520D01*
G01X577212Y33291D02*
X576501Y32580D01*
G01D02*
X575985D01*
G01X578272Y32848D02*
X576944Y31520D01*
G01X576501Y32580D02*
X575985D01*
G01X576944Y31520D02*
X575962D01*
G01X583458Y33732D02*
X580266Y30540D01*
G01X578272Y32848D02*
X576944Y31520D01*
G01X577212Y33291D02*
X576501Y32580D01*
G01X578272Y32848D02*
X576944Y31520D01*
G01D02*
X575962D01*
G01X576501Y32580D02*
X575985D01*
G01X546647Y33732D02*
X543455Y30540D01*
G01X546647Y33732D02*
X543455Y30540D01*
G01X546647Y33732D02*
X543455Y30540D01*
G01X546647Y33732D02*
X543455Y30540D01*
G01X546647Y33732D02*
X543455Y30540D01*
G01X546647Y33732D02*
X543455Y30540D01*
G01X583458Y33732D02*
X580266Y30540D01*
G01X583458Y33732D02*
X580266Y30540D01*
G01X575166Y49500D02*
X576265D01*
G01D02*
X577212Y48553D01*
G01X575166Y52100D02*
X578272Y48994D01*
G01X577212Y48553D02*
Y46020D01*
G01Y41880D02*
Y40920D01*
G01Y36580D02*
Y33291D01*
G01X578272Y48994D02*
Y32848D01*
G01X577186Y109373D02*
Y63565D01*
G01Y109373D02*
Y63565D01*
G01X578246Y93780D02*
Y83320D01*
G01X577186Y109373D02*
Y63565D01*
G01X578246Y81080D02*
Y80320D01*
G01X577186Y109373D02*
Y63565D01*
G01X578246Y78080D02*
Y77320D01*
G01X577186Y109373D02*
Y63565D01*
G01X578246Y75080D02*
Y63122D01*
G01X577186Y63565D02*
X573312Y59691D01*
G01X578246Y63122D02*
X574372Y59248D01*
G01X573312Y59691D02*
Y51354D01*
G01X574372Y59248D02*
Y57420D01*
G01X575166Y52100D02*
X578272Y48994D01*
G01X575166Y49500D02*
X576265D01*
G01X575166Y52100D02*
X578272Y48994D01*
G01X576265Y49500D02*
X577212Y48553D01*
G01X578272Y48994D02*
Y32848D01*
G01X577212Y48553D02*
Y46020D01*
G01X578272Y48994D02*
Y32848D01*
G01X577212Y41880D02*
Y40920D01*
G01X578272Y48994D02*
Y32848D01*
G01X577212Y36580D02*
Y33291D01*
G01X578246Y93780D02*
Y83320D01*
G01Y81080D02*
Y80320D01*
G01Y78080D02*
Y77320D01*
G01Y75080D02*
Y63122D01*
G01X577186Y109373D02*
Y63565D01*
G01X578246Y63122D02*
X574372Y59248D01*
G01X577186Y63565D02*
X573312Y59691D01*
G01X574372Y59248D02*
Y57420D01*
G01X573312Y59691D02*
Y51354D01*
G01X580266Y52314D02*
X583458Y49122D01*
G01X580266Y49715D02*
X581364D01*
G01X580266Y52314D02*
X583458Y49122D01*
G01X581364Y49715D02*
X582398Y48681D01*
G01X583458Y49122D02*
Y33732D01*
G01X582398Y48681D02*
Y45906D01*
G01X583458Y49122D02*
Y33732D01*
G01X582398Y42080D02*
Y40707D01*
G01X583458Y49122D02*
Y33732D01*
G01X582398Y36793D02*
Y34172D01*
G01D02*
X581375Y33149D01*
G01D02*
X580266D01*
G01X583346Y110117D02*
Y71620D01*
G01Y69380D02*
Y68620D01*
G01Y66380D02*
Y62382D01*
G01X582286Y109676D02*
Y62825D01*
G01X583346Y62382D02*
X579572Y58608D01*
G01X582286Y62825D02*
X578512Y59051D01*
G01X579572Y58608D02*
Y57620D01*
G01X578512Y59051D02*
Y51468D01*
G01X580266Y49715D02*
X581364D01*
G01D02*
X582398Y48681D01*
G01X580266Y52314D02*
X583458Y49122D01*
G01X582398Y48681D02*
Y45906D01*
G01Y42080D02*
Y40707D01*
G01Y36793D02*
Y34172D01*
G01X583458Y49122D02*
Y33732D01*
G01X582398Y34172D02*
X581375Y33149D01*
G01D02*
X580266D01*
G01X582286Y109676D02*
Y62825D01*
G01X583346Y110117D02*
Y71620D01*
G01X582286Y109676D02*
Y62825D01*
G01X583346Y69380D02*
Y68620D01*
G01X582286Y109676D02*
Y62825D01*
G01X583346Y66380D02*
Y62382D01*
G01X582286Y62825D02*
X578512Y59051D01*
G01X583346Y62382D02*
X579572Y58608D01*
G01X578512Y59051D02*
Y51468D01*
G01X579572Y58608D02*
Y57620D01*
G01X540312Y105934D02*
Y62190D01*
G01X541372Y107497D02*
Y61747D01*
G01X540401Y48553D02*
Y46020D01*
G01Y41880D02*
Y40920D01*
G01Y36580D02*
Y33291D01*
G01X541461Y48994D02*
Y32851D01*
G01X541372Y107497D02*
Y61747D01*
G01X540312Y105934D02*
Y62190D01*
G01X541461Y48994D02*
Y32851D01*
G01X540401Y48553D02*
Y46020D01*
G01X541461Y48994D02*
Y32851D01*
G01X540401Y41880D02*
Y40920D01*
G01X541461Y48994D02*
Y32851D01*
G01X540401Y36580D02*
Y33291D01*
G01X540312Y105934D02*
Y62190D01*
G01X541372Y107497D02*
Y61747D01*
G01X540401Y48553D02*
Y46020D01*
G01Y41880D02*
Y40920D01*
G01Y36580D02*
Y33291D01*
G01X541461Y48994D02*
Y32851D01*
G01X541372Y107497D02*
Y61747D01*
G01X540312Y105934D02*
Y62190D01*
G01X541461Y48994D02*
Y32851D01*
G01X540401Y48553D02*
Y46020D01*
G01X541461Y48994D02*
Y32851D01*
G01X540401Y41880D02*
Y40920D01*
G01X541461Y48994D02*
Y32851D01*
G01X540401Y36580D02*
Y33291D01*
G01X575166Y49500D02*
X576265D01*
G01D02*
X577212Y48553D01*
G01X575166Y52100D02*
X578272Y48994D01*
G01X577212Y48553D02*
Y46020D01*
G01Y41880D02*
Y40920D01*
G01Y36580D02*
Y33291D01*
G01X578272Y48994D02*
Y32848D01*
G01X577186Y109373D02*
Y63565D01*
G01Y109373D02*
Y63565D01*
G01X578246Y93780D02*
Y83320D01*
G01X577186Y109373D02*
Y63565D01*
G01X578246Y81080D02*
Y80320D01*
G01X577186Y109373D02*
Y63565D01*
G01X578246Y78080D02*
Y77320D01*
G01X577186Y109373D02*
Y63565D01*
G01X578246Y75080D02*
Y63122D01*
G01X577186Y63565D02*
X573312Y59691D01*
G01X578246Y63122D02*
X574372Y59248D01*
G01X573312Y59691D02*
Y51354D01*
G01X574372Y59248D02*
Y57420D01*
G01X580266Y49715D02*
X581364D01*
G01D02*
X582398Y48681D01*
G01X580266Y52314D02*
X583458Y49122D01*
G01X582398Y48681D02*
Y45906D01*
G01Y42080D02*
Y40707D01*
G01Y36793D02*
Y34172D01*
G01X583458Y49122D02*
Y33732D01*
G01X582398Y34172D02*
X581375Y33149D01*
G01D02*
X580266D01*
G01X582286Y109676D02*
Y62825D01*
G01X583346Y110117D02*
Y71620D01*
G01X582286Y109676D02*
Y62825D01*
G01X583346Y69380D02*
Y68620D01*
G01X582286Y109676D02*
Y62825D01*
G01X583346Y66380D02*
Y62382D01*
G01X582286Y62825D02*
X578512Y59051D01*
G01X583346Y62382D02*
X579572Y58608D01*
G01X578512Y59051D02*
Y51468D01*
G01X579572Y58608D02*
Y57620D01*
G01X575166Y52100D02*
X578272Y48994D01*
G01X575166Y49500D02*
X576265D01*
G01X575166Y52100D02*
X578272Y48994D01*
G01X576265Y49500D02*
X577212Y48553D01*
G01X578272Y48994D02*
Y32848D01*
G01X577212Y48553D02*
Y46020D01*
G01X578272Y48994D02*
Y32848D01*
G01X577212Y41880D02*
Y40920D01*
G01X578272Y48994D02*
Y32848D01*
G01X577212Y36580D02*
Y33291D01*
G01X578246Y93780D02*
Y83320D01*
G01Y81080D02*
Y80320D01*
G01Y78080D02*
Y77320D01*
G01Y75080D02*
Y63122D01*
G01X577186Y109373D02*
Y63565D01*
G01X578246Y63122D02*
X574372Y59248D01*
G01X577186Y63565D02*
X573312Y59691D01*
G01X574372Y59248D02*
Y57420D01*
G01X573312Y59691D02*
Y51354D01*
G01X545412Y105698D02*
Y60092D01*
G01X546472Y107247D02*
Y59649D01*
G01X545412Y60092D02*
X543512Y58192D01*
G01X546472Y59649D02*
X544572Y57749D01*
G01X543512Y58192D02*
Y57520D01*
G01X544572Y57749D02*
Y56620D01*
G01X543455Y49715D02*
X544553D01*
G01D02*
X545587Y48681D01*
G01X543455Y52314D02*
X546647Y49122D01*
G01X545587Y48681D02*
Y45906D01*
G01Y42080D02*
Y40707D01*
G01Y36793D02*
Y34172D01*
G01X546647Y49122D02*
Y33732D01*
G01X545587Y34172D02*
X544564Y33149D01*
G01D02*
X543455D01*
G01Y52314D02*
X546647Y49122D01*
G01X543455Y49715D02*
X544553D01*
G01X543455Y52314D02*
X546647Y49122D01*
G01X544553Y49715D02*
X545587Y48681D01*
G01X546647Y49122D02*
Y33732D01*
G01X545587Y48681D02*
Y45906D01*
G01X546647Y49122D02*
Y33732D01*
G01X545587Y42080D02*
Y40707D01*
G01X546647Y49122D02*
Y33732D01*
G01X545587Y36793D02*
Y34172D01*
G01D02*
X544564Y33149D01*
G01D02*
X543455D01*
G01X546472Y107247D02*
Y59649D01*
G01X545412Y105698D02*
Y60092D01*
G01X546472Y59649D02*
X544572Y57749D01*
G01X545412Y60092D02*
X543512Y58192D01*
G01X544572Y57749D02*
Y56620D01*
G01X543512Y58192D02*
Y57520D01*
G01X543455Y52314D02*
X546647Y49122D01*
G01X543455Y49715D02*
X544553D01*
G01X543455Y52314D02*
X546647Y49122D01*
G01X544553Y49715D02*
X545587Y48681D01*
G01X546647Y49122D02*
Y33732D01*
G01X545587Y48681D02*
Y45906D01*
G01X546647Y49122D02*
Y33732D01*
G01X545587Y42080D02*
Y40707D01*
G01X546647Y49122D02*
Y33732D01*
G01X545587Y36793D02*
Y34172D01*
G01D02*
X544564Y33149D01*
G01D02*
X543455D01*
G01X546472Y107247D02*
Y59649D01*
G01X545412Y105698D02*
Y60092D01*
G01X546472Y59649D02*
X544572Y57749D01*
G01X545412Y60092D02*
X543512Y58192D01*
G01X544572Y57749D02*
Y56620D01*
G01X543512Y58192D02*
Y57520D01*
G01X545412Y105698D02*
Y60092D01*
G01X546472Y107247D02*
Y59649D01*
G01X545412Y60092D02*
X543512Y58192D01*
G01X546472Y59649D02*
X544572Y57749D01*
G01X543512Y58192D02*
Y57520D01*
G01X544572Y57749D02*
Y56620D01*
G01X543455Y49715D02*
X544553D01*
G01D02*
X545587Y48681D01*
G01X543455Y52314D02*
X546647Y49122D01*
G01X545587Y48681D02*
Y45906D01*
G01Y42080D02*
Y40707D01*
G01Y36793D02*
Y34172D01*
G01X546647Y49122D02*
Y33732D01*
G01X545587Y34172D02*
X544564Y33149D01*
G01D02*
X543455D01*
G01X580266Y52314D02*
X583458Y49122D01*
G01X580266Y49715D02*
X581364D01*
G01X580266Y52314D02*
X583458Y49122D01*
G01X581364Y49715D02*
X582398Y48681D01*
G01X583458Y49122D02*
Y33732D01*
G01X582398Y48681D02*
Y45906D01*
G01X583458Y49122D02*
Y33732D01*
G01X582398Y42080D02*
Y40707D01*
G01X583458Y49122D02*
Y33732D01*
G01X582398Y36793D02*
Y34172D01*
G01D02*
X581375Y33149D01*
G01D02*
X580266D01*
G01X583346Y110117D02*
Y71620D01*
G01Y69380D02*
Y68620D01*
G01Y66380D02*
Y62382D01*
G01X582286Y109676D02*
Y62825D01*
G01X583346Y62382D02*
X579572Y58608D01*
G01X582286Y62825D02*
X578512Y59051D01*
G01X579572Y58608D02*
Y57620D01*
G01X578512Y59051D02*
Y51468D01*
G01X557744Y136465D02*
Y135234D01*
G01X558804Y136905D02*
Y134794D01*
G01X557744Y135234D02*
X555333Y132823D01*
G01X558804Y134794D02*
X556393Y132383D01*
G01X555333Y132823D02*
Y130816D01*
G01X556393Y132383D02*
Y131256D01*
G01X555333Y130816D02*
X557736Y128413D01*
G01X556393Y131256D02*
X558176Y129473D01*
G01X557736Y128413D02*
X559926D01*
G01D02*
X561972Y130459D01*
G01X558176Y129473D02*
X559486D01*
G01X559926Y128413D02*
X561972Y130459D01*
G01X559486Y129473D02*
X561532Y131519D01*
G01X561972Y130459D02*
X563201D01*
G01X561532Y131519D02*
X563641D01*
G01X563201Y130459D02*
X564969Y128691D01*
G01X563641Y131519D02*
X566029Y129131D01*
G01X564969Y128691D02*
Y127462D01*
G01X566029Y129131D02*
Y127019D01*
G01X564969Y127462D02*
X563089Y125582D01*
G01X566029Y127019D02*
X564149Y125139D01*
G01X563089Y125582D02*
Y123470D01*
G01X564149Y125139D02*
Y123913D01*
G01X563089Y123470D02*
X577186Y109373D01*
G01X564149Y123913D02*
X578246Y109816D01*
G01D02*
Y96020D01*
G01X558804Y136905D02*
Y134794D01*
G01X557744Y136465D02*
Y135234D01*
G01X558804Y134794D02*
X556393Y132383D01*
G01X557744Y135234D02*
X555333Y132823D01*
G01X556393Y132383D02*
Y131256D01*
G01X555333Y132823D02*
Y130816D01*
G01X556393Y131256D02*
X558176Y129473D01*
G01X555333Y130816D02*
X557736Y128413D01*
G01X558176Y129473D02*
X559486D01*
G01X557736Y128413D02*
X559926D01*
G01X558176Y129473D02*
X559486D01*
G01D02*
X561532Y131519D01*
G01X559926Y128413D02*
X561972Y130459D01*
G01X561532Y131519D02*
X563641D01*
G01X561972Y130459D02*
X563201D01*
G01X563641Y131519D02*
X566029Y129131D01*
G01X563201Y130459D02*
X564969Y128691D01*
G01X566029Y129131D02*
Y127019D01*
G01X564969Y128691D02*
Y127462D01*
G01X566029Y127019D02*
X564149Y125139D01*
G01X564969Y127462D02*
X563089Y125582D01*
G01X564149Y125139D02*
Y123913D01*
G01X563089Y125582D02*
Y123470D01*
G01X564149Y123913D02*
X578246Y109816D01*
G01X563089Y123470D02*
X577186Y109373D01*
G01X578246Y109816D02*
Y96020D01*
G01X570172Y130937D02*
Y123291D01*
G01X569112Y130497D02*
Y122851D01*
G01X570172Y123291D02*
X572078Y121386D01*
G01X569112Y122851D02*
X571328Y120636D01*
G01X572078Y121386D02*
X583346Y110117D01*
G01X571328Y120636D02*
X573728Y118236D01*
G01X572078Y121386D02*
X583346Y110117D01*
G01X573728Y118236D02*
X576009Y115954D01*
G01X572078Y121386D02*
X583346Y110117D01*
G01X576009Y115953D02*
X582286Y109676D01*
G01X569112Y130497D02*
Y122851D01*
G01X570172Y130937D02*
Y123291D01*
G01X569112Y122851D02*
X571328Y120636D01*
G01X570172Y123291D02*
X572078Y121386D01*
G01X571328Y120636D02*
X573728Y118236D01*
G01D02*
X576009Y115954D01*
G01Y115953D02*
X582286Y109676D01*
G01X572078Y121386D02*
X583346Y110117D01*
G01X557744Y136465D02*
Y135234D01*
G01X558804Y136905D02*
Y134794D01*
G01X557744Y135234D02*
X555333Y132823D01*
G01X558804Y134794D02*
X556393Y132383D01*
G01X555333Y132823D02*
Y130816D01*
G01X556393Y132383D02*
Y131256D01*
G01X555333Y130816D02*
X557736Y128413D01*
G01X556393Y131256D02*
X558176Y129473D01*
G01X557736Y128413D02*
X559926D01*
G01D02*
X561972Y130459D01*
G01X558176Y129473D02*
X559486D01*
G01X559926Y128413D02*
X561972Y130459D01*
G01X559486Y129473D02*
X561532Y131519D01*
G01X561972Y130459D02*
X563201D01*
G01X561532Y131519D02*
X563641D01*
G01X563201Y130459D02*
X564969Y128691D01*
G01X563641Y131519D02*
X566029Y129131D01*
G01X564969Y128691D02*
Y127462D01*
G01X566029Y129131D02*
Y127019D01*
G01X564969Y127462D02*
X563089Y125582D01*
G01X566029Y127019D02*
X564149Y125139D01*
G01X563089Y125582D02*
Y123470D01*
G01X564149Y125139D02*
Y123913D01*
G01X563089Y123470D02*
X577186Y109373D01*
G01X564149Y123913D02*
X578246Y109816D01*
G01D02*
Y96020D01*
G01X569112Y130497D02*
Y122851D01*
G01X570172Y130937D02*
Y123291D01*
G01X569112Y122851D02*
X571328Y120636D01*
G01X570172Y123291D02*
X572078Y121386D01*
G01X571328Y120636D02*
X573728Y118236D01*
G01D02*
X576009Y115954D01*
G01Y115953D02*
X582286Y109676D01*
G01X572078Y121386D02*
X583346Y110117D01*
G01X558804Y136905D02*
Y134794D01*
G01X557744Y136465D02*
Y135234D01*
G01X558804Y134794D02*
X556393Y132383D01*
G01X557744Y135234D02*
X555333Y132823D01*
G01X556393Y132383D02*
Y131256D01*
G01X555333Y132823D02*
Y130816D01*
G01X556393Y131256D02*
X558176Y129473D01*
G01X555333Y130816D02*
X557736Y128413D01*
G01X558176Y129473D02*
X559486D01*
G01X557736Y128413D02*
X559926D01*
G01X558176Y129473D02*
X559486D01*
G01D02*
X561532Y131519D01*
G01X559926Y128413D02*
X561972Y130459D01*
G01X561532Y131519D02*
X563641D01*
G01X561972Y130459D02*
X563201D01*
G01X563641Y131519D02*
X566029Y129131D01*
G01X563201Y130459D02*
X564969Y128691D01*
G01X566029Y129131D02*
Y127019D01*
G01X564969Y128691D02*
Y127462D01*
G01X566029Y127019D02*
X564149Y125139D01*
G01X564969Y127462D02*
X563089Y125582D01*
G01X564149Y125139D02*
Y123913D01*
G01X563089Y125582D02*
Y123470D01*
G01X564149Y123913D02*
X578246Y109816D01*
G01X563089Y123470D02*
X577186Y109373D01*
G01X578246Y109816D02*
Y96020D01*
G01X570172Y130937D02*
Y123291D01*
G01X569112Y130497D02*
Y122851D01*
G01X570172Y123291D02*
X572078Y121386D01*
G01X569112Y122851D02*
X571328Y120636D01*
G01X572078Y121386D02*
X583346Y110117D01*
G01X571328Y120636D02*
X573728Y118236D01*
G01X572078Y121386D02*
X583346Y110117D01*
G01X573728Y118236D02*
X576009Y115954D01*
G01X572078Y121386D02*
X583346Y110117D01*
G01X576009Y115953D02*
X582286Y109676D01*
G01X577186Y494764D02*
Y538398D01*
G01X578246Y494324D02*
Y550020D01*
G01X562167Y473578D02*
X567098D01*
G01X561727Y474638D02*
X566658D01*
G01X567098Y473578D02*
X571740Y478220D01*
G01X566658Y474638D02*
X570680Y478660D01*
G01X571740Y478220D02*
Y480536D01*
G01X570680Y478660D02*
Y480976D01*
G01X571740Y480536D02*
X573004Y481800D01*
G01X570680Y480976D02*
X572564Y482860D01*
G01X573004Y481800D02*
X575330D01*
G01X572564Y482860D02*
X574890D01*
G01X575330Y481800D02*
X576934Y483404D01*
G01X574890Y482860D02*
X575874Y483844D01*
G01X576934Y483404D02*
Y485156D01*
G01X575874Y483844D02*
Y484716D01*
G01X576934Y485156D02*
X576228Y485862D01*
G01X575874Y484716D02*
X575168Y485422D01*
G01X576228Y485862D02*
Y486722D01*
G01X575168Y485422D02*
Y487162D01*
G01X576228Y486722D02*
X577216Y487710D01*
G01X575168Y487162D02*
X576776Y488770D01*
G01X577216Y487710D02*
X578076D01*
G01X576776Y488770D02*
X578516D01*
G01X577216Y487710D02*
X578076D01*
G01D02*
X578782Y487004D01*
G01X578516Y488770D02*
X579222Y488064D01*
G01X578782Y487004D02*
X580524D01*
G01X579222Y488064D02*
X580084D01*
G01X580524Y487004D02*
X583346Y489826D01*
G01X580084Y488064D02*
X582286Y490266D01*
G01X583346Y489826D02*
Y550234D01*
G01X582286Y490266D02*
Y493415D01*
G01X583346Y489826D02*
Y550234D01*
G01X582286Y495655D02*
Y496655D01*
G01X583346Y489826D02*
Y550234D01*
G01X582286Y498895D02*
Y499895D01*
G01X583346Y489826D02*
Y550234D01*
G01X582286Y502135D02*
Y503135D01*
G01X583346Y489826D02*
Y550234D01*
G01X582286Y505375D02*
Y506375D01*
G01X583346Y489826D02*
Y550234D01*
G01X582286Y508615D02*
Y510432D01*
G01X583346Y489826D02*
Y550234D01*
G01X582286Y512538D02*
Y519067D01*
G01X583346Y489826D02*
Y550234D01*
G01X582286Y521307D02*
Y522307D01*
G01X583346Y489826D02*
Y550234D01*
G01X582286Y524547D02*
Y525547D01*
G01X583346Y489826D02*
Y550234D01*
G01Y489826D02*
Y550234D01*
G01Y489826D02*
Y550234D01*
G01Y489826D02*
Y550234D01*
G01Y489826D02*
Y550234D01*
G01Y489826D02*
Y550234D01*
G01X578246Y494324D02*
Y550020D01*
G01X577186Y494764D02*
Y538398D01*
G01X578246Y494324D02*
Y550020D01*
G01Y494324D02*
Y550020D01*
G01Y494324D02*
Y550020D01*
G01X561727Y474638D02*
X566658D01*
G01X562167Y473578D02*
X567098D01*
G01X566658Y474638D02*
X570680Y478660D01*
G01X567098Y473578D02*
X571740Y478220D01*
G01X570680Y478660D02*
Y480976D01*
G01X571740Y478220D02*
Y480536D01*
G01X570680Y480976D02*
X572564Y482860D01*
G01X571740Y480536D02*
X573004Y481800D01*
G01X572564Y482860D02*
X574890D01*
G01X573004Y481800D02*
X575330D01*
G01X574890Y482860D02*
X575874Y483844D01*
G01X575330Y481800D02*
X576934Y483404D01*
G01X575874Y483844D02*
Y484716D01*
G01X576934Y483404D02*
Y485156D01*
G01X575874Y484716D02*
X575168Y485422D01*
G01X576934Y485156D02*
X576228Y485862D01*
G01X575168Y485422D02*
Y487162D01*
G01X576228Y485862D02*
Y486722D01*
G01X575168Y487162D02*
X576776Y488770D01*
G01X576228Y486722D02*
X577216Y487710D01*
G01X576776Y488770D02*
X578516D01*
G01D02*
X579222Y488064D01*
G01X577216Y487710D02*
X578076D01*
G01X578516Y488770D02*
X579222Y488064D01*
G01X578076Y487710D02*
X578782Y487004D01*
G01X579222Y488064D02*
X580084D01*
G01X578782Y487004D02*
X580524D01*
G01X580084Y488064D02*
X582286Y490266D01*
G01X580524Y487004D02*
X583346Y489826D01*
G01X582286Y490266D02*
Y493415D01*
G01Y495655D02*
Y496655D01*
G01Y498895D02*
Y499895D01*
G01Y502135D02*
Y503135D01*
G01Y505375D02*
Y506375D01*
G01Y508615D02*
Y510432D01*
G01Y512538D02*
Y519067D01*
G01Y521307D02*
Y522307D01*
G01Y524547D02*
Y525547D01*
G01X583346Y489826D02*
Y550234D01*
G01X540375Y506529D02*
Y548674D01*
G01X541435Y506089D02*
Y549532D01*
G01Y506089D02*
Y549532D01*
G01X540375Y506529D02*
Y548674D01*
G01X545192Y501600D02*
X546535Y502943D01*
G01X541692Y499600D02*
X545475Y503383D01*
G01X546535Y502943D02*
Y519925D01*
G01X545475Y503383D02*
Y519485D01*
G01X546535Y519925D02*
X545171Y521289D01*
G01X545475Y519485D02*
X544111Y520849D01*
G01X545171Y521289D02*
Y524621D01*
G01X544111Y520849D02*
Y525061D01*
G01X545171Y524621D02*
X546535Y525985D01*
G01X544111Y525061D02*
X545475Y526425D01*
G01X546535Y525985D02*
Y539230D01*
G01X545475Y526425D02*
Y538790D01*
G01X541692Y499600D02*
X545475Y503383D01*
G01X545192Y501600D02*
X546535Y502943D01*
G01X545475Y503383D02*
Y519485D01*
G01X546535Y502943D02*
Y519925D01*
G01X545475Y519485D02*
X544111Y520849D01*
G01X546535Y519925D02*
X545171Y521289D01*
G01X544111Y520849D02*
Y525061D01*
G01X545171Y521289D02*
Y524621D01*
G01X544111Y525061D02*
X545475Y526425D01*
G01X545171Y524621D02*
X546535Y525985D01*
G01X545475Y526425D02*
Y538790D01*
G01X546535Y525985D02*
Y539230D01*
G01X577186Y494764D02*
Y538398D01*
G01X578246Y494324D02*
Y550020D01*
G01X562167Y473578D02*
X567098D01*
G01X561727Y474638D02*
X566658D01*
G01X567098Y473578D02*
X571740Y478220D01*
G01X566658Y474638D02*
X570680Y478660D01*
G01X571740Y478220D02*
Y480536D01*
G01X570680Y478660D02*
Y480976D01*
G01X571740Y480536D02*
X573004Y481800D01*
G01X570680Y480976D02*
X572564Y482860D01*
G01X573004Y481800D02*
X575330D01*
G01X572564Y482860D02*
X574890D01*
G01X575330Y481800D02*
X576934Y483404D01*
G01X574890Y482860D02*
X575874Y483844D01*
G01X576934Y483404D02*
Y485156D01*
G01X575874Y483844D02*
Y484716D01*
G01X576934Y485156D02*
X576228Y485862D01*
G01X575874Y484716D02*
X575168Y485422D01*
G01X576228Y485862D02*
Y486722D01*
G01X575168Y485422D02*
Y487162D01*
G01X576228Y486722D02*
X577216Y487710D01*
G01X575168Y487162D02*
X576776Y488770D01*
G01X577216Y487710D02*
X578076D01*
G01X576776Y488770D02*
X578516D01*
G01X577216Y487710D02*
X578076D01*
G01D02*
X578782Y487004D01*
G01X578516Y488770D02*
X579222Y488064D01*
G01X578782Y487004D02*
X580524D01*
G01X579222Y488064D02*
X580084D01*
G01X580524Y487004D02*
X583346Y489826D01*
G01X580084Y488064D02*
X582286Y490266D01*
G01X583346Y489826D02*
Y550234D01*
G01X582286Y490266D02*
Y493415D01*
G01X583346Y489826D02*
Y550234D01*
G01X582286Y495655D02*
Y496655D01*
G01X583346Y489826D02*
Y550234D01*
G01X582286Y498895D02*
Y499895D01*
G01X583346Y489826D02*
Y550234D01*
G01X582286Y502135D02*
Y503135D01*
G01X583346Y489826D02*
Y550234D01*
G01X582286Y505375D02*
Y506375D01*
G01X583346Y489826D02*
Y550234D01*
G01X582286Y508615D02*
Y510432D01*
G01X583346Y489826D02*
Y550234D01*
G01X582286Y512538D02*
Y519067D01*
G01X583346Y489826D02*
Y550234D01*
G01X582286Y521307D02*
Y522307D01*
G01X583346Y489826D02*
Y550234D01*
G01X582286Y524547D02*
Y525547D01*
G01X583346Y489826D02*
Y550234D01*
G01Y489826D02*
Y550234D01*
G01Y489826D02*
Y550234D01*
G01Y489826D02*
Y550234D01*
G01Y489826D02*
Y550234D01*
G01Y489826D02*
Y550234D01*
G01X578246Y494324D02*
Y550020D01*
G01X577186Y494764D02*
Y538398D01*
G01X578246Y494324D02*
Y550020D01*
G01Y494324D02*
Y550020D01*
G01Y494324D02*
Y550020D01*
G01X561727Y474638D02*
X566658D01*
G01X562167Y473578D02*
X567098D01*
G01X566658Y474638D02*
X570680Y478660D01*
G01X567098Y473578D02*
X571740Y478220D01*
G01X570680Y478660D02*
Y480976D01*
G01X571740Y478220D02*
Y480536D01*
G01X570680Y480976D02*
X572564Y482860D01*
G01X571740Y480536D02*
X573004Y481800D01*
G01X572564Y482860D02*
X574890D01*
G01X573004Y481800D02*
X575330D01*
G01X574890Y482860D02*
X575874Y483844D01*
G01X575330Y481800D02*
X576934Y483404D01*
G01X575874Y483844D02*
Y484716D01*
G01X576934Y483404D02*
Y485156D01*
G01X575874Y484716D02*
X575168Y485422D01*
G01X576934Y485156D02*
X576228Y485862D01*
G01X575168Y485422D02*
Y487162D01*
G01X576228Y485862D02*
Y486722D01*
G01X575168Y487162D02*
X576776Y488770D01*
G01X576228Y486722D02*
X577216Y487710D01*
G01X576776Y488770D02*
X578516D01*
G01D02*
X579222Y488064D01*
G01X577216Y487710D02*
X578076D01*
G01X578516Y488770D02*
X579222Y488064D01*
G01X578076Y487710D02*
X578782Y487004D01*
G01X579222Y488064D02*
X580084D01*
G01X578782Y487004D02*
X580524D01*
G01X580084Y488064D02*
X582286Y490266D01*
G01X580524Y487004D02*
X583346Y489826D01*
G01X582286Y490266D02*
Y493415D01*
G01Y495655D02*
Y496655D01*
G01Y498895D02*
Y499895D01*
G01Y502135D02*
Y503135D01*
G01Y505375D02*
Y506375D01*
G01Y508615D02*
Y510432D01*
G01Y512538D02*
Y519067D01*
G01Y521307D02*
Y522307D01*
G01Y524547D02*
Y525547D01*
G01X583346Y489826D02*
Y550234D01*
G01X573178Y552200D02*
Y570211D01*
G01X574238Y558090D02*
Y559460D01*
G01X573178Y552200D02*
Y570211D01*
G01X574238Y563140D02*
Y564560D01*
G01X577186Y540320D02*
Y541479D01*
G01Y543719D02*
Y544719D01*
G01Y546959D02*
Y549580D01*
G01D02*
X576266Y550500D01*
G01X578246Y550020D02*
X575166Y553100D01*
G01X579462Y557700D02*
X578791Y558371D01*
G01X578560Y557101D02*
X577731Y557930D01*
G01X578791Y558371D02*
Y559648D01*
G01Y563138D02*
Y564029D01*
G01X577731Y557930D02*
Y564470D01*
G01X578791Y564029D02*
X579562Y564800D01*
G01X577731Y564470D02*
X578560Y565299D01*
G01X582286Y527787D02*
Y529287D01*
G01Y531235D02*
Y534458D01*
G01Y536326D02*
Y537841D01*
G01Y540081D02*
Y541081D01*
G01Y543321D02*
Y544321D01*
G01Y546561D02*
Y549794D01*
G01X583346Y550234D02*
X580266Y553314D01*
G01X582286Y549794D02*
X581366Y550714D01*
G01X574238Y558090D02*
Y559460D01*
G01Y563140D02*
Y564560D01*
G01X573178Y552200D02*
Y570211D01*
G01X577186Y540320D02*
Y541479D01*
G01Y543719D02*
Y544719D01*
G01Y546959D02*
Y549580D01*
G01X578246Y550020D02*
X575166Y553100D01*
G01X577186Y549580D02*
X576266Y550500D01*
G01X578560Y557101D02*
X577731Y557930D01*
G01X579462Y557700D02*
X578791Y558371D01*
G01X577731Y557930D02*
Y564470D01*
G01X578791Y558371D02*
Y559648D01*
G01X577731Y557930D02*
Y564470D01*
G01X578791Y563138D02*
Y564029D01*
G01X577731Y564470D02*
X578560Y565299D01*
G01X578791Y564029D02*
X579562Y564800D01*
G01X582286Y527787D02*
Y529287D01*
G01Y531235D02*
Y534458D01*
G01Y536326D02*
Y537841D01*
G01Y540081D02*
Y541081D01*
G01Y543321D02*
Y544321D01*
G01Y546561D02*
Y549794D01*
G01D02*
X581366Y550714D01*
G01X583346Y550234D02*
X580266Y553314D01*
G01X546535Y539230D02*
X544968Y540797D01*
G01X545475Y538790D02*
X543908Y540357D01*
G01X544968Y540797D02*
Y543400D01*
G01X543908Y540357D02*
Y543840D01*
G01X544968Y543400D02*
X546535Y544967D01*
G01X543908Y543840D02*
X545475Y545407D01*
G01X546535Y544967D02*
Y550234D01*
G01X545475Y545407D02*
Y548694D01*
G01Y538790D02*
X543908Y540357D01*
G01X546535Y539230D02*
X544968Y540797D01*
G01X543908Y540357D02*
Y543840D01*
G01X544968Y540797D02*
Y543400D01*
G01X543908Y543840D02*
X545475Y545407D01*
G01X544968Y543400D02*
X546535Y544967D01*
G01X545475Y545407D02*
Y548694D01*
G01X546535Y544967D02*
Y550234D01*
G01X573178Y552200D02*
Y570211D01*
G01X574238Y558090D02*
Y559460D01*
G01X573178Y552200D02*
Y570211D01*
G01X574238Y563140D02*
Y564560D01*
G01X577186Y540320D02*
Y541479D01*
G01Y543719D02*
Y544719D01*
G01Y546959D02*
Y549580D01*
G01D02*
X576266Y550500D01*
G01X578246Y550020D02*
X575166Y553100D01*
G01X579462Y557700D02*
X578791Y558371D01*
G01X578560Y557101D02*
X577731Y557930D01*
G01X578791Y558371D02*
Y559648D01*
G01Y563138D02*
Y564029D01*
G01X577731Y557930D02*
Y564470D01*
G01X578791Y564029D02*
X579562Y564800D01*
G01X577731Y564470D02*
X578560Y565299D01*
G01X582286Y527787D02*
Y529287D01*
G01Y531235D02*
Y534458D01*
G01Y536326D02*
Y537841D01*
G01Y540081D02*
Y541081D01*
G01Y543321D02*
Y544321D01*
G01Y546561D02*
Y549794D01*
G01X583346Y550234D02*
X580266Y553314D01*
G01X582286Y549794D02*
X581366Y550714D01*
G01X574238Y558090D02*
Y559460D01*
G01Y563140D02*
Y564560D01*
G01X573178Y552200D02*
Y570211D01*
G01X577186Y540320D02*
Y541479D01*
G01Y543719D02*
Y544719D01*
G01Y546959D02*
Y549580D01*
G01X578246Y550020D02*
X575166Y553100D01*
G01X577186Y549580D02*
X576266Y550500D01*
G01X578560Y557101D02*
X577731Y557930D01*
G01X579462Y557700D02*
X578791Y558371D01*
G01X577731Y557930D02*
Y564470D01*
G01X578791Y558371D02*
Y559648D01*
G01X577731Y557930D02*
Y564470D01*
G01X578791Y563138D02*
Y564029D01*
G01X577731Y564470D02*
X578560Y565299D01*
G01X578791Y564029D02*
X579562Y564800D01*
G01X582286Y527787D02*
Y529287D01*
G01Y531235D02*
Y534458D01*
G01Y536326D02*
Y537841D01*
G01Y540081D02*
Y541081D01*
G01Y543321D02*
Y544321D01*
G01Y546561D02*
Y549794D01*
G01D02*
X581366Y550714D01*
G01X583346Y550234D02*
X580266Y553314D01*
G01X777172Y-47440D02*
G02Y-50100I0J-1330D01*
G01Y-46380D02*
G02Y-51160I0J-2390D01*
G01Y-46380D02*
G02Y-51160I0J-2390D01*
G01Y-47440D02*
G02Y-50100I0J-1330D01*
G01X784534Y51354D02*
Y59928D01*
G01X785594Y57420D02*
Y59488D01*
G01X784534Y59928D02*
X788408Y63802D01*
G01X785594Y59488D02*
X789468Y63362D01*
G01X789494Y48994D02*
X786388Y52100D01*
G01X784534Y51354D02*
Y59928D01*
G01X785594Y57420D02*
Y59488D01*
G01X784534Y59928D02*
X788408Y63802D01*
G01X785594Y59488D02*
X789468Y63362D01*
G01X789494Y48994D02*
X786388Y52100D01*
G01X789494Y48994D02*
X786388Y52100D01*
G01X785594Y57420D02*
Y59488D01*
G01X784534Y51354D02*
Y59928D01*
G01X785594Y59488D02*
X789468Y63362D01*
G01X784534Y59928D02*
X788408Y63802D01*
G01X789494Y48994D02*
X786388Y52100D01*
G01X785594Y57420D02*
Y59488D01*
G01X784534Y51354D02*
Y59928D01*
G01X785594Y59488D02*
X789468Y63362D01*
G01X784534Y59928D02*
X788408Y63802D01*
G01Y109020D02*
X786220Y111208D01*
G01D02*
Y113924D01*
G01D02*
X789620Y117324D01*
G01X787309Y120492D02*
X785820Y121981D01*
G01X787309Y120492D02*
X785820Y121981D01*
G01D02*
Y125363D01*
G01D02*
X787309Y126852D01*
G01X785820Y125363D02*
X787309Y126852D01*
G01X789320Y130223D02*
X785820Y133723D01*
G01D02*
Y145769D01*
G01D02*
X794561Y154510D01*
G01X788408Y109020D02*
X786220Y111208D01*
G01D02*
Y113924D01*
G01D02*
X789620Y117324D01*
G01X787309Y120492D02*
X785820Y121981D01*
G01X787309Y120492D02*
X785820Y121981D01*
G01D02*
Y125363D01*
G01D02*
X787309Y126852D01*
G01X785820Y125363D02*
X787309Y126852D01*
G01X789320Y130223D02*
X785820Y133723D01*
G01D02*
Y145769D01*
G01D02*
X794561Y154510D01*
G01X788408Y109020D02*
X786220Y111208D01*
G01D02*
Y113924D01*
G01D02*
X789620Y117324D01*
G01X787309Y120492D02*
X785820Y121981D01*
G01D02*
Y125363D01*
G01D02*
X787309Y126852D01*
G01X789320Y130223D02*
X785820Y133723D01*
G01D02*
Y145769D01*
G01D02*
X794561Y154510D01*
G01X788408Y109020D02*
X786220Y111208D01*
G01D02*
Y113924D01*
G01D02*
X789620Y117324D01*
G01X787309Y120492D02*
X785820Y121981D01*
G01D02*
Y125363D01*
G01D02*
X787309Y126852D01*
G01X789320Y130223D02*
X785820Y133723D01*
G01D02*
Y145769D01*
G01D02*
X794561Y154510D01*
G01X785220Y463312D02*
X798689Y449843D01*
G01X799749Y450283D02*
X786280Y463752D01*
G01X785220Y465688D02*
Y463312D01*
G01X786280Y463752D02*
Y465248D01*
G01Y463752D02*
Y465248D01*
G01X785220Y465688D02*
Y463312D01*
G01X799749Y450283D02*
X786280Y463752D01*
G01X785220Y463312D02*
X798689Y449843D01*
G01X785220Y463312D02*
X798689Y449843D01*
G01X799749Y450283D02*
X786280Y463752D01*
G01X785220Y465688D02*
Y463312D01*
G01X786280Y463752D02*
Y465248D01*
G01Y463752D02*
Y465248D01*
G01X785220Y465688D02*
Y463312D01*
G01X799749Y450283D02*
X786280Y463752D01*
G01X785220Y463312D02*
X798689Y449843D01*
G01X786496Y466964D02*
X785220Y465688D01*
G01X786280Y465248D02*
X786936Y465904D01*
G01X789050Y466964D02*
X786496D01*
G01X785220Y471896D02*
X786712Y470404D01*
G01X787152Y471464D02*
X786280Y472336D01*
G01X785220Y506285D02*
Y471896D01*
G01X786280Y472336D02*
Y505845D01*
G01X788408Y509473D02*
X785220Y506285D01*
G01X786280Y505845D02*
X789468Y509033D01*
G01X786280Y505845D02*
X789468Y509033D01*
G01X788408Y509473D02*
X785220Y506285D01*
G01X786280Y472336D02*
Y505845D01*
G01X785220Y506285D02*
Y471896D01*
G01X787152Y471464D02*
X786280Y472336D01*
G01X785220Y471896D02*
X786712Y470404D01*
G01X789050Y466964D02*
X786496D01*
G01X786280Y465248D02*
X786936Y465904D01*
G01X786496Y466964D02*
X785220Y465688D01*
G01X786496Y466964D02*
X785220Y465688D01*
G01X786280Y465248D02*
X786936Y465904D01*
G01X789050Y466964D02*
X786496D01*
G01X785220Y471896D02*
X786712Y470404D01*
G01X787152Y471464D02*
X786280Y472336D01*
G01X785220Y506285D02*
Y471896D01*
G01X786280Y472336D02*
Y505845D01*
G01X788408Y509473D02*
X785220Y506285D01*
G01X786280Y505845D02*
X789468Y509033D01*
G01X786280Y505845D02*
X789468Y509033D01*
G01X788408Y509473D02*
X785220Y506285D01*
G01X786280Y472336D02*
Y505845D01*
G01X785220Y506285D02*
Y471896D01*
G01X787152Y471464D02*
X786280Y472336D01*
G01X785220Y471896D02*
X786712Y470404D01*
G01X789050Y466964D02*
X786496D01*
G01X786280Y465248D02*
X786936Y465904D01*
G01X786496Y466964D02*
X785220Y465688D01*
G01X784400Y570211D02*
Y552200D01*
G01X785460Y558090D02*
Y559460D01*
G01X784400Y570211D02*
Y552200D01*
G01X785460Y563140D02*
Y564560D01*
G01Y558090D02*
Y559460D01*
G01Y563140D02*
Y564560D01*
G01X784400Y570211D02*
Y552200D01*
G01Y570211D02*
Y552200D01*
G01X785460Y558090D02*
Y559460D01*
G01X784400Y570211D02*
Y552200D01*
G01X785460Y563140D02*
Y564560D01*
G01Y558090D02*
Y559460D01*
G01Y563140D02*
Y564560D01*
G01X784400Y570211D02*
Y552200D01*
G01X787207Y32580D02*
X787723D01*
G01X787184Y31520D02*
X788166D01*
G01X787723Y32580D02*
X788434Y33291D01*
G01X788166Y31520D02*
X789494Y32848D01*
G01X787207Y32580D02*
X787723D01*
G01X787184Y31520D02*
X788166D01*
G01X787723Y32580D02*
X788434Y33291D01*
G01X788166Y31520D02*
X789494Y32848D01*
G01X787184Y31520D02*
X788166D01*
G01X787207Y32580D02*
X787723D01*
G01X788166Y31520D02*
X789494Y32848D01*
G01X787723Y32580D02*
X788434Y33291D01*
G01X787184Y31520D02*
X788166D01*
G01X787207Y32580D02*
X787723D01*
G01X788166Y31520D02*
X789494Y32848D01*
G01X787723Y32580D02*
X788434Y33291D01*
G01X794680Y33732D02*
X791488Y30540D01*
G01X824534Y32580D02*
X825245Y33291D01*
G01X826305Y32848D02*
X824977Y31520D01*
G01X824018Y32580D02*
X824534D01*
G01X824977Y31520D02*
X823995D01*
G01X828299Y30540D02*
X831491Y33732D01*
G01X824977Y31520D02*
X823995D01*
G01X824018Y32580D02*
X824534D01*
G01X826305Y32848D02*
X824977Y31520D01*
G01X824534Y32580D02*
X825245Y33291D01*
G01X794680Y33732D02*
X791488Y30540D01*
G01X824534Y32580D02*
X825245Y33291D01*
G01X826305Y32848D02*
X824977Y31520D01*
G01X824018Y32580D02*
X824534D01*
G01X824977Y31520D02*
X823995D01*
G01X828299Y30540D02*
X831491Y33732D01*
G01X794680D02*
X791488Y30540D01*
G01X794680Y33732D02*
X791488Y30540D01*
G01X794680Y33732D02*
X791488Y30540D01*
G01X794680Y33732D02*
X791488Y30540D01*
G01X824977Y31520D02*
X823995D01*
G01X824018Y32580D02*
X824534D01*
G01X826305Y32848D02*
X824977Y31520D01*
G01X824534Y32580D02*
X825245Y33291D01*
G01X828299Y30540D02*
X831491Y33732D01*
G01X828299Y30540D02*
X831491Y33732D01*
G01X828299Y30540D02*
X831491Y33732D01*
G01X828299Y30540D02*
X831491Y33732D01*
G01X788408Y63802D02*
Y109020D01*
G01X789468Y63362D02*
Y77580D01*
G01X788408Y63802D02*
Y109020D01*
G01X789468Y79820D02*
Y80580D01*
G01X788408Y63802D02*
Y109020D01*
G01X789468Y82820D02*
Y93480D01*
G01X788408Y63802D02*
Y109020D01*
G01X788434Y33291D02*
Y36580D01*
G01Y40920D02*
Y41880D01*
G01Y46020D02*
Y48553D01*
G01X789494Y32848D02*
Y48994D01*
G01X788434Y48553D02*
X787487Y49500D01*
G01X788408Y63802D02*
Y109020D01*
G01X789468Y63362D02*
Y77580D01*
G01X788408Y63802D02*
Y109020D01*
G01X789468Y79820D02*
Y80580D01*
G01X788408Y63802D02*
Y109020D01*
G01X789468Y82820D02*
Y93480D01*
G01X788408Y63802D02*
Y109020D01*
G01X788434Y33291D02*
Y36580D01*
G01Y40920D02*
Y41880D01*
G01Y46020D02*
Y48553D01*
G01X789494Y32848D02*
Y48994D01*
G01X788434Y48553D02*
X787487Y49500D01*
G01X789494Y32848D02*
Y48994D01*
G01X788434Y33291D02*
Y36580D01*
G01X789494Y32848D02*
Y48994D01*
G01X788434Y40920D02*
Y41880D01*
G01X789494Y32848D02*
Y48994D01*
G01X788434Y46020D02*
Y48553D01*
G01D02*
X787487Y49500D01*
G01X789468Y63362D02*
Y77580D01*
G01Y79820D02*
Y80580D01*
G01Y82820D02*
Y93480D01*
G01X788408Y63802D02*
Y109020D01*
G01X789494Y32848D02*
Y48994D01*
G01X788434Y33291D02*
Y36580D01*
G01X789494Y32848D02*
Y48994D01*
G01X788434Y40920D02*
Y41880D01*
G01X789494Y32848D02*
Y48994D01*
G01X788434Y46020D02*
Y48553D01*
G01D02*
X787487Y49500D01*
G01X789468Y63362D02*
Y77580D01*
G01Y79820D02*
Y80580D01*
G01Y82820D02*
Y93480D01*
G01X788408Y63802D02*
Y109020D01*
G01X793508Y97690D02*
Y63341D01*
G01X794568Y97250D02*
Y62901D01*
G01X793508Y63341D02*
X789783Y59616D01*
G01X794568Y62901D02*
X790843Y59176D01*
G01X789783Y59616D02*
Y51419D01*
G01X790843Y59176D02*
Y57457D01*
G01X791488Y49715D02*
X792586D01*
G01D02*
X793620Y48681D01*
G01X791488Y52314D02*
X794680Y49122D01*
G01X793620Y48681D02*
Y45906D01*
G01Y42080D02*
Y40707D01*
G01Y36793D02*
Y34172D01*
G01X794680Y49122D02*
Y33732D01*
G01X793620Y34172D02*
X792597Y33149D01*
G01D02*
X791488D01*
G01X825219Y62805D02*
Y103488D01*
G01Y62805D02*
Y103488D01*
G01Y62805D02*
Y103488D01*
G01Y62805D02*
Y103488D01*
G01X826279Y93480D02*
Y80620D01*
G01X825219Y62805D02*
Y103488D01*
G01X826279Y78380D02*
Y76274D01*
G01X825219Y62805D02*
Y103488D01*
G01X826279Y74025D02*
Y62362D01*
G01X821345Y58931D02*
X825219Y62805D01*
G01X826279Y62362D02*
X824950Y61033D01*
G01X821345Y58931D02*
X825219Y62805D01*
G01X823359Y59442D02*
X822405Y58488D01*
G01X821345Y51354D02*
Y58931D01*
G01X822405Y58488D02*
Y57420D01*
G01X825245Y48553D02*
X824298Y49500D01*
G01X823199Y52100D02*
X826305Y48994D01*
G01X825245Y33291D02*
Y36580D01*
G01Y40920D02*
Y41880D01*
G01Y46020D02*
Y48553D01*
G01X826305Y48994D02*
Y32848D01*
G01X827045Y59031D02*
Y58199D01*
G01X828105Y57720D02*
Y58588D01*
G01X830319Y62305D02*
X827045Y59031D01*
G01X828105Y58588D02*
X829079Y59562D01*
G01X830319Y93987D02*
Y62305D01*
G01X831379Y63934D02*
Y74580D01*
G01X830319Y93987D02*
Y62305D01*
G01X831379Y76820D02*
Y77580D01*
G01X830319Y93987D02*
Y62305D01*
G01X831379Y79820D02*
Y93547D01*
G01X831420Y95088D02*
X830319Y93987D01*
G01X831379Y93547D02*
X832480Y94648D01*
G01X830431Y34172D02*
X829408Y33149D01*
G01D02*
X828299D01*
G01X830431Y48681D02*
Y45906D01*
G01Y42080D02*
Y40707D01*
G01Y36793D02*
Y34172D01*
G01X831491Y33732D02*
Y49122D01*
G01X828299Y49715D02*
X829397D01*
G01D02*
X830431Y48681D01*
G01X831491Y49122D02*
X828299Y52314D01*
G01X822405Y58488D02*
Y57420D01*
G01X821345Y51354D02*
Y58931D01*
G01X826279Y62362D02*
X824950Y61033D01*
G01X823359Y59442D02*
X822405Y58488D01*
G01X821345Y58931D02*
X825219Y62805D01*
G01X826279Y93480D02*
Y80620D01*
G01Y78380D02*
Y76274D01*
G01Y74025D02*
Y62362D01*
G01X825219Y62805D02*
Y103488D01*
G01X826305Y48994D02*
Y32848D01*
G01X825245Y33291D02*
Y36580D01*
G01X826305Y48994D02*
Y32848D01*
G01X825245Y40920D02*
Y41880D01*
G01X826305Y48994D02*
Y32848D01*
G01X825245Y46020D02*
Y48553D01*
G01X823199Y52100D02*
X826305Y48994D01*
G01X825245Y48553D02*
X824298Y49500D01*
G01X793508Y97690D02*
Y63341D01*
G01X794568Y97250D02*
Y62901D01*
G01X793508Y63341D02*
X789783Y59616D01*
G01X794568Y62901D02*
X790843Y59176D01*
G01X789783Y59616D02*
Y51419D01*
G01X790843Y59176D02*
Y57457D01*
G01X791488Y49715D02*
X792586D01*
G01D02*
X793620Y48681D01*
G01X791488Y52314D02*
X794680Y49122D01*
G01X793620Y48681D02*
Y45906D01*
G01Y42080D02*
Y40707D01*
G01Y36793D02*
Y34172D01*
G01X794680Y49122D02*
Y33732D01*
G01X793620Y34172D02*
X792597Y33149D01*
G01D02*
X791488D01*
G01X825219Y62805D02*
Y103488D01*
G01Y62805D02*
Y103488D01*
G01Y62805D02*
Y103488D01*
G01Y62805D02*
Y103488D01*
G01X826279Y93480D02*
Y80620D01*
G01X825219Y62805D02*
Y103488D01*
G01X826279Y78380D02*
Y76274D01*
G01X825219Y62805D02*
Y103488D01*
G01X826279Y74025D02*
Y62362D01*
G01X821345Y58931D02*
X825219Y62805D01*
G01X826279Y62362D02*
X824950Y61033D01*
G01X821345Y58931D02*
X825219Y62805D01*
G01X823359Y59442D02*
X822405Y58488D01*
G01X821345Y51354D02*
Y58931D01*
G01X822405Y58488D02*
Y57420D01*
G01X825245Y48553D02*
X824298Y49500D01*
G01X823199Y52100D02*
X826305Y48994D01*
G01X825245Y33291D02*
Y36580D01*
G01Y40920D02*
Y41880D01*
G01Y46020D02*
Y48553D01*
G01X826305Y48994D02*
Y32848D01*
G01X827045Y59031D02*
Y58199D01*
G01X828105Y57720D02*
Y58588D01*
G01X830319Y62305D02*
X827045Y59031D01*
G01X828105Y58588D02*
X829079Y59562D01*
G01X830319Y93987D02*
Y62305D01*
G01X831379Y63934D02*
Y74580D01*
G01X830319Y93987D02*
Y62305D01*
G01X831379Y76820D02*
Y77580D01*
G01X830319Y93987D02*
Y62305D01*
G01X831379Y79820D02*
Y93547D01*
G01X831420Y95088D02*
X830319Y93987D01*
G01X831379Y93547D02*
X832480Y94648D01*
G01X830431Y34172D02*
X829408Y33149D01*
G01D02*
X828299D01*
G01X830431Y48681D02*
Y45906D01*
G01Y42080D02*
Y40707D01*
G01Y36793D02*
Y34172D01*
G01X831491Y33732D02*
Y49122D01*
G01X828299Y49715D02*
X829397D01*
G01D02*
X830431Y48681D01*
G01X831491Y49122D02*
X828299Y52314D01*
G01X791488D02*
X794680Y49122D01*
G01X791488Y49715D02*
X792586D01*
G01X791488Y52314D02*
X794680Y49122D01*
G01X792586Y49715D02*
X793620Y48681D01*
G01X794680Y49122D02*
Y33732D01*
G01X793620Y48681D02*
Y45906D01*
G01X794680Y49122D02*
Y33732D01*
G01X793620Y42080D02*
Y40707D01*
G01X794680Y49122D02*
Y33732D01*
G01X793620Y36793D02*
Y34172D01*
G01D02*
X792597Y33149D01*
G01D02*
X791488D01*
G01X794568Y97250D02*
Y62901D01*
G01X793508Y97690D02*
Y63341D01*
G01X794568Y62901D02*
X790843Y59176D01*
G01X793508Y63341D02*
X789783Y59616D01*
G01X790843Y59176D02*
Y57457D01*
G01X789783Y59616D02*
Y51419D01*
G01X791488Y52314D02*
X794680Y49122D01*
G01X791488Y49715D02*
X792586D01*
G01X791488Y52314D02*
X794680Y49122D01*
G01X792586Y49715D02*
X793620Y48681D01*
G01X794680Y49122D02*
Y33732D01*
G01X793620Y48681D02*
Y45906D01*
G01X794680Y49122D02*
Y33732D01*
G01X793620Y42080D02*
Y40707D01*
G01X794680Y49122D02*
Y33732D01*
G01X793620Y36793D02*
Y34172D01*
G01D02*
X792597Y33149D01*
G01D02*
X791488D01*
G01X794568Y97250D02*
Y62901D01*
G01X793508Y97690D02*
Y63341D01*
G01X794568Y62901D02*
X790843Y59176D01*
G01X793508Y63341D02*
X789783Y59616D01*
G01X790843Y59176D02*
Y57457D01*
G01X789783Y59616D02*
Y51419D01*
G01X822405Y58488D02*
Y57420D01*
G01X821345Y51354D02*
Y58931D01*
G01X826279Y62362D02*
X824950Y61033D01*
G01X823359Y59442D02*
X822405Y58488D01*
G01X821345Y58931D02*
X825219Y62805D01*
G01X826279Y93480D02*
Y80620D01*
G01Y78380D02*
Y76274D01*
G01Y74025D02*
Y62362D01*
G01X825219Y62805D02*
Y103488D01*
G01X826305Y48994D02*
Y32848D01*
G01X825245Y33291D02*
Y36580D01*
G01X826305Y48994D02*
Y32848D01*
G01X825245Y40920D02*
Y41880D01*
G01X826305Y48994D02*
Y32848D01*
G01X825245Y46020D02*
Y48553D01*
G01X823199Y52100D02*
X826305Y48994D01*
G01X825245Y48553D02*
X824298Y49500D01*
G01X831379Y93547D02*
X832480Y94648D01*
G01X831420Y95088D02*
X830319Y93987D01*
G01X831379Y63934D02*
Y74580D01*
G01Y76820D02*
Y77580D01*
G01Y79820D02*
Y93547D01*
G01X830319Y93987D02*
Y62305D01*
G01X828105Y58588D02*
X829079Y59562D01*
G01X830319Y62305D02*
X827045Y59031D01*
G01X828105Y57720D02*
Y58588D01*
G01X827045Y59031D02*
Y58199D01*
G01X831491Y49122D02*
X828299Y52314D01*
G01Y49715D02*
X829397D01*
G01X831491Y49122D02*
X828299Y52314D01*
G01X829397Y49715D02*
X830431Y48681D01*
G01X831491Y33732D02*
Y49122D01*
G01X830431Y48681D02*
Y45906D01*
G01X831491Y33732D02*
Y49122D01*
G01X830431Y42080D02*
Y40707D01*
G01X831491Y33732D02*
Y49122D01*
G01X830431Y36793D02*
Y34172D01*
G01D02*
X829408Y33149D01*
G01D02*
X828299D01*
G01X831379Y93547D02*
X832480Y94648D01*
G01X831420Y95088D02*
X830319Y93987D01*
G01X831379Y63934D02*
Y74580D01*
G01Y76820D02*
Y77580D01*
G01Y79820D02*
Y93547D01*
G01X830319Y93987D02*
Y62305D01*
G01X828105Y58588D02*
X829079Y59562D01*
G01X830319Y62305D02*
X827045Y59031D01*
G01X828105Y57720D02*
Y58588D01*
G01X827045Y59031D02*
Y58199D01*
G01X831491Y49122D02*
X828299Y52314D01*
G01Y49715D02*
X829397D01*
G01X831491Y49122D02*
X828299Y52314D01*
G01X829397Y49715D02*
X830431Y48681D01*
G01X831491Y33732D02*
Y49122D01*
G01X830431Y48681D02*
Y45906D01*
G01X831491Y33732D02*
Y49122D01*
G01X830431Y42080D02*
Y40707D01*
G01X831491Y33732D02*
Y49122D01*
G01X830431Y36793D02*
Y34172D01*
G01D02*
X829408Y33149D01*
G01D02*
X828299D01*
G01X789468Y95720D02*
Y109463D01*
G01D02*
X787280Y111651D01*
G01D02*
Y113481D01*
G01D02*
X790680Y116881D01*
G01X789620Y117324D02*
Y119320D01*
G01X790680Y116881D02*
Y119763D01*
G01X789620Y119320D02*
X788448Y120492D01*
G01D02*
X787309D01*
G01X790680Y119763D02*
X788891Y121552D01*
G01X788448Y120492D02*
X787309D01*
G01X788891Y121552D02*
X787752D01*
G01D02*
X786880Y122424D01*
G01D02*
Y124920D01*
G01D02*
X787752Y125792D01*
G01X787309Y126852D02*
X788448D01*
G01X787752Y125792D02*
X788891D01*
G01X787309Y126852D02*
X788448D01*
G01D02*
X789320Y127724D01*
G01X788891Y125792D02*
X790380Y127281D01*
G01X789320Y127724D02*
Y130223D01*
G01X790380Y127281D02*
Y130663D01*
G01D02*
X786880Y134163D01*
G01D02*
Y145329D01*
G01D02*
X795001Y153450D01*
G01X794561Y154510D02*
X802261D01*
G01X795001Y153450D02*
X802701D01*
G01X802261Y154510D02*
X804866Y157115D01*
G01X802701Y153450D02*
X805926Y156675D01*
G01X789468Y95720D02*
Y109463D01*
G01D02*
X787280Y111651D01*
G01D02*
Y113481D01*
G01D02*
X790680Y116881D01*
G01X789620Y117324D02*
Y119320D01*
G01X790680Y116881D02*
Y119763D01*
G01X789620Y119320D02*
X788448Y120492D01*
G01D02*
X787309D01*
G01X790680Y119763D02*
X788891Y121552D01*
G01X788448Y120492D02*
X787309D01*
G01X788891Y121552D02*
X787752D01*
G01D02*
X786880Y122424D01*
G01D02*
Y124920D01*
G01D02*
X787752Y125792D01*
G01X787309Y126852D02*
X788448D01*
G01X787752Y125792D02*
X788891D01*
G01X787309Y126852D02*
X788448D01*
G01D02*
X789320Y127724D01*
G01X788891Y125792D02*
X790380Y127281D01*
G01X789320Y127724D02*
Y130223D01*
G01X790380Y127281D02*
Y130663D01*
G01D02*
X786880Y134163D01*
G01D02*
Y145329D01*
G01D02*
X795001Y153450D01*
G01X794561Y154510D02*
X802261D01*
G01X795001Y153450D02*
X802701D01*
G01X802261Y154510D02*
X804866Y157115D01*
G01X802701Y153450D02*
X805926Y156675D01*
G01X789468Y95720D02*
Y109463D01*
G01D02*
X787280Y111651D01*
G01D02*
Y113481D01*
G01D02*
X790680Y116881D01*
G01D02*
Y119763D01*
G01X789620Y117324D02*
Y119320D01*
G01X790680Y119763D02*
X788891Y121552D01*
G01X789620Y119320D02*
X788448Y120492D01*
G01X790680Y119763D02*
X788891Y121552D01*
G01D02*
X787752D01*
G01X788448Y120492D02*
X787309D01*
G01X788891Y121552D02*
X787752D01*
G01D02*
X786880Y122424D01*
G01D02*
Y124920D01*
G01D02*
X787752Y125792D01*
G01D02*
X788891D01*
G01X787752D02*
X788891D01*
G01D02*
X790380Y127281D01*
G01X787309Y126852D02*
X788448D01*
G01X788891Y125792D02*
X790380Y127281D01*
G01X788448Y126852D02*
X789320Y127724D01*
G01X790380Y127281D02*
Y130663D01*
G01X789320Y127724D02*
Y130223D01*
G01X790380Y130663D02*
X786880Y134163D01*
G01D02*
Y145329D01*
G01D02*
X795001Y153450D01*
G01D02*
X802701D01*
G01X794561Y154510D02*
X802261D01*
G01X802701Y153450D02*
X805926Y156675D01*
G01X802261Y154510D02*
X804866Y157115D01*
G01X789468Y95720D02*
Y109463D01*
G01D02*
X787280Y111651D01*
G01D02*
Y113481D01*
G01D02*
X790680Y116881D01*
G01D02*
Y119763D01*
G01X789620Y117324D02*
Y119320D01*
G01X790680Y119763D02*
X788891Y121552D01*
G01X789620Y119320D02*
X788448Y120492D01*
G01X790680Y119763D02*
X788891Y121552D01*
G01D02*
X787752D01*
G01X788448Y120492D02*
X787309D01*
G01X788891Y121552D02*
X787752D01*
G01D02*
X786880Y122424D01*
G01D02*
Y124920D01*
G01D02*
X787752Y125792D01*
G01D02*
X788891D01*
G01X787752D02*
X788891D01*
G01D02*
X790380Y127281D01*
G01X787309Y126852D02*
X788448D01*
G01X788891Y125792D02*
X790380Y127281D01*
G01X788448Y126852D02*
X789320Y127724D01*
G01X790380Y127281D02*
Y130663D01*
G01X789320Y127724D02*
Y130223D01*
G01X790380Y130663D02*
X786880Y134163D01*
G01D02*
Y145329D01*
G01D02*
X795001Y153450D01*
G01D02*
X802701D01*
G01X794561Y154510D02*
X802261D01*
G01X802701Y153450D02*
X805926Y156675D01*
G01X802261Y154510D02*
X804866Y157115D01*
G01X809190Y163540D02*
Y156140D01*
G01X810250Y163100D02*
Y155700D01*
G01X809190Y156140D02*
X803225Y150175D01*
G01X810250Y155700D02*
X803665Y149115D01*
G01X803225Y150175D02*
X794926D01*
G01X803665Y149115D02*
X795366D01*
G01X794926Y150175D02*
X791253Y146502D01*
G01X795366Y149115D02*
X792313Y146062D01*
G01X791253Y146502D02*
Y144916D01*
G01X792313Y146062D02*
Y145356D01*
G01X791253Y144916D02*
X793508Y142661D01*
G01X792313Y145356D02*
X794568Y143101D01*
G01X793508Y142661D02*
Y141711D01*
G01X794568Y143101D02*
Y141268D01*
G01X793508Y141711D02*
X792636Y140839D01*
G01D02*
X791109D01*
G01X794568Y141268D02*
X793079Y139779D01*
G01X792636Y140839D02*
X791109D01*
G01D02*
X789620Y139350D01*
G01X793079Y139779D02*
X791552D01*
G01X791109Y140839D02*
X789620Y139350D01*
G01X791552Y139779D02*
X790680Y138907D01*
G01X789620Y139350D02*
Y135968D01*
G01X790680Y138907D02*
Y136411D01*
G01X789620Y135968D02*
X791109Y134479D01*
G01X790680Y136411D02*
X791552Y135539D01*
G01X789620Y135968D02*
X791109Y134479D01*
G01D02*
X792636D01*
G01X791552Y135539D02*
X793076D01*
G01X792636Y134479D02*
X793508Y133607D01*
G01X793076Y135539D02*
X794568Y134047D01*
G01X793508Y133607D02*
Y115510D01*
G01X794568Y134047D02*
Y115950D01*
G01X793508Y115510D02*
X794890Y114128D01*
G01X794568Y115950D02*
X795950Y114568D01*
G01X794890Y114128D02*
Y110422D01*
G01X795950Y114568D02*
Y109982D01*
G01X794890Y110422D02*
X793508Y109040D01*
G01X795950Y109982D02*
X794568Y108600D01*
G01X793508Y109040D02*
Y103642D01*
G01X794568Y108600D02*
Y104082D01*
G01X793508Y103642D02*
X795190Y101960D01*
G01X794568Y104082D02*
X796250Y102400D01*
G01X795190Y101960D02*
Y99372D01*
G01X796250Y102400D02*
Y98932D01*
G01X795190Y99372D02*
X793508Y97690D01*
G01X796250Y98932D02*
X794568Y97250D01*
G01X842281Y153910D02*
X905790Y217419D01*
G01X842281Y153910D02*
X905790Y217419D01*
G01X842281Y153910D02*
X905790Y217419D01*
G01X842281Y153910D02*
X905790Y217419D01*
G01X842281Y153910D02*
X905790Y217419D01*
G01X842281Y153910D02*
X905790Y217419D01*
G01X842281Y153910D02*
X905790Y217419D01*
G01X842281Y153910D02*
X905790Y217419D01*
G01X842281Y153910D02*
X905790Y217419D01*
G01X842281Y153910D02*
X905790Y217419D01*
G01X842281Y153910D02*
X905790Y217419D01*
G01X842281Y153910D02*
X905790Y217419D01*
G01X842281Y153910D02*
X905790Y217419D01*
G01X842281Y153910D02*
X905790Y217419D01*
G01X873501Y183630D02*
X843341Y153470D01*
G01X842281Y152168D02*
Y153910D01*
G01X843341Y153470D02*
Y152608D01*
G01X845697Y148752D02*
X842281Y152168D01*
G01X843341Y152608D02*
X846757Y149192D01*
G01X845697Y148047D02*
Y148752D01*
G01X846757Y149192D02*
Y147607D01*
G01X844554Y146904D02*
X845697Y148047D01*
G01X846757Y147607D02*
X844994Y145844D01*
G01X843849Y146904D02*
X844554D01*
G01X844994Y145844D02*
X843409D01*
G01X841453Y149300D02*
X843849Y146904D01*
G01D02*
X844554D01*
G01X843409Y145844D02*
X841013Y148240D01*
G01X837671Y149300D02*
X841453D01*
G01X841013Y148240D02*
X838111D01*
G01X834740Y146369D02*
X837671Y149300D01*
G01X838111Y148240D02*
X835800Y145929D01*
G01X834740Y132990D02*
Y146369D01*
G01X835800Y145929D02*
Y132550D01*
G01X827620Y125870D02*
X834740Y132990D01*
G01X835800Y132550D02*
X828680Y125430D01*
G01X827620Y105889D02*
Y125870D01*
G01X828680Y125430D02*
Y105449D01*
G01X825219Y103488D02*
X827620Y105889D01*
G01X828680Y105449D02*
X826279Y103048D01*
G01D02*
Y101720D01*
G01Y99480D02*
Y98720D01*
G01Y96480D02*
Y95720D01*
G01X831420Y124221D02*
Y95088D01*
G01X832480Y94648D02*
Y123781D01*
G01X841288Y134089D02*
X831420Y124221D01*
G01X832480Y123781D02*
X842348Y133649D01*
G01X841288Y134951D02*
Y134089D01*
G01X842348Y133649D02*
Y135391D01*
G01X838464Y137775D02*
X841288Y134951D01*
G01X842348Y135391D02*
X839524Y138215D01*
G01X838464Y139514D02*
Y137775D01*
G01X839524Y138215D02*
Y139074D01*
G01X840074Y141124D02*
X838464Y139514D01*
G01X839524Y139074D02*
X840514Y140064D01*
G01X841811Y141124D02*
X840074D01*
G01D02*
X838464Y139514D01*
G01X840514Y140064D02*
X841371D01*
G01X844636Y138299D02*
X841811Y141124D01*
G01X841371Y140064D02*
X844196Y137239D01*
G01X845498Y138299D02*
X844636D01*
G01X844196Y137239D02*
X845938D01*
G01X851220Y144021D02*
X845498Y138299D01*
G01D02*
X844636D01*
G01X845938Y137239D02*
X852280Y143581D01*
G01X826279Y103048D02*
Y101720D01*
G01Y99480D02*
Y98720D01*
G01Y96480D02*
Y95720D01*
G01X828680Y105449D02*
X826279Y103048D01*
G01X825219Y103488D02*
X827620Y105889D01*
G01X828680Y125430D02*
Y105449D01*
G01X827620Y105889D02*
Y125870D01*
G01X835800Y132550D02*
X828680Y125430D01*
G01X827620Y125870D02*
X834740Y132990D01*
G01X835800Y145929D02*
Y132550D01*
G01X834740Y132990D02*
Y146369D01*
G01X838111Y148240D02*
X835800Y145929D01*
G01X834740Y146369D02*
X837671Y149300D01*
G01X841013Y148240D02*
X838111D01*
G01X837671Y149300D02*
X841453D01*
G01X843409Y145844D02*
X841013Y148240D01*
G01X841453Y149300D02*
X843849Y146904D01*
G01X844994Y145844D02*
X843409D01*
G01D02*
X841013Y148240D01*
G01X843849Y146904D02*
X844554D01*
G01X846757Y147607D02*
X844994Y145844D01*
G01X844554Y146904D02*
X845697Y148047D01*
G01X846757Y149192D02*
Y147607D01*
G01X845697Y148047D02*
Y148752D01*
G01X843341Y152608D02*
X846757Y149192D01*
G01X845697Y148752D02*
X842281Y152168D01*
G01X843341Y153470D02*
Y152608D01*
G01X842281Y152168D02*
Y153910D01*
G01X873501Y183630D02*
X843341Y153470D01*
G01X842281Y153910D02*
X905790Y217419D01*
G01X809190Y163540D02*
Y156140D01*
G01X810250Y163100D02*
Y155700D01*
G01X809190Y156140D02*
X803225Y150175D01*
G01X810250Y155700D02*
X803665Y149115D01*
G01X803225Y150175D02*
X794926D01*
G01X803665Y149115D02*
X795366D01*
G01X794926Y150175D02*
X791253Y146502D01*
G01X795366Y149115D02*
X792313Y146062D01*
G01X791253Y146502D02*
Y144916D01*
G01X792313Y146062D02*
Y145356D01*
G01X791253Y144916D02*
X793508Y142661D01*
G01X792313Y145356D02*
X794568Y143101D01*
G01X793508Y142661D02*
Y141711D01*
G01X794568Y143101D02*
Y141268D01*
G01X793508Y141711D02*
X792636Y140839D01*
G01D02*
X791109D01*
G01X794568Y141268D02*
X793079Y139779D01*
G01X792636Y140839D02*
X791109D01*
G01D02*
X789620Y139350D01*
G01X793079Y139779D02*
X791552D01*
G01X791109Y140839D02*
X789620Y139350D01*
G01X791552Y139779D02*
X790680Y138907D01*
G01X789620Y139350D02*
Y135968D01*
G01X790680Y138907D02*
Y136411D01*
G01X789620Y135968D02*
X791109Y134479D01*
G01X790680Y136411D02*
X791552Y135539D01*
G01X789620Y135968D02*
X791109Y134479D01*
G01D02*
X792636D01*
G01X791552Y135539D02*
X793076D01*
G01X792636Y134479D02*
X793508Y133607D01*
G01X793076Y135539D02*
X794568Y134047D01*
G01X793508Y133607D02*
Y115510D01*
G01X794568Y134047D02*
Y115950D01*
G01X793508Y115510D02*
X794890Y114128D01*
G01X794568Y115950D02*
X795950Y114568D01*
G01X794890Y114128D02*
Y110422D01*
G01X795950Y114568D02*
Y109982D01*
G01X794890Y110422D02*
X793508Y109040D01*
G01X795950Y109982D02*
X794568Y108600D01*
G01X793508Y109040D02*
Y103642D01*
G01X794568Y108600D02*
Y104082D01*
G01X793508Y103642D02*
X795190Y101960D01*
G01X794568Y104082D02*
X796250Y102400D01*
G01X795190Y101960D02*
Y99372D01*
G01X796250Y102400D02*
Y98932D01*
G01X795190Y99372D02*
X793508Y97690D01*
G01X796250Y98932D02*
X794568Y97250D01*
G01X842281Y153910D02*
X905790Y217419D01*
G01X842281Y153910D02*
X905790Y217419D01*
G01X842281Y153910D02*
X905790Y217419D01*
G01X842281Y153910D02*
X905790Y217419D01*
G01X842281Y153910D02*
X905790Y217419D01*
G01X842281Y153910D02*
X905790Y217419D01*
G01X842281Y153910D02*
X905790Y217419D01*
G01X842281Y153910D02*
X905790Y217419D01*
G01X842281Y153910D02*
X905790Y217419D01*
G01X842281Y153910D02*
X905790Y217419D01*
G01X842281Y153910D02*
X905790Y217419D01*
G01X842281Y153910D02*
X905790Y217419D01*
G01X842281Y153910D02*
X905790Y217419D01*
G01X842281Y153910D02*
X905790Y217419D01*
G01X873501Y183630D02*
X843341Y153470D01*
G01X842281Y152168D02*
Y153910D01*
G01X843341Y153470D02*
Y152608D01*
G01X845697Y148752D02*
X842281Y152168D01*
G01X843341Y152608D02*
X846757Y149192D01*
G01X845697Y148047D02*
Y148752D01*
G01X846757Y149192D02*
Y147607D01*
G01X844554Y146904D02*
X845697Y148047D01*
G01X846757Y147607D02*
X844994Y145844D01*
G01X843849Y146904D02*
X844554D01*
G01X844994Y145844D02*
X843409D01*
G01X841453Y149300D02*
X843849Y146904D01*
G01D02*
X844554D01*
G01X843409Y145844D02*
X841013Y148240D01*
G01X837671Y149300D02*
X841453D01*
G01X841013Y148240D02*
X838111D01*
G01X834740Y146369D02*
X837671Y149300D01*
G01X838111Y148240D02*
X835800Y145929D01*
G01X834740Y132990D02*
Y146369D01*
G01X835800Y145929D02*
Y132550D01*
G01X827620Y125870D02*
X834740Y132990D01*
G01X835800Y132550D02*
X828680Y125430D01*
G01X827620Y105889D02*
Y125870D01*
G01X828680Y125430D02*
Y105449D01*
G01X825219Y103488D02*
X827620Y105889D01*
G01X828680Y105449D02*
X826279Y103048D01*
G01D02*
Y101720D01*
G01Y99480D02*
Y98720D01*
G01Y96480D02*
Y95720D01*
G01X831420Y124221D02*
Y95088D01*
G01X832480Y94648D02*
Y123781D01*
G01X841288Y134089D02*
X831420Y124221D01*
G01X832480Y123781D02*
X842348Y133649D01*
G01X841288Y134951D02*
Y134089D01*
G01X842348Y133649D02*
Y135391D01*
G01X838464Y137775D02*
X841288Y134951D01*
G01X842348Y135391D02*
X839524Y138215D01*
G01X838464Y139514D02*
Y137775D01*
G01X839524Y138215D02*
Y139074D01*
G01X840074Y141124D02*
X838464Y139514D01*
G01X839524Y139074D02*
X840514Y140064D01*
G01X841811Y141124D02*
X840074D01*
G01D02*
X838464Y139514D01*
G01X840514Y140064D02*
X841371D01*
G01X844636Y138299D02*
X841811Y141124D01*
G01X841371Y140064D02*
X844196Y137239D01*
G01X845498Y138299D02*
X844636D01*
G01X844196Y137239D02*
X845938D01*
G01X851220Y144021D02*
X845498Y138299D01*
G01D02*
X844636D01*
G01X845938Y137239D02*
X852280Y143581D01*
G01X810250Y163100D02*
Y155700D01*
G01X809190Y163540D02*
Y156140D01*
G01X810250Y155700D02*
X803665Y149115D01*
G01X809190Y156140D02*
X803225Y150175D01*
G01X803665Y149115D02*
X795366D01*
G01X803225Y150175D02*
X794926D01*
G01X795366Y149115D02*
X792313Y146062D01*
G01X794926Y150175D02*
X791253Y146502D01*
G01X792313Y146062D02*
Y145356D01*
G01X791253Y146502D02*
Y144916D01*
G01X792313Y145356D02*
X794568Y143101D01*
G01X791253Y144916D02*
X793508Y142661D01*
G01X794568Y143101D02*
Y141268D01*
G01X793508Y142661D02*
Y141711D01*
G01X794568Y141268D02*
X793079Y139779D01*
G01X793508Y141711D02*
X792636Y140839D01*
G01X794568Y141268D02*
X793079Y139779D01*
G01D02*
X791552D01*
G01X792636Y140839D02*
X791109D01*
G01X793079Y139779D02*
X791552D01*
G01D02*
X790680Y138907D01*
G01X791109Y140839D02*
X789620Y139350D01*
G01X790680Y138907D02*
Y136411D01*
G01X789620Y139350D02*
Y135968D01*
G01X790680Y136411D02*
X791552Y135539D01*
G01D02*
X793076D01*
G01X789620Y135968D02*
X791109Y134479D01*
G01X791552Y135539D02*
X793076D01*
G01X791109Y134479D02*
X792636D01*
G01X793076Y135539D02*
X794568Y134047D01*
G01X792636Y134479D02*
X793508Y133607D01*
G01X794568Y134047D02*
Y115950D01*
G01X793508Y133607D02*
Y115510D01*
G01X794568Y115950D02*
X795950Y114568D01*
G01X793508Y115510D02*
X794890Y114128D01*
G01X795950Y114568D02*
Y109982D01*
G01X794890Y114128D02*
Y110422D01*
G01X795950Y109982D02*
X794568Y108600D01*
G01X794890Y110422D02*
X793508Y109040D01*
G01X794568Y108600D02*
Y104082D01*
G01X793508Y109040D02*
Y103642D01*
G01X794568Y104082D02*
X796250Y102400D01*
G01X793508Y103642D02*
X795190Y101960D01*
G01X796250Y102400D02*
Y98932D01*
G01X795190Y101960D02*
Y99372D01*
G01X796250Y98932D02*
X794568Y97250D01*
G01X795190Y99372D02*
X793508Y97690D01*
G01X810250Y163100D02*
Y155700D01*
G01X809190Y163540D02*
Y156140D01*
G01X810250Y155700D02*
X803665Y149115D01*
G01X809190Y156140D02*
X803225Y150175D01*
G01X803665Y149115D02*
X795366D01*
G01X803225Y150175D02*
X794926D01*
G01X795366Y149115D02*
X792313Y146062D01*
G01X794926Y150175D02*
X791253Y146502D01*
G01X792313Y146062D02*
Y145356D01*
G01X791253Y146502D02*
Y144916D01*
G01X792313Y145356D02*
X794568Y143101D01*
G01X791253Y144916D02*
X793508Y142661D01*
G01X794568Y143101D02*
Y141268D01*
G01X793508Y142661D02*
Y141711D01*
G01X794568Y141268D02*
X793079Y139779D01*
G01X793508Y141711D02*
X792636Y140839D01*
G01X794568Y141268D02*
X793079Y139779D01*
G01D02*
X791552D01*
G01X792636Y140839D02*
X791109D01*
G01X793079Y139779D02*
X791552D01*
G01D02*
X790680Y138907D01*
G01X791109Y140839D02*
X789620Y139350D01*
G01X790680Y138907D02*
Y136411D01*
G01X789620Y139350D02*
Y135968D01*
G01X790680Y136411D02*
X791552Y135539D01*
G01D02*
X793076D01*
G01X789620Y135968D02*
X791109Y134479D01*
G01X791552Y135539D02*
X793076D01*
G01X791109Y134479D02*
X792636D01*
G01X793076Y135539D02*
X794568Y134047D01*
G01X792636Y134479D02*
X793508Y133607D01*
G01X794568Y134047D02*
Y115950D01*
G01X793508Y133607D02*
Y115510D01*
G01X794568Y115950D02*
X795950Y114568D01*
G01X793508Y115510D02*
X794890Y114128D01*
G01X795950Y114568D02*
Y109982D01*
G01X794890Y114128D02*
Y110422D01*
G01X795950Y109982D02*
X794568Y108600D01*
G01X794890Y110422D02*
X793508Y109040D01*
G01X794568Y108600D02*
Y104082D01*
G01X793508Y109040D02*
Y103642D01*
G01X794568Y104082D02*
X796250Y102400D01*
G01X793508Y103642D02*
X795190Y101960D01*
G01X796250Y102400D02*
Y98932D01*
G01X795190Y101960D02*
Y99372D01*
G01X796250Y98932D02*
X794568Y97250D01*
G01X795190Y99372D02*
X793508Y97690D01*
G01X826279Y103048D02*
Y101720D01*
G01Y99480D02*
Y98720D01*
G01Y96480D02*
Y95720D01*
G01X828680Y105449D02*
X826279Y103048D01*
G01X825219Y103488D02*
X827620Y105889D01*
G01X828680Y125430D02*
Y105449D01*
G01X827620Y105889D02*
Y125870D01*
G01X835800Y132550D02*
X828680Y125430D01*
G01X827620Y125870D02*
X834740Y132990D01*
G01X835800Y145929D02*
Y132550D01*
G01X834740Y132990D02*
Y146369D01*
G01X838111Y148240D02*
X835800Y145929D01*
G01X834740Y146369D02*
X837671Y149300D01*
G01X841013Y148240D02*
X838111D01*
G01X837671Y149300D02*
X841453D01*
G01X843409Y145844D02*
X841013Y148240D01*
G01X841453Y149300D02*
X843849Y146904D01*
G01X844994Y145844D02*
X843409D01*
G01D02*
X841013Y148240D01*
G01X843849Y146904D02*
X844554D01*
G01X846757Y147607D02*
X844994Y145844D01*
G01X844554Y146904D02*
X845697Y148047D01*
G01X846757Y149192D02*
Y147607D01*
G01X845697Y148047D02*
Y148752D01*
G01X843341Y152608D02*
X846757Y149192D01*
G01X845697Y148752D02*
X842281Y152168D01*
G01X843341Y153470D02*
Y152608D01*
G01X842281Y152168D02*
Y153910D01*
G01X873501Y183630D02*
X843341Y153470D01*
G01X842281Y153910D02*
X905790Y217419D01*
G01X845938Y137239D02*
X852280Y143581D01*
G01X851220Y144021D02*
X845498Y138299D01*
G01X844196Y137239D02*
X845938D01*
G01D02*
X852280Y143581D01*
G01X845498Y138299D02*
X844636D01*
G01X841371Y140064D02*
X844196Y137239D01*
G01X844636Y138299D02*
X841811Y141124D01*
G01X840514Y140064D02*
X841371D01*
G01X841811Y141124D02*
X840074D01*
G01X839524Y139074D02*
X840514Y140064D01*
G01D02*
X841371D01*
G01X840074Y141124D02*
X838464Y139514D01*
G01X839524Y138215D02*
Y139074D01*
G01X838464Y139514D02*
Y137775D01*
G01X842348Y135391D02*
X839524Y138215D01*
G01X838464Y137775D02*
X841288Y134951D01*
G01X842348Y133649D02*
Y135391D01*
G01X841288Y134951D02*
Y134089D01*
G01X832480Y123781D02*
X842348Y133649D01*
G01X841288Y134089D02*
X831420Y124221D01*
G01X832480Y94648D02*
Y123781D01*
G01X831420Y124221D02*
Y95088D01*
G01X845938Y137239D02*
X852280Y143581D01*
G01X851220Y144021D02*
X845498Y138299D01*
G01X844196Y137239D02*
X845938D01*
G01D02*
X852280Y143581D01*
G01X845498Y138299D02*
X844636D01*
G01X841371Y140064D02*
X844196Y137239D01*
G01X844636Y138299D02*
X841811Y141124D01*
G01X840514Y140064D02*
X841371D01*
G01X841811Y141124D02*
X840074D01*
G01X839524Y139074D02*
X840514Y140064D01*
G01D02*
X841371D01*
G01X840074Y141124D02*
X838464Y139514D01*
G01X839524Y138215D02*
Y139074D01*
G01X838464Y139514D02*
Y137775D01*
G01X842348Y135391D02*
X839524Y138215D01*
G01X838464Y137775D02*
X841288Y134951D01*
G01X842348Y133649D02*
Y135391D01*
G01X841288Y134951D02*
Y134089D01*
G01X832480Y123781D02*
X842348Y133649D01*
G01X841288Y134089D02*
X831420Y124221D01*
G01X832480Y94648D02*
Y123781D01*
G01X831420Y124221D02*
Y95088D01*
G01X804866Y157115D02*
Y164815D01*
G01X805926Y156675D02*
Y164375D01*
G01X804866Y164815D02*
X863361Y223310D01*
G01X805926Y164375D02*
X863801Y222250D01*
G01X804866Y164815D02*
X863361Y223310D01*
G01X804866Y157115D02*
Y164815D01*
G01X805926Y156675D02*
Y164375D01*
G01X804866Y164815D02*
X863361Y223310D01*
G01X805926Y164375D02*
X863801Y222250D01*
G01X804866Y164815D02*
X863361Y223310D01*
G01X805926Y156675D02*
Y164375D01*
G01X804866Y157115D02*
Y164815D01*
G01X805926Y164375D02*
X863801Y222250D01*
G01X804866Y164815D02*
X863361Y223310D01*
G01X805926Y156675D02*
Y164375D01*
G01X804866Y157115D02*
Y164815D01*
G01X805926Y164375D02*
X863801Y222250D01*
G01X804866Y164815D02*
X863361Y223310D01*
G01X865110Y219460D02*
X809190Y163540D01*
G01X865550Y218400D02*
X810250Y163100D01*
G01X865110Y219460D02*
X809190Y163540D01*
G01X865550Y218400D02*
X810250Y163100D01*
G01X865550Y218400D02*
X810250Y163100D01*
G01X865110Y219460D02*
X809190Y163540D01*
G01X865550Y218400D02*
X810250Y163100D01*
G01X865110Y219460D02*
X809190Y163540D01*
G01X821059Y428740D02*
X867521Y382278D01*
G01X821059Y428740D02*
X867521Y382278D01*
G01X821059Y428740D02*
X867521Y382278D01*
G01X821059Y428740D02*
X867521Y382278D01*
G01X868581Y382718D02*
X821499Y429800D01*
G01X816531Y428740D02*
X821059D01*
G01X821499Y429800D02*
X816971D01*
G01X798689Y446582D02*
X816531Y428740D01*
G01X816971Y429800D02*
X799749Y447022D01*
G01X798689Y449843D02*
Y446582D01*
G01X799749Y447022D02*
Y450283D01*
G01Y447022D02*
Y450283D01*
G01X798689Y449843D02*
Y446582D01*
G01X816971Y429800D02*
X799749Y447022D01*
G01X798689Y446582D02*
X816531Y428740D01*
G01X821499Y429800D02*
X816971D01*
G01X816531Y428740D02*
X821059D01*
G01X868581Y382718D02*
X821499Y429800D01*
G01X868581Y382718D02*
X821499Y429800D01*
G01X816531Y428740D02*
X821059D01*
G01X821499Y429800D02*
X816971D01*
G01X798689Y446582D02*
X816531Y428740D01*
G01X816971Y429800D02*
X799749Y447022D01*
G01X798689Y449843D02*
Y446582D01*
G01X799749Y447022D02*
Y450283D01*
G01Y447022D02*
Y450283D01*
G01X798689Y449843D02*
Y446582D01*
G01X816971Y429800D02*
X799749Y447022D01*
G01X798689Y446582D02*
X816531Y428740D01*
G01X821499Y429800D02*
X816971D01*
G01X816531Y428740D02*
X821059D01*
G01X868581Y382718D02*
X821499Y429800D01*
G01X793616Y461856D02*
Y465308D01*
G01X792556Y465748D02*
Y461416D01*
G01X803599Y451873D02*
X793616Y461856D01*
G01X792556Y461416D02*
X802539Y451433D01*
G01X803599Y448569D02*
Y451873D01*
G01X802539Y451433D02*
Y448129D01*
G01X819268Y432900D02*
X803599Y448569D01*
G01X802539Y448129D02*
X818828Y431840D01*
G01X822600Y432900D02*
X819268D01*
G01X818828Y431840D02*
X822160D01*
G01X871526Y383974D02*
X822600Y432900D01*
G01X822160Y431840D02*
X870466Y383534D01*
G01X835636Y455432D02*
X871200Y419868D01*
G01X872260Y420308D02*
X836696Y455872D01*
G01X835636Y457765D02*
Y455432D01*
G01X836696Y455872D02*
Y457325D01*
G01X837240Y459369D02*
X835636Y457765D01*
G01X836696Y457325D02*
X837680Y458309D01*
G01X839451Y459369D02*
X837240D01*
G01X837680Y458309D02*
X839891D01*
G01X841040Y460958D02*
X839451Y459369D01*
G01X839891Y458309D02*
X842100Y460518D01*
G01X841040Y462460D02*
Y460958D01*
G01X842100Y460518D02*
Y462900D01*
G01X839891Y463609D02*
X841040Y462460D01*
G01X842100Y462900D02*
X840331Y464669D01*
G01X837612Y463609D02*
X839891D01*
G01X840331Y464669D02*
X838052D01*
G01X833820Y467401D02*
X837612Y463609D01*
G01X838052Y464669D02*
X834880Y467841D01*
G01X838680Y471452D02*
X847480Y462652D01*
G01X837620Y471009D02*
X846420Y462209D01*
G01X847480Y462652D02*
Y460309D01*
G01X846420Y462209D02*
Y460752D01*
G01X847480Y460309D02*
X843480Y456309D01*
G01X846420Y460752D02*
X842420Y456752D01*
G01X843480Y456309D02*
Y454691D01*
G01X842420Y456752D02*
Y454248D01*
G01X843480Y454691D02*
X844791Y453380D01*
G01X842420Y454248D02*
X844348Y452320D01*
G01X844791Y453380D02*
X846575D01*
G01X844348Y452320D02*
X847018D01*
G01X846575Y453380D02*
X849357Y456162D01*
G01X847018Y452320D02*
X849800Y455102D01*
G01X822160Y431840D02*
X870466Y383534D01*
G01X871526Y383974D02*
X822600Y432900D01*
G01X818828Y431840D02*
X822160D01*
G01X822600Y432900D02*
X819268D01*
G01X802539Y448129D02*
X818828Y431840D01*
G01X819268Y432900D02*
X803599Y448569D01*
G01X802539Y451433D02*
Y448129D01*
G01X803599Y448569D02*
Y451873D01*
G01X792556Y461416D02*
X802539Y451433D01*
G01X803599Y451873D02*
X793616Y461856D01*
G01X792556Y465748D02*
Y461416D01*
G01X793616Y461856D02*
Y465308D01*
G01X838052Y464669D02*
X834880Y467841D01*
G01X833820Y467401D02*
X837612Y463609D01*
G01X840331Y464669D02*
X838052D01*
G01X837612Y463609D02*
X839891D01*
G01X842100Y462900D02*
X840331Y464669D01*
G01X839891Y463609D02*
X841040Y462460D01*
G01X842100Y460518D02*
Y462900D01*
G01X841040Y462460D02*
Y460958D01*
G01X839891Y458309D02*
X842100Y460518D01*
G01X841040Y460958D02*
X839451Y459369D01*
G01X837680Y458309D02*
X839891D01*
G01X839451Y459369D02*
X837240D01*
G01X836696Y457325D02*
X837680Y458309D01*
G01X837240Y459369D02*
X835636Y457765D01*
G01X836696Y455872D02*
Y457325D01*
G01X835636Y457765D02*
Y455432D01*
G01X872260Y420308D02*
X836696Y455872D01*
G01X835636Y455432D02*
X871200Y419868D01*
G01X837620Y471009D02*
X846420Y462209D01*
G01X838680Y471452D02*
X847480Y462652D01*
G01X846420Y462209D02*
Y460752D01*
G01X847480Y462652D02*
Y460309D01*
G01X846420Y460752D02*
X842420Y456752D01*
G01X847480Y460309D02*
X843480Y456309D01*
G01X842420Y456752D02*
Y454248D01*
G01X843480Y456309D02*
Y454691D01*
G01X842420Y454248D02*
X844348Y452320D01*
G01X843480Y454691D02*
X844791Y453380D01*
G01X844348Y452320D02*
X847018D01*
G01X844791Y453380D02*
X846575D01*
G01X847018Y452320D02*
X849800Y455102D01*
G01X846575Y453380D02*
X849357Y456162D01*
G01X793616Y461856D02*
Y465308D01*
G01X792556Y465748D02*
Y461416D01*
G01X803599Y451873D02*
X793616Y461856D01*
G01X792556Y461416D02*
X802539Y451433D01*
G01X803599Y448569D02*
Y451873D01*
G01X802539Y451433D02*
Y448129D01*
G01X819268Y432900D02*
X803599Y448569D01*
G01X802539Y448129D02*
X818828Y431840D01*
G01X822600Y432900D02*
X819268D01*
G01X818828Y431840D02*
X822160D01*
G01X871526Y383974D02*
X822600Y432900D01*
G01X822160Y431840D02*
X870466Y383534D01*
G01X835636Y455432D02*
X871200Y419868D01*
G01X872260Y420308D02*
X836696Y455872D01*
G01X835636Y457765D02*
Y455432D01*
G01X836696Y455872D02*
Y457325D01*
G01X837240Y459369D02*
X835636Y457765D01*
G01X836696Y457325D02*
X837680Y458309D01*
G01X839451Y459369D02*
X837240D01*
G01X837680Y458309D02*
X839891D01*
G01X841040Y460958D02*
X839451Y459369D01*
G01X839891Y458309D02*
X842100Y460518D01*
G01X841040Y462460D02*
Y460958D01*
G01X842100Y460518D02*
Y462900D01*
G01X839891Y463609D02*
X841040Y462460D01*
G01X842100Y462900D02*
X840331Y464669D01*
G01X837612Y463609D02*
X839891D01*
G01X840331Y464669D02*
X838052D01*
G01X833820Y467401D02*
X837612Y463609D01*
G01X838052Y464669D02*
X834880Y467841D01*
G01X838680Y471452D02*
X847480Y462652D01*
G01X837620Y471009D02*
X846420Y462209D01*
G01X847480Y462652D02*
Y460309D01*
G01X846420Y462209D02*
Y460752D01*
G01X847480Y460309D02*
X843480Y456309D01*
G01X846420Y460752D02*
X842420Y456752D01*
G01X843480Y456309D02*
Y454691D01*
G01X842420Y456752D02*
Y454248D01*
G01X843480Y454691D02*
X844791Y453380D01*
G01X842420Y454248D02*
X844348Y452320D01*
G01X844791Y453380D02*
X846575D01*
G01X844348Y452320D02*
X847018D01*
G01X846575Y453380D02*
X849357Y456162D01*
G01X847018Y452320D02*
X849800Y455102D01*
G01X822160Y431840D02*
X870466Y383534D01*
G01X871526Y383974D02*
X822600Y432900D01*
G01X818828Y431840D02*
X822160D01*
G01X822600Y432900D02*
X819268D01*
G01X802539Y448129D02*
X818828Y431840D01*
G01X819268Y432900D02*
X803599Y448569D01*
G01X802539Y451433D02*
Y448129D01*
G01X803599Y448569D02*
Y451873D01*
G01X792556Y461416D02*
X802539Y451433D01*
G01X803599Y451873D02*
X793616Y461856D01*
G01X792556Y465748D02*
Y461416D01*
G01X793616Y461856D02*
Y465308D01*
G01X838052Y464669D02*
X834880Y467841D01*
G01X833820Y467401D02*
X837612Y463609D01*
G01X840331Y464669D02*
X838052D01*
G01X837612Y463609D02*
X839891D01*
G01X842100Y462900D02*
X840331Y464669D01*
G01X839891Y463609D02*
X841040Y462460D01*
G01X842100Y460518D02*
Y462900D01*
G01X841040Y462460D02*
Y460958D01*
G01X839891Y458309D02*
X842100Y460518D01*
G01X841040Y460958D02*
X839451Y459369D01*
G01X837680Y458309D02*
X839891D01*
G01X839451Y459369D02*
X837240D01*
G01X836696Y457325D02*
X837680Y458309D01*
G01X837240Y459369D02*
X835636Y457765D01*
G01X836696Y455872D02*
Y457325D01*
G01X835636Y457765D02*
Y455432D01*
G01X872260Y420308D02*
X836696Y455872D01*
G01X835636Y455432D02*
X871200Y419868D01*
G01X837620Y471009D02*
X846420Y462209D01*
G01X838680Y471452D02*
X847480Y462652D01*
G01X846420Y462209D02*
Y460752D01*
G01X847480Y462652D02*
Y460309D01*
G01X846420Y460752D02*
X842420Y456752D01*
G01X847480Y460309D02*
X843480Y456309D01*
G01X842420Y456752D02*
Y454248D01*
G01X843480Y456309D02*
Y454691D01*
G01X842420Y454248D02*
X844348Y452320D01*
G01X843480Y454691D02*
X844791Y453380D01*
G01X844348Y452320D02*
X847018D01*
G01X844791Y453380D02*
X846575D01*
G01X847018Y452320D02*
X849800Y455102D01*
G01X846575Y453380D02*
X849357Y456162D01*
G01X786936Y465904D02*
X789493D01*
G01X789922Y467836D02*
X789050Y466964D01*
G01X789493Y465904D02*
X790982Y467393D01*
G01X789922Y469535D02*
Y467836D01*
G01X790982Y467393D02*
Y469975D01*
G01X789053Y470404D02*
X789922Y469535D01*
G01X790982Y469975D02*
X789493Y471464D01*
G01X786712Y470404D02*
X789053D01*
G01X789493Y471464D02*
X787152D01*
G01X788408Y549461D02*
Y509473D01*
G01X789468Y509033D02*
Y541466D01*
G01X788408Y549461D02*
Y509473D01*
G01Y549461D02*
Y509473D01*
G01X789468Y509033D02*
Y541466D01*
G01X788408Y549461D02*
Y509473D01*
G01X789493Y471464D02*
X787152D01*
G01X786712Y470404D02*
X789053D01*
G01X790982Y469975D02*
X789493Y471464D01*
G01X789053Y470404D02*
X789922Y469535D01*
G01X790982Y467393D02*
Y469975D01*
G01X789922Y469535D02*
Y467836D01*
G01X789493Y465904D02*
X790982Y467393D01*
G01X789922Y467836D02*
X789050Y466964D01*
G01X786936Y465904D02*
X789493D01*
G01X786936D02*
X789493D01*
G01X789922Y467836D02*
X789050Y466964D01*
G01X789493Y465904D02*
X790982Y467393D01*
G01X789922Y469535D02*
Y467836D01*
G01X790982Y467393D02*
Y469975D01*
G01X789053Y470404D02*
X789922Y469535D01*
G01X790982Y469975D02*
X789493Y471464D01*
G01X786712Y470404D02*
X789053D01*
G01X789493Y471464D02*
X787152D01*
G01X788408Y549461D02*
Y509473D01*
G01X789468Y509033D02*
Y541466D01*
G01X788408Y549461D02*
Y509473D01*
G01Y549461D02*
Y509473D01*
G01X789468Y509033D02*
Y541466D01*
G01X788408Y549461D02*
Y509473D01*
G01X789493Y471464D02*
X787152D01*
G01X786712Y470404D02*
X789053D01*
G01X790982Y469975D02*
X789493Y471464D01*
G01X789053Y470404D02*
X789922Y469535D01*
G01X790982Y467393D02*
Y469975D01*
G01X789922Y469535D02*
Y467836D01*
G01X789493Y465904D02*
X790982Y467393D01*
G01X789922Y467836D02*
X789050Y466964D01*
G01X786936Y465904D02*
X789493D01*
G01X794568Y508136D02*
Y550270D01*
G01Y508136D02*
Y550270D01*
G01Y508136D02*
Y550270D01*
G01Y508136D02*
Y550270D01*
G01Y508136D02*
Y550270D01*
G01Y508136D02*
Y550270D01*
G01Y508136D02*
Y550270D01*
G01X793508Y525680D02*
Y524680D01*
G01X794568Y508136D02*
Y550270D01*
G01X793508Y522440D02*
Y521440D01*
G01X794568Y508136D02*
Y550270D01*
G01X793508Y519200D02*
Y508579D01*
G01X790180Y503748D02*
X794568Y508136D01*
G01X793508Y508579D02*
X792527Y507598D01*
G01X790180Y503748D02*
X794568Y508136D01*
G01X790942Y506013D02*
X789120Y504191D01*
G01X790180Y493749D02*
Y503748D01*
G01X789120Y504191D02*
Y493309D01*
G01X791049Y492880D02*
X790180Y493749D01*
G01X789120Y493309D02*
X790609Y491820D01*
G01X795249Y492880D02*
X791049D01*
G01X790609Y491820D02*
X794809D01*
G01X796580Y491549D02*
X795249Y492880D01*
G01X794809Y491820D02*
X795520Y491109D01*
G01X796580Y488290D02*
Y491549D01*
G01X795520Y491109D02*
Y488730D01*
G01X795088Y486798D02*
X796580Y488290D01*
G01X795520Y488730D02*
X794648Y487858D01*
G01X790944Y486798D02*
X795088D01*
G01X794648Y487858D02*
X790504D01*
G01X790102Y485956D02*
X790944Y486798D01*
G01X790504Y487858D02*
X789042Y486396D01*
G01X790102Y484254D02*
Y485956D01*
G01X789042Y486396D02*
Y483814D01*
G01X790998Y483358D02*
X790102Y484254D01*
G01X789042Y483814D02*
X790558Y482298D01*
G01X795088Y483358D02*
X790998D01*
G01X790558Y482298D02*
X794648D01*
G01X796580Y481866D02*
X795088Y483358D01*
G01X794648Y482298D02*
X795520Y481426D01*
G01X796580Y479287D02*
Y481866D01*
G01X795520Y481426D02*
Y479730D01*
G01X795091Y477798D02*
X796580Y479287D01*
G01X795520Y479730D02*
X794648Y478858D01*
G01X791452Y477798D02*
X795091D01*
G01X794648Y478858D02*
X791009D01*
G01X790580Y476926D02*
X791452Y477798D01*
G01X791009Y478858D02*
X789520Y477369D01*
G01X790580Y475230D02*
Y476926D01*
G01X789520Y477369D02*
Y474787D01*
G01X791452Y474358D02*
X790580Y475230D01*
G01X789520Y474787D02*
X791009Y473298D01*
G01X795088Y474358D02*
X791452D01*
G01X791009Y473298D02*
X794648D01*
G01X796580Y472866D02*
X795088Y474358D01*
G01X794648Y473298D02*
X795520Y472426D01*
G01X796580Y468272D02*
Y472866D01*
G01X795520Y472426D02*
Y468712D01*
G01X793616Y465308D02*
X796580Y468272D01*
G01X795520Y468712D02*
X792556Y465748D01*
G01X833820Y495009D02*
Y467401D01*
G01X834880Y467841D02*
Y495452D01*
G01X826120Y502709D02*
X833820Y495009D01*
G01X834880Y495452D02*
X827180Y503152D01*
G01X826120Y509809D02*
Y502709D01*
G01X827180Y503152D02*
Y510252D01*
G01X825219Y510710D02*
X826120Y509809D01*
G01X827180Y510252D02*
X826279Y511153D01*
G01X825219Y549608D02*
Y510710D01*
G01X826279Y511153D02*
Y541764D01*
G01X825219Y549608D02*
Y510710D01*
G01Y549608D02*
Y510710D01*
G01X831379Y550259D02*
Y504650D01*
G01Y550259D02*
Y504650D01*
G01Y550259D02*
Y504650D01*
G01Y550259D02*
Y504650D01*
G01Y550259D02*
Y504650D01*
G01X830319Y526103D02*
Y504210D01*
G01X831379Y504650D02*
X838680Y497349D01*
G01X830319Y504210D02*
X837620Y496909D01*
G01X838680Y497349D02*
Y471452D01*
G01X837620Y496909D02*
Y471009D01*
G01X795520Y468712D02*
X792556Y465748D01*
G01X793616Y465308D02*
X796580Y468272D01*
G01X795520Y472426D02*
Y468712D01*
G01X796580Y468272D02*
Y472866D01*
G01X794648Y473298D02*
X795520Y472426D01*
G01X796580Y472866D02*
X795088Y474358D01*
G01X791009Y473298D02*
X794648D01*
G01X795088Y474358D02*
X791452D01*
G01X789520Y474787D02*
X791009Y473298D01*
G01X791452Y474358D02*
X790580Y475230D01*
G01X789520Y477369D02*
Y474787D01*
G01X790580Y475230D02*
Y476926D01*
G01X791009Y478858D02*
X789520Y477369D01*
G01X790580Y476926D02*
X791452Y477798D01*
G01X794648Y478858D02*
X791009D01*
G01X791452Y477798D02*
X795091D01*
G01X795520Y479730D02*
X794648Y478858D01*
G01X795091Y477798D02*
X796580Y479287D01*
G01X795520Y481426D02*
Y479730D01*
G01X796580Y479287D02*
Y481866D01*
G01X794648Y482298D02*
X795520Y481426D01*
G01X796580Y481866D02*
X795088Y483358D01*
G01X790558Y482298D02*
X794648D01*
G01X795088Y483358D02*
X790998D01*
G01X789042Y483814D02*
X790558Y482298D01*
G01X790998Y483358D02*
X790102Y484254D01*
G01X789042Y486396D02*
Y483814D01*
G01X790102Y484254D02*
Y485956D01*
G01X790504Y487858D02*
X789042Y486396D01*
G01X790102Y485956D02*
X790944Y486798D01*
G01X794648Y487858D02*
X790504D01*
G01X790944Y486798D02*
X795088D01*
G01X795520Y488730D02*
X794648Y487858D01*
G01X795088Y486798D02*
X796580Y488290D01*
G01X795520Y491109D02*
Y488730D01*
G01X796580Y488290D02*
Y491549D01*
G01X794809Y491820D02*
X795520Y491109D01*
G01X796580Y491549D02*
X795249Y492880D01*
G01X790609Y491820D02*
X794809D01*
G01X795249Y492880D02*
X791049D01*
G01X789120Y493309D02*
X790609Y491820D01*
G01X791049Y492880D02*
X790180Y493749D01*
G01X789120Y504191D02*
Y493309D01*
G01X790180Y493749D02*
Y503748D01*
G01X793508Y508579D02*
X792527Y507598D01*
G01X790942Y506013D02*
X789120Y504191D01*
G01X790180Y503748D02*
X794568Y508136D01*
G01X793508Y525680D02*
Y524680D01*
G01Y522440D02*
Y521440D01*
G01Y519200D02*
Y508579D01*
G01X794568Y508136D02*
Y550270D01*
G01X826279Y511153D02*
Y541764D01*
G01X825219Y549608D02*
Y510710D01*
G01X827180Y510252D02*
X826279Y511153D01*
G01X825219Y510710D02*
X826120Y509809D01*
G01X827180Y503152D02*
Y510252D01*
G01X826120Y509809D02*
Y502709D01*
G01X834880Y495452D02*
X827180Y503152D01*
G01X826120Y502709D02*
X833820Y495009D01*
G01X834880Y467841D02*
Y495452D01*
G01X833820Y495009D02*
Y467401D01*
G01X830319Y526103D02*
Y504210D01*
G01X831379Y550259D02*
Y504650D01*
G01X830319Y504210D02*
X837620Y496909D01*
G01X831379Y504650D02*
X838680Y497349D01*
G01X837620Y496909D02*
Y471009D01*
G01X838680Y497349D02*
Y471452D01*
G01X794568Y508136D02*
Y550270D01*
G01Y508136D02*
Y550270D01*
G01Y508136D02*
Y550270D01*
G01Y508136D02*
Y550270D01*
G01Y508136D02*
Y550270D01*
G01Y508136D02*
Y550270D01*
G01Y508136D02*
Y550270D01*
G01X793508Y525680D02*
Y524680D01*
G01X794568Y508136D02*
Y550270D01*
G01X793508Y522440D02*
Y521440D01*
G01X794568Y508136D02*
Y550270D01*
G01X793508Y519200D02*
Y508579D01*
G01X790180Y503748D02*
X794568Y508136D01*
G01X793508Y508579D02*
X792527Y507598D01*
G01X790180Y503748D02*
X794568Y508136D01*
G01X790942Y506013D02*
X789120Y504191D01*
G01X790180Y493749D02*
Y503748D01*
G01X789120Y504191D02*
Y493309D01*
G01X791049Y492880D02*
X790180Y493749D01*
G01X789120Y493309D02*
X790609Y491820D01*
G01X795249Y492880D02*
X791049D01*
G01X790609Y491820D02*
X794809D01*
G01X796580Y491549D02*
X795249Y492880D01*
G01X794809Y491820D02*
X795520Y491109D01*
G01X796580Y488290D02*
Y491549D01*
G01X795520Y491109D02*
Y488730D01*
G01X795088Y486798D02*
X796580Y488290D01*
G01X795520Y488730D02*
X794648Y487858D01*
G01X790944Y486798D02*
X795088D01*
G01X794648Y487858D02*
X790504D01*
G01X790102Y485956D02*
X790944Y486798D01*
G01X790504Y487858D02*
X789042Y486396D01*
G01X790102Y484254D02*
Y485956D01*
G01X789042Y486396D02*
Y483814D01*
G01X790998Y483358D02*
X790102Y484254D01*
G01X789042Y483814D02*
X790558Y482298D01*
G01X795088Y483358D02*
X790998D01*
G01X790558Y482298D02*
X794648D01*
G01X796580Y481866D02*
X795088Y483358D01*
G01X794648Y482298D02*
X795520Y481426D01*
G01X796580Y479287D02*
Y481866D01*
G01X795520Y481426D02*
Y479730D01*
G01X795091Y477798D02*
X796580Y479287D01*
G01X795520Y479730D02*
X794648Y478858D01*
G01X791452Y477798D02*
X795091D01*
G01X794648Y478858D02*
X791009D01*
G01X790580Y476926D02*
X791452Y477798D01*
G01X791009Y478858D02*
X789520Y477369D01*
G01X790580Y475230D02*
Y476926D01*
G01X789520Y477369D02*
Y474787D01*
G01X791452Y474358D02*
X790580Y475230D01*
G01X789520Y474787D02*
X791009Y473298D01*
G01X795088Y474358D02*
X791452D01*
G01X791009Y473298D02*
X794648D01*
G01X796580Y472866D02*
X795088Y474358D01*
G01X794648Y473298D02*
X795520Y472426D01*
G01X796580Y468272D02*
Y472866D01*
G01X795520Y472426D02*
Y468712D01*
G01X793616Y465308D02*
X796580Y468272D01*
G01X795520Y468712D02*
X792556Y465748D01*
G01X833820Y495009D02*
Y467401D01*
G01X834880Y467841D02*
Y495452D01*
G01X826120Y502709D02*
X833820Y495009D01*
G01X834880Y495452D02*
X827180Y503152D01*
G01X826120Y509809D02*
Y502709D01*
G01X827180Y503152D02*
Y510252D01*
G01X825219Y510710D02*
X826120Y509809D01*
G01X827180Y510252D02*
X826279Y511153D01*
G01X825219Y549608D02*
Y510710D01*
G01X826279Y511153D02*
Y541764D01*
G01X825219Y549608D02*
Y510710D01*
G01Y549608D02*
Y510710D01*
G01X831379Y550259D02*
Y504650D01*
G01Y550259D02*
Y504650D01*
G01Y550259D02*
Y504650D01*
G01Y550259D02*
Y504650D01*
G01Y550259D02*
Y504650D01*
G01X830319Y526103D02*
Y504210D01*
G01X831379Y504650D02*
X838680Y497349D01*
G01X830319Y504210D02*
X837620Y496909D01*
G01X838680Y497349D02*
Y471452D01*
G01X837620Y496909D02*
Y471009D01*
G01X795520Y468712D02*
X792556Y465748D01*
G01X793616Y465308D02*
X796580Y468272D01*
G01X795520Y472426D02*
Y468712D01*
G01X796580Y468272D02*
Y472866D01*
G01X794648Y473298D02*
X795520Y472426D01*
G01X796580Y472866D02*
X795088Y474358D01*
G01X791009Y473298D02*
X794648D01*
G01X795088Y474358D02*
X791452D01*
G01X789520Y474787D02*
X791009Y473298D01*
G01X791452Y474358D02*
X790580Y475230D01*
G01X789520Y477369D02*
Y474787D01*
G01X790580Y475230D02*
Y476926D01*
G01X791009Y478858D02*
X789520Y477369D01*
G01X790580Y476926D02*
X791452Y477798D01*
G01X794648Y478858D02*
X791009D01*
G01X791452Y477798D02*
X795091D01*
G01X795520Y479730D02*
X794648Y478858D01*
G01X795091Y477798D02*
X796580Y479287D01*
G01X795520Y481426D02*
Y479730D01*
G01X796580Y479287D02*
Y481866D01*
G01X794648Y482298D02*
X795520Y481426D01*
G01X796580Y481866D02*
X795088Y483358D01*
G01X790558Y482298D02*
X794648D01*
G01X795088Y483358D02*
X790998D01*
G01X789042Y483814D02*
X790558Y482298D01*
G01X790998Y483358D02*
X790102Y484254D01*
G01X789042Y486396D02*
Y483814D01*
G01X790102Y484254D02*
Y485956D01*
G01X790504Y487858D02*
X789042Y486396D01*
G01X790102Y485956D02*
X790944Y486798D01*
G01X794648Y487858D02*
X790504D01*
G01X790944Y486798D02*
X795088D01*
G01X795520Y488730D02*
X794648Y487858D01*
G01X795088Y486798D02*
X796580Y488290D01*
G01X795520Y491109D02*
Y488730D01*
G01X796580Y488290D02*
Y491549D01*
G01X794809Y491820D02*
X795520Y491109D01*
G01X796580Y491549D02*
X795249Y492880D01*
G01X790609Y491820D02*
X794809D01*
G01X795249Y492880D02*
X791049D01*
G01X789120Y493309D02*
X790609Y491820D01*
G01X791049Y492880D02*
X790180Y493749D01*
G01X789120Y504191D02*
Y493309D01*
G01X790180Y493749D02*
Y503748D01*
G01X793508Y508579D02*
X792527Y507598D01*
G01X790942Y506013D02*
X789120Y504191D01*
G01X790180Y503748D02*
X794568Y508136D01*
G01X793508Y525680D02*
Y524680D01*
G01Y522440D02*
Y521440D01*
G01Y519200D02*
Y508579D01*
G01X794568Y508136D02*
Y550270D01*
G01X826279Y511153D02*
Y541764D01*
G01X825219Y549608D02*
Y510710D01*
G01X827180Y510252D02*
X826279Y511153D01*
G01X825219Y510710D02*
X826120Y509809D01*
G01X827180Y503152D02*
Y510252D01*
G01X826120Y509809D02*
Y502709D01*
G01X834880Y495452D02*
X827180Y503152D01*
G01X826120Y502709D02*
X833820Y495009D01*
G01X834880Y467841D02*
Y495452D01*
G01X833820Y495009D02*
Y467401D01*
G01X830319Y526103D02*
Y504210D01*
G01X831379Y550259D02*
Y504650D01*
G01X830319Y504210D02*
X837620Y496909D01*
G01X831379Y504650D02*
X838680Y497349D01*
G01X837620Y496909D02*
Y471009D01*
G01X838680Y497349D02*
Y471452D01*
G01X789468Y543414D02*
Y544560D01*
G01Y546800D02*
Y550049D01*
G01Y543414D02*
Y544560D01*
G01Y546800D02*
Y550049D01*
G01Y543414D02*
Y544560D01*
G01Y546800D02*
Y550049D01*
G01Y543414D02*
Y544560D01*
G01Y546800D02*
Y550049D01*
G01X790013Y564029D02*
X790784Y564800D01*
G01X789783Y565300D02*
X788953Y564470D01*
G01X790013Y558371D02*
Y559648D01*
G01Y563138D02*
Y564029D01*
G01X788953Y564470D02*
Y557930D01*
G01X790684Y557700D02*
X790013Y558371D01*
G01X788953Y557930D02*
X789783Y557100D01*
G01X793508Y549659D02*
Y546920D01*
G01Y544680D02*
Y543680D01*
G01Y541440D02*
Y540440D01*
G01Y538200D02*
Y536424D01*
G01Y534424D02*
Y531267D01*
G01Y529293D02*
Y527920D01*
G01X821211Y570211D02*
Y552200D01*
G01X822271Y558090D02*
Y559460D01*
G01X821211Y570211D02*
Y552200D01*
G01X822271Y563140D02*
Y564560D01*
G01X826279Y543452D02*
Y544545D01*
G01Y546445D02*
Y550049D01*
G01X824327Y550500D02*
X825219Y549608D01*
G01X826279Y550049D02*
X823228Y553100D01*
G01X827595Y564800D02*
X826824Y564029D01*
G01X826594Y565300D02*
X825764Y564470D01*
G01X826824Y564029D02*
Y563138D01*
G01Y559648D02*
Y558371D01*
G01X825764Y564470D02*
Y557930D01*
G01X826824Y558371D02*
X827495Y557700D01*
G01X825764Y557930D02*
X826594Y557100D01*
G01X830319Y549648D02*
Y546854D01*
G01Y544614D02*
Y543614D01*
G01Y541374D02*
Y540307D01*
G01Y538279D02*
Y527893D01*
G01X788953Y557930D02*
X789783Y557100D01*
G01X790684Y557700D02*
X790013Y558371D01*
G01X788953Y564470D02*
Y557930D01*
G01X790013Y558371D02*
Y559648D01*
G01X788953Y564470D02*
Y557930D01*
G01X790013Y563138D02*
Y564029D01*
G01X789783Y565300D02*
X788953Y564470D01*
G01X790013Y564029D02*
X790784Y564800D01*
G01X793508Y549659D02*
Y546920D01*
G01Y544680D02*
Y543680D01*
G01Y541440D02*
Y540440D01*
G01Y538200D02*
Y536424D01*
G01Y534424D02*
Y531267D01*
G01Y529293D02*
Y527920D01*
G01X822271Y558090D02*
Y559460D01*
G01Y563140D02*
Y564560D01*
G01X821211Y570211D02*
Y552200D01*
G01X826279Y550049D02*
X823228Y553100D01*
G01X824327Y550500D02*
X825219Y549608D01*
G01X826279Y543452D02*
Y544545D01*
G01Y546445D02*
Y550049D01*
G01X826594Y565300D02*
X825764Y564470D01*
G01X827595Y564800D02*
X826824Y564029D01*
G01X825764Y564470D02*
Y557930D01*
G01X826824Y564029D02*
Y563138D01*
G01X825764Y564470D02*
Y557930D01*
G01X826824Y559648D02*
Y558371D01*
G01X825764Y557930D02*
X826594Y557100D01*
G01X826824Y558371D02*
X827495Y557700D01*
G01X830319Y549648D02*
Y546854D01*
G01Y544614D02*
Y543614D01*
G01Y541374D02*
Y540307D01*
G01Y538279D02*
Y527893D01*
G01X790013Y564029D02*
X790784Y564800D01*
G01X789783Y565300D02*
X788953Y564470D01*
G01X790013Y558371D02*
Y559648D01*
G01Y563138D02*
Y564029D01*
G01X788953Y564470D02*
Y557930D01*
G01X790684Y557700D02*
X790013Y558371D01*
G01X788953Y557930D02*
X789783Y557100D01*
G01X793508Y549659D02*
Y546920D01*
G01Y544680D02*
Y543680D01*
G01Y541440D02*
Y540440D01*
G01Y538200D02*
Y536424D01*
G01Y534424D02*
Y531267D01*
G01Y529293D02*
Y527920D01*
G01X821211Y570211D02*
Y552200D01*
G01X822271Y558090D02*
Y559460D01*
G01X821211Y570211D02*
Y552200D01*
G01X822271Y563140D02*
Y564560D01*
G01X826279Y543452D02*
Y544545D01*
G01Y546445D02*
Y550049D01*
G01X824327Y550500D02*
X825219Y549608D01*
G01X826279Y550049D02*
X823228Y553100D01*
G01X827595Y564800D02*
X826824Y564029D01*
G01X826594Y565300D02*
X825764Y564470D01*
G01X826824Y564029D02*
Y563138D01*
G01Y559648D02*
Y558371D01*
G01X825764Y564470D02*
Y557930D01*
G01X826824Y558371D02*
X827495Y557700D01*
G01X825764Y557930D02*
X826594Y557100D01*
G01X830319Y549648D02*
Y546854D01*
G01Y544614D02*
Y543614D01*
G01Y541374D02*
Y540307D01*
G01Y538279D02*
Y527893D01*
G01X788953Y557930D02*
X789783Y557100D01*
G01X790684Y557700D02*
X790013Y558371D01*
G01X788953Y564470D02*
Y557930D01*
G01X790013Y558371D02*
Y559648D01*
G01X788953Y564470D02*
Y557930D01*
G01X790013Y563138D02*
Y564029D01*
G01X789783Y565300D02*
X788953Y564470D01*
G01X790013Y564029D02*
X790784Y564800D01*
G01X793508Y549659D02*
Y546920D01*
G01Y544680D02*
Y543680D01*
G01Y541440D02*
Y540440D01*
G01Y538200D02*
Y536424D01*
G01Y534424D02*
Y531267D01*
G01Y529293D02*
Y527920D01*
G01X822271Y558090D02*
Y559460D01*
G01Y563140D02*
Y564560D01*
G01X821211Y570211D02*
Y552200D01*
G01X826279Y550049D02*
X823228Y553100D01*
G01X824327Y550500D02*
X825219Y549608D01*
G01X826279Y543452D02*
Y544545D01*
G01Y546445D02*
Y550049D01*
G01X826594Y565300D02*
X825764Y564470D01*
G01X827595Y564800D02*
X826824Y564029D01*
G01X825764Y564470D02*
Y557930D01*
G01X826824Y564029D02*
Y563138D01*
G01X825764Y564470D02*
Y557930D01*
G01X826824Y559648D02*
Y558371D01*
G01X825764Y557930D02*
X826594Y557100D01*
G01X826824Y558371D02*
X827495Y557700D01*
G01X830319Y549648D02*
Y546854D01*
G01Y544614D02*
Y543614D01*
G01Y541374D02*
Y540307D01*
G01Y538279D02*
Y527893D01*
G01X860829Y32580D02*
X861345D01*
G01X860806Y31520D02*
X861788D01*
G01X860829Y32580D02*
X861345D01*
G01D02*
X862056Y33291D01*
G01X861788Y31520D02*
X863116Y32848D01*
G01X898156Y32580D02*
X897640D01*
G01X897617Y31520D02*
X898599D01*
G01X898867Y33291D02*
X898156Y32580D01*
G01D02*
X897640D01*
G01X898599Y31520D02*
X899927Y32848D01*
G01X865110Y30540D02*
X868302Y33732D01*
G01X860806Y31520D02*
X861788D01*
G01D02*
X863116Y32848D01*
G01X860829Y32580D02*
X861345D01*
G01X861788Y31520D02*
X863116Y32848D01*
G01X861345Y32580D02*
X862056Y33291D01*
G01X898599Y31520D02*
X899927Y32848D01*
G01X898867Y33291D02*
X898156Y32580D01*
G01X897617Y31520D02*
X898599D01*
G01D02*
X899927Y32848D01*
G01X898156Y32580D02*
X897640D01*
G01X901921Y30540D02*
X905113Y33732D01*
G01X860829Y32580D02*
X861345D01*
G01X860806Y31520D02*
X861788D01*
G01X860829Y32580D02*
X861345D01*
G01D02*
X862056Y33291D01*
G01X861788Y31520D02*
X863116Y32848D01*
G01X898156Y32580D02*
X897640D01*
G01X897617Y31520D02*
X898599D01*
G01X898867Y33291D02*
X898156Y32580D01*
G01D02*
X897640D01*
G01X898599Y31520D02*
X899927Y32848D01*
G01X865110Y30540D02*
X868302Y33732D01*
G01X901921Y30540D02*
X905113Y33732D01*
G01X901921Y30540D02*
X905113Y33732D01*
G01X901921Y30540D02*
X905113Y33732D01*
G01X901921Y30540D02*
X905113Y33732D01*
G01X860806Y31520D02*
X861788D01*
G01D02*
X863116Y32848D01*
G01X860829Y32580D02*
X861345D01*
G01X861788Y31520D02*
X863116Y32848D01*
G01X861345Y32580D02*
X862056Y33291D01*
G01X898599Y31520D02*
X899927Y32848D01*
G01X898867Y33291D02*
X898156Y32580D01*
G01X897617Y31520D02*
X898599D01*
G01D02*
X899927Y32848D01*
G01X898156Y32580D02*
X897640D01*
G01X865110Y30540D02*
X868302Y33732D01*
G01X865110Y30540D02*
X868302Y33732D01*
G01X865110Y30540D02*
X868302Y33732D01*
G01X865110Y30540D02*
X868302Y33732D01*
G01X901921Y30540D02*
X905113Y33732D01*
G01X858156Y51354D02*
Y59731D01*
G01X859216Y57420D02*
Y59288D01*
G01X858156Y59731D02*
X862030Y63605D01*
G01X859216Y59288D02*
X860170Y60242D01*
G01X858156Y59731D02*
X862030Y63605D01*
G01X861761Y61833D02*
X863090Y63162D01*
G01X862030Y63605D02*
Y115998D01*
G01X863090Y63162D02*
Y74275D01*
G01X862030Y63605D02*
Y115998D01*
G01X863090Y76524D02*
Y78026D01*
G01X862030Y63605D02*
Y115998D01*
G01X863090Y80275D02*
Y93980D01*
G01X862030Y63605D02*
Y115998D01*
G01Y63605D02*
Y115998D01*
G01Y63605D02*
Y115998D01*
G01Y63605D02*
Y115998D01*
G01X862056Y33291D02*
Y36580D01*
G01Y40920D02*
Y41880D01*
G01Y46020D02*
Y48553D01*
G01X863116Y32848D02*
Y48994D01*
G01X862056Y48553D02*
X861109Y49500D01*
G01X863116Y48994D02*
X860010Y52100D01*
G01X896778Y60190D02*
Y57320D01*
G01X897838Y56781D02*
Y59747D01*
G01X898778Y62190D02*
X896778Y60190D01*
G01X897838Y59747D02*
X899838Y61747D01*
G01X898778Y105934D02*
Y62190D01*
G01X899838Y61747D02*
Y107497D01*
G01X898867Y48553D02*
Y46020D01*
G01Y41880D02*
Y40920D01*
G01Y36580D02*
Y33291D01*
G01X899927Y32848D02*
Y48994D01*
G01X896821Y49500D02*
X897920D01*
G01D02*
X898867Y48553D01*
G01X899927Y48994D02*
X896821Y52100D01*
G01X863856Y59031D02*
Y58199D01*
G01X864916Y57684D02*
Y58588D01*
G01X867130Y62305D02*
X863856Y59031D01*
G01X864916Y58588D02*
X868190Y61862D01*
G01X867130Y115701D02*
Y62305D01*
G01X868190Y61862D02*
Y115258D01*
G01X867242Y34172D02*
X866219Y33149D01*
G01D02*
X865110D01*
G01X867242Y48681D02*
Y45906D01*
G01Y42080D02*
Y40707D01*
G01Y36793D02*
Y34172D01*
G01X868302Y33732D02*
Y49122D01*
G01X865110Y49715D02*
X866208D01*
G01D02*
X867242Y48681D01*
G01X868302Y49122D02*
X865110Y52314D01*
G01X859216Y57420D02*
Y59288D01*
G01X858156Y51354D02*
Y59731D01*
G01X859216Y59288D02*
X860170Y60242D01*
G01X861761Y61833D02*
X863090Y63162D01*
G01X858156Y59731D02*
X862030Y63605D01*
G01X863090Y63162D02*
Y74275D01*
G01Y76524D02*
Y78026D01*
G01Y80275D02*
Y93980D01*
G01X862030Y63605D02*
Y115998D01*
G01X863116Y32848D02*
Y48994D01*
G01X862056Y33291D02*
Y36580D01*
G01X863116Y32848D02*
Y48994D01*
G01X862056Y40920D02*
Y41880D01*
G01X863116Y32848D02*
Y48994D01*
G01X862056Y46020D02*
Y48553D01*
G01X863116Y48994D02*
X860010Y52100D01*
G01X862056Y48553D02*
X861109Y49500D01*
G01X899838Y61747D02*
Y107497D01*
G01X898778Y105934D02*
Y62190D01*
G01X897838Y59747D02*
X899838Y61747D01*
G01X898778Y62190D02*
X896778Y60190D01*
G01X897838Y56781D02*
Y59747D01*
G01X896778Y60190D02*
Y57320D01*
G01X899927Y48994D02*
X896821Y52100D01*
G01Y49500D02*
X897920D01*
G01X899927Y48994D02*
X896821Y52100D01*
G01X897920Y49500D02*
X898867Y48553D01*
G01X899927Y32848D02*
Y48994D01*
G01X898867Y48553D02*
Y46020D01*
G01X899927Y32848D02*
Y48994D01*
G01X898867Y41880D02*
Y40920D01*
G01X899927Y32848D02*
Y48994D01*
G01X898867Y36580D02*
Y33291D01*
G01X901978Y57520D02*
Y58192D01*
G01X903038Y56620D02*
Y57749D01*
G01X901978Y58192D02*
X903878Y60092D01*
G01X903038Y57749D02*
X904938Y59649D01*
G01X903878Y60092D02*
Y106722D01*
G01X904938Y59649D02*
Y108263D01*
G01X901921Y33149D02*
X903030D01*
G01D02*
X904053Y34172D01*
G01D02*
Y36793D01*
G01Y40707D02*
Y42080D01*
G01Y45906D02*
Y48681D01*
G01X905113Y33732D02*
Y49122D01*
G01X904053Y48681D02*
X903019Y49715D01*
G01D02*
X901921D01*
G01X905113Y49122D02*
X901921Y52314D01*
G01X858156Y51354D02*
Y59731D01*
G01X859216Y57420D02*
Y59288D01*
G01X858156Y59731D02*
X862030Y63605D01*
G01X859216Y59288D02*
X860170Y60242D01*
G01X858156Y59731D02*
X862030Y63605D01*
G01X861761Y61833D02*
X863090Y63162D01*
G01X862030Y63605D02*
Y115998D01*
G01X863090Y63162D02*
Y74275D01*
G01X862030Y63605D02*
Y115998D01*
G01X863090Y76524D02*
Y78026D01*
G01X862030Y63605D02*
Y115998D01*
G01X863090Y80275D02*
Y93980D01*
G01X862030Y63605D02*
Y115998D01*
G01Y63605D02*
Y115998D01*
G01Y63605D02*
Y115998D01*
G01Y63605D02*
Y115998D01*
G01X862056Y33291D02*
Y36580D01*
G01Y40920D02*
Y41880D01*
G01Y46020D02*
Y48553D01*
G01X863116Y32848D02*
Y48994D01*
G01X862056Y48553D02*
X861109Y49500D01*
G01X863116Y48994D02*
X860010Y52100D01*
G01X896778Y60190D02*
Y57320D01*
G01X897838Y56781D02*
Y59747D01*
G01X898778Y62190D02*
X896778Y60190D01*
G01X897838Y59747D02*
X899838Y61747D01*
G01X898778Y105934D02*
Y62190D01*
G01X899838Y61747D02*
Y107497D01*
G01X898867Y48553D02*
Y46020D01*
G01Y41880D02*
Y40920D01*
G01Y36580D02*
Y33291D01*
G01X899927Y32848D02*
Y48994D01*
G01X896821Y49500D02*
X897920D01*
G01D02*
X898867Y48553D01*
G01X899927Y48994D02*
X896821Y52100D01*
G01X863856Y59031D02*
Y58199D01*
G01X864916Y57684D02*
Y58588D01*
G01X867130Y62305D02*
X863856Y59031D01*
G01X864916Y58588D02*
X868190Y61862D01*
G01X867130Y115701D02*
Y62305D01*
G01X868190Y61862D02*
Y115258D01*
G01X867242Y34172D02*
X866219Y33149D01*
G01D02*
X865110D01*
G01X867242Y48681D02*
Y45906D01*
G01Y42080D02*
Y40707D01*
G01Y36793D02*
Y34172D01*
G01X868302Y33732D02*
Y49122D01*
G01X865110Y49715D02*
X866208D01*
G01D02*
X867242Y48681D01*
G01X868302Y49122D02*
X865110Y52314D01*
G01X903038Y56620D02*
Y57749D01*
G01X901978Y57520D02*
Y58192D01*
G01X903038Y57749D02*
X904938Y59649D01*
G01X901978Y58192D02*
X903878Y60092D01*
G01X904938Y59649D02*
Y108263D01*
G01X903878Y60092D02*
Y106722D01*
G01X901921Y33149D02*
X903030D01*
G01D02*
X904053Y34172D01*
G01X905113Y33732D02*
Y49122D01*
G01X904053Y34172D02*
Y36793D01*
G01X905113Y33732D02*
Y49122D01*
G01X904053Y40707D02*
Y42080D01*
G01X905113Y33732D02*
Y49122D01*
G01X904053Y45906D02*
Y48681D01*
G01X905113Y49122D02*
X901921Y52314D01*
G01X904053Y48681D02*
X903019Y49715D01*
G01X905113Y49122D02*
X901921Y52314D01*
G01X903019Y49715D02*
X901921D01*
G01X903038Y56620D02*
Y57749D01*
G01X901978Y57520D02*
Y58192D01*
G01X903038Y57749D02*
X904938Y59649D01*
G01X901978Y58192D02*
X903878Y60092D01*
G01X904938Y59649D02*
Y108263D01*
G01X903878Y60092D02*
Y106722D01*
G01X901921Y33149D02*
X903030D01*
G01D02*
X904053Y34172D01*
G01X905113Y33732D02*
Y49122D01*
G01X904053Y34172D02*
Y36793D01*
G01X905113Y33732D02*
Y49122D01*
G01X904053Y40707D02*
Y42080D01*
G01X905113Y33732D02*
Y49122D01*
G01X904053Y45906D02*
Y48681D01*
G01X905113Y49122D02*
X901921Y52314D01*
G01X904053Y48681D02*
X903019Y49715D01*
G01X905113Y49122D02*
X901921Y52314D01*
G01X903019Y49715D02*
X901921D01*
G01X859216Y57420D02*
Y59288D01*
G01X858156Y51354D02*
Y59731D01*
G01X859216Y59288D02*
X860170Y60242D01*
G01X861761Y61833D02*
X863090Y63162D01*
G01X858156Y59731D02*
X862030Y63605D01*
G01X863090Y63162D02*
Y74275D01*
G01Y76524D02*
Y78026D01*
G01Y80275D02*
Y93980D01*
G01X862030Y63605D02*
Y115998D01*
G01X863116Y32848D02*
Y48994D01*
G01X862056Y33291D02*
Y36580D01*
G01X863116Y32848D02*
Y48994D01*
G01X862056Y40920D02*
Y41880D01*
G01X863116Y32848D02*
Y48994D01*
G01X862056Y46020D02*
Y48553D01*
G01X863116Y48994D02*
X860010Y52100D01*
G01X862056Y48553D02*
X861109Y49500D01*
G01X899838Y61747D02*
Y107497D01*
G01X898778Y105934D02*
Y62190D01*
G01X897838Y59747D02*
X899838Y61747D01*
G01X898778Y62190D02*
X896778Y60190D01*
G01X897838Y56781D02*
Y59747D01*
G01X896778Y60190D02*
Y57320D01*
G01X899927Y48994D02*
X896821Y52100D01*
G01Y49500D02*
X897920D01*
G01X899927Y48994D02*
X896821Y52100D01*
G01X897920Y49500D02*
X898867Y48553D01*
G01X899927Y32848D02*
Y48994D01*
G01X898867Y48553D02*
Y46020D01*
G01X899927Y32848D02*
Y48994D01*
G01X898867Y41880D02*
Y40920D01*
G01X899927Y32848D02*
Y48994D01*
G01X898867Y36580D02*
Y33291D01*
G01X868302Y49122D02*
X865110Y52314D01*
G01Y49715D02*
X866208D01*
G01X868302Y49122D02*
X865110Y52314D01*
G01X866208Y49715D02*
X867242Y48681D01*
G01X868302Y33732D02*
Y49122D01*
G01X867242Y48681D02*
Y45906D01*
G01X868302Y33732D02*
Y49122D01*
G01X867242Y42080D02*
Y40707D01*
G01X868302Y33732D02*
Y49122D01*
G01X867242Y36793D02*
Y34172D01*
G01D02*
X866219Y33149D01*
G01D02*
X865110D01*
G01X868190Y61862D02*
Y115258D01*
G01X867130Y115701D02*
Y62305D01*
G01X864916Y58588D02*
X868190Y61862D01*
G01X867130Y62305D02*
X863856Y59031D01*
G01X864916Y57684D02*
Y58588D01*
G01X863856Y59031D02*
Y58199D01*
G01X868302Y49122D02*
X865110Y52314D01*
G01Y49715D02*
X866208D01*
G01X868302Y49122D02*
X865110Y52314D01*
G01X866208Y49715D02*
X867242Y48681D01*
G01X868302Y33732D02*
Y49122D01*
G01X867242Y48681D02*
Y45906D01*
G01X868302Y33732D02*
Y49122D01*
G01X867242Y42080D02*
Y40707D01*
G01X868302Y33732D02*
Y49122D01*
G01X867242Y36793D02*
Y34172D01*
G01D02*
X866219Y33149D01*
G01D02*
X865110D01*
G01X868190Y61862D02*
Y115258D01*
G01X867130Y115701D02*
Y62305D01*
G01X864916Y58588D02*
X868190Y61862D01*
G01X867130Y62305D02*
X863856Y59031D01*
G01X864916Y57684D02*
Y58588D01*
G01X863856Y59031D02*
Y58199D01*
G01X901978Y57520D02*
Y58192D01*
G01X903038Y56620D02*
Y57749D01*
G01X901978Y58192D02*
X903878Y60092D01*
G01X903038Y57749D02*
X904938Y59649D01*
G01X903878Y60092D02*
Y106722D01*
G01X904938Y59649D02*
Y108263D01*
G01X901921Y33149D02*
X903030D01*
G01D02*
X904053Y34172D01*
G01D02*
Y36793D01*
G01Y40707D02*
Y42080D01*
G01Y45906D02*
Y48681D01*
G01X905113Y33732D02*
Y49122D01*
G01X904053Y48681D02*
X903019Y49715D01*
G01D02*
X901921D01*
G01X905113Y49122D02*
X901921Y52314D01*
G01X851220Y151612D02*
Y144021D01*
G01X852280Y143581D02*
Y152052D01*
G01X849420Y153412D02*
X851220Y151612D01*
G01X852280Y152052D02*
X850480Y153852D01*
G01X849420Y155617D02*
Y153412D01*
G01X850480Y153852D02*
Y155174D01*
G01X921251Y227445D02*
X849422Y155616D01*
G01X850480Y155174D02*
X918783Y223477D01*
G01X921251Y227445D02*
X849422Y155616D01*
G01X921251Y227445D02*
X849422Y155616D01*
G01X851220Y151612D02*
Y144021D01*
G01X852280Y143581D02*
Y152052D01*
G01X849420Y153412D02*
X851220Y151612D01*
G01X852280Y152052D02*
X850480Y153852D01*
G01X849420Y155617D02*
Y153412D01*
G01X850480Y153852D02*
Y155174D01*
G01X921251Y227445D02*
X849422Y155616D01*
G01X850480Y155174D02*
X918783Y223477D01*
G01X921251Y227445D02*
X849422Y155616D01*
G01X921251Y227445D02*
X849422Y155616D01*
G01X850480Y155174D02*
X918783Y223477D01*
G01X921251Y227445D02*
X849422Y155616D01*
G01X850480Y153852D02*
Y155174D01*
G01X849420Y155617D02*
Y153412D01*
G01X852280Y152052D02*
X850480Y153852D01*
G01X849420Y153412D02*
X851220Y151612D01*
G01X852280Y143581D02*
Y152052D01*
G01X851220Y151612D02*
Y144021D01*
G01X850480Y155174D02*
X918783Y223477D01*
G01X921251Y227445D02*
X849422Y155616D01*
G01X850480Y153852D02*
Y155174D01*
G01X849420Y155617D02*
Y153412D01*
G01X852280Y152052D02*
X850480Y153852D01*
G01X849420Y153412D02*
X851220Y151612D01*
G01X852280Y143581D02*
Y152052D01*
G01X851220Y151612D02*
Y144021D01*
G01X863090Y96220D02*
Y96980D01*
G01Y99220D02*
Y99980D01*
G01Y102220D02*
Y103568D01*
G01Y105818D02*
Y115558D01*
G01X862030Y115998D02*
X883933Y137901D01*
G01X863090Y115558D02*
X884993Y137461D01*
G01X883933Y137901D02*
Y140863D01*
G01X884993Y137461D02*
Y140423D01*
G01X883933Y140863D02*
X885638Y142568D01*
G01Y142571D02*
X885946Y142879D01*
G01X884993Y140423D02*
X886389Y141819D01*
G01X885946Y142879D02*
X888908D01*
G01X886389Y141819D02*
X889351D01*
G01X888908Y142879D02*
X890300Y144271D01*
G01X889351Y141819D02*
X891360Y143828D01*
G01X890300Y144271D02*
Y147233D01*
G01X891360Y143828D02*
Y146790D01*
G01X890300Y147233D02*
X892313Y149246D01*
G01X891360Y146790D02*
X892756Y148186D01*
G01X892313Y149246D02*
X895275D01*
G01X892756Y148186D02*
X895718D01*
G01X895275Y149246D02*
X896667Y150638D01*
G01X895718Y148186D02*
X897727Y150195D01*
G01X896667Y150638D02*
Y153600D01*
G01X897727Y150195D02*
Y153157D01*
G01X896667Y153600D02*
X898680Y155613D01*
G01X897727Y153157D02*
X899123Y154553D01*
G01X898680Y155613D02*
X901642D01*
G01X899123Y154553D02*
X902085D01*
G01X901642Y155613D02*
X902220Y156191D01*
G01X902085Y154553D02*
X903280Y155748D01*
G01X902220Y156191D02*
Y169591D01*
G01X903280Y155748D02*
Y158352D01*
G01X902220Y156191D02*
Y169591D01*
G01Y156191D02*
Y169591D01*
G01Y156191D02*
Y169591D01*
G01X906020Y154591D02*
X867130Y115701D01*
G01X868190Y115258D02*
X907080Y154148D01*
G01X906020Y167891D02*
Y154591D01*
G01X907080Y154148D02*
Y167448D01*
G01X863090Y96220D02*
Y96980D01*
G01Y99220D02*
Y99980D01*
G01Y102220D02*
Y103568D01*
G01Y105818D02*
Y115558D01*
G01D02*
X884993Y137461D01*
G01X862030Y115998D02*
X883933Y137901D01*
G01X884993Y137461D02*
Y140423D01*
G01X883933Y137901D02*
Y140863D01*
G01X884993Y140423D02*
X886389Y141819D01*
G01X883933Y140863D02*
X885638Y142568D01*
G01X884993Y140423D02*
X886389Y141819D01*
G01X885638Y142571D02*
X885946Y142879D01*
G01X886389Y141819D02*
X889351D01*
G01X885946Y142879D02*
X888908D01*
G01X889351Y141819D02*
X891360Y143828D01*
G01X888908Y142879D02*
X890300Y144271D01*
G01X891360Y143828D02*
Y146790D01*
G01X890300Y144271D02*
Y147233D01*
G01X891360Y146790D02*
X892756Y148186D01*
G01X890300Y147233D02*
X892313Y149246D01*
G01X892756Y148186D02*
X895718D01*
G01X892313Y149246D02*
X895275D01*
G01X895718Y148186D02*
X897727Y150195D01*
G01X895275Y149246D02*
X896667Y150638D01*
G01X897727Y150195D02*
Y153157D01*
G01X896667Y150638D02*
Y153600D01*
G01X897727Y153157D02*
X899123Y154553D01*
G01X896667Y153600D02*
X898680Y155613D01*
G01X899123Y154553D02*
X902085D01*
G01X898680Y155613D02*
X901642D01*
G01X902085Y154553D02*
X903280Y155748D01*
G01X901642Y155613D02*
X902220Y156191D01*
G01X903280Y155748D02*
Y158352D01*
G01X902220Y156191D02*
Y169591D01*
G01X863090Y96220D02*
Y96980D01*
G01Y99220D02*
Y99980D01*
G01Y102220D02*
Y103568D01*
G01Y105818D02*
Y115558D01*
G01X862030Y115998D02*
X883933Y137901D01*
G01X863090Y115558D02*
X884993Y137461D01*
G01X883933Y137901D02*
Y140863D01*
G01X884993Y137461D02*
Y140423D01*
G01X883933Y140863D02*
X885638Y142568D01*
G01Y142571D02*
X885946Y142879D01*
G01X884993Y140423D02*
X886389Y141819D01*
G01X885946Y142879D02*
X888908D01*
G01X886389Y141819D02*
X889351D01*
G01X888908Y142879D02*
X890300Y144271D01*
G01X889351Y141819D02*
X891360Y143828D01*
G01X890300Y144271D02*
Y147233D01*
G01X891360Y143828D02*
Y146790D01*
G01X890300Y147233D02*
X892313Y149246D01*
G01X891360Y146790D02*
X892756Y148186D01*
G01X892313Y149246D02*
X895275D01*
G01X892756Y148186D02*
X895718D01*
G01X895275Y149246D02*
X896667Y150638D01*
G01X895718Y148186D02*
X897727Y150195D01*
G01X896667Y150638D02*
Y153600D01*
G01X897727Y150195D02*
Y153157D01*
G01X896667Y153600D02*
X898680Y155613D01*
G01X897727Y153157D02*
X899123Y154553D01*
G01X898680Y155613D02*
X901642D01*
G01X899123Y154553D02*
X902085D01*
G01X901642Y155613D02*
X902220Y156191D01*
G01X902085Y154553D02*
X903280Y155748D01*
G01X902220Y156191D02*
Y169591D01*
G01X903280Y155748D02*
Y158352D01*
G01X902220Y156191D02*
Y169591D01*
G01Y156191D02*
Y169591D01*
G01Y156191D02*
Y169591D01*
G01X906020Y154591D02*
X867130Y115701D01*
G01X868190Y115258D02*
X907080Y154148D01*
G01X906020Y167891D02*
Y154591D01*
G01X907080Y154148D02*
Y167448D01*
G01X863090Y96220D02*
Y96980D01*
G01Y99220D02*
Y99980D01*
G01Y102220D02*
Y103568D01*
G01Y105818D02*
Y115558D01*
G01D02*
X884993Y137461D01*
G01X862030Y115998D02*
X883933Y137901D01*
G01X884993Y137461D02*
Y140423D01*
G01X883933Y137901D02*
Y140863D01*
G01X884993Y140423D02*
X886389Y141819D01*
G01X883933Y140863D02*
X885638Y142568D01*
G01X884993Y140423D02*
X886389Y141819D01*
G01X885638Y142571D02*
X885946Y142879D01*
G01X886389Y141819D02*
X889351D01*
G01X885946Y142879D02*
X888908D01*
G01X889351Y141819D02*
X891360Y143828D01*
G01X888908Y142879D02*
X890300Y144271D01*
G01X891360Y143828D02*
Y146790D01*
G01X890300Y144271D02*
Y147233D01*
G01X891360Y146790D02*
X892756Y148186D01*
G01X890300Y147233D02*
X892313Y149246D01*
G01X892756Y148186D02*
X895718D01*
G01X892313Y149246D02*
X895275D01*
G01X895718Y148186D02*
X897727Y150195D01*
G01X895275Y149246D02*
X896667Y150638D01*
G01X897727Y150195D02*
Y153157D01*
G01X896667Y150638D02*
Y153600D01*
G01X897727Y153157D02*
X899123Y154553D01*
G01X896667Y153600D02*
X898680Y155613D01*
G01X899123Y154553D02*
X902085D01*
G01X898680Y155613D02*
X901642D01*
G01X902085Y154553D02*
X903280Y155748D01*
G01X901642Y155613D02*
X902220Y156191D01*
G01X903280Y155748D02*
Y158352D01*
G01X902220Y156191D02*
Y169591D01*
G01X907080Y154148D02*
Y167448D01*
G01X906020Y167891D02*
Y154591D01*
G01X868190Y115258D02*
X907080Y154148D01*
G01X906020Y154591D02*
X867130Y115701D01*
G01X907080Y154148D02*
Y167448D01*
G01X906020Y167891D02*
Y154591D01*
G01X868190Y115258D02*
X907080Y154148D01*
G01X906020Y154591D02*
X867130Y115701D01*
G01X905790Y217419D02*
Y221005D01*
G01X906850Y220565D02*
Y216979D01*
G01D02*
X905881Y216010D01*
G01X904290Y214419D02*
X903081Y213210D01*
G01X901490Y211619D02*
X900537Y210666D01*
G01X898946Y209075D02*
X897992Y208121D01*
G01X896401Y206530D02*
X895448Y205577D01*
G01X893857Y203986D02*
X892903Y203032D01*
G01X891312Y201441D02*
X890359Y200488D01*
G01X888768Y198897D02*
X887814Y197943D01*
G01X886223Y196352D02*
X885270Y195399D01*
G01X883679Y193808D02*
X882725Y192854D01*
G01X881134Y191263D02*
X880181Y190310D01*
G01X878590Y188719D02*
X877636Y187765D01*
G01X876045Y186174D02*
X875092Y185221D01*
G01X906850Y216979D02*
X905881Y216010D01*
G01X904290Y214419D02*
X903081Y213210D01*
G01X901490Y211619D02*
X900537Y210666D01*
G01X898946Y209075D02*
X897992Y208121D01*
G01X896401Y206530D02*
X895448Y205577D01*
G01X893857Y203986D02*
X892903Y203032D01*
G01X891312Y201441D02*
X890359Y200488D01*
G01X888768Y198897D02*
X887814Y197943D01*
G01X886223Y196352D02*
X885270Y195399D01*
G01X883679Y193808D02*
X882725Y192854D01*
G01X881134Y191263D02*
X880181Y190310D01*
G01X878590Y188719D02*
X877636Y187765D01*
G01X876045Y186174D02*
X875092Y185221D01*
G01X906850Y220565D02*
Y216979D01*
G01X905790Y217419D02*
Y221005D01*
G01Y217419D02*
Y221005D01*
G01X906850Y220565D02*
Y216979D01*
G01D02*
X905881Y216010D01*
G01X904290Y214419D02*
X903081Y213210D01*
G01X901490Y211619D02*
X900537Y210666D01*
G01X898946Y209075D02*
X897992Y208121D01*
G01X896401Y206530D02*
X895448Y205577D01*
G01X893857Y203986D02*
X892903Y203032D01*
G01X891312Y201441D02*
X890359Y200488D01*
G01X888768Y198897D02*
X887814Y197943D01*
G01X886223Y196352D02*
X885270Y195399D01*
G01X883679Y193808D02*
X882725Y192854D01*
G01X881134Y191263D02*
X880181Y190310D01*
G01X878590Y188719D02*
X877636Y187765D01*
G01X876045Y186174D02*
X875092Y185221D01*
G01X906850Y216979D02*
X905881Y216010D01*
G01X904290Y214419D02*
X903081Y213210D01*
G01X901490Y211619D02*
X900537Y210666D01*
G01X898946Y209075D02*
X897992Y208121D01*
G01X896401Y206530D02*
X895448Y205577D01*
G01X893857Y203986D02*
X892903Y203032D01*
G01X891312Y201441D02*
X890359Y200488D01*
G01X888768Y198897D02*
X887814Y197943D01*
G01X886223Y196352D02*
X885270Y195399D01*
G01X883679Y193808D02*
X882725Y192854D01*
G01X881134Y191263D02*
X880181Y190310D01*
G01X878590Y188719D02*
X877636Y187765D01*
G01X876045Y186174D02*
X875092Y185221D01*
G01X906850Y220565D02*
Y216979D01*
G01X905790Y217419D02*
Y221005D01*
G01X903280Y160602D02*
Y161951D01*
G01Y164201D02*
Y165549D01*
G01Y167799D02*
Y169148D01*
G01X902220Y169591D02*
X915137Y182508D01*
G01X903280Y169148D02*
X906022Y171890D01*
G01X902220Y169591D02*
X915137Y182508D01*
G01X906022Y171890D02*
X906658D01*
G01X902220Y169591D02*
X915137Y182508D01*
G01X907613Y173481D02*
X908566Y174434D01*
G01X902220Y169591D02*
X915137Y182508D01*
G01X908566Y174434D02*
X909202D01*
G01X902220Y169591D02*
X915137Y182508D01*
G01X910157Y176025D02*
X911111Y176979D01*
G01X902220Y169591D02*
X915137Y182508D01*
G01X902220Y169591D02*
X915137Y182508D01*
G01X902220Y169591D02*
X915137Y182508D01*
G01X902220Y169591D02*
X915137Y182508D01*
G01X919150Y181018D02*
X906022Y167890D01*
G01X907080Y167448D02*
X912576Y172944D01*
G01X919150Y181018D02*
X906022Y167890D01*
G01X919150Y181018D02*
X906022Y167890D01*
G01X919150Y181018D02*
X906022Y167890D01*
G01X919150Y181018D02*
X906022Y167890D01*
G01X919150Y181018D02*
X906022Y167890D01*
G01X919150Y181018D02*
X906022Y167890D01*
G01X903280Y160602D02*
Y161951D01*
G01Y164201D02*
Y165549D01*
G01Y167799D02*
Y169148D01*
G01D02*
X906022Y171890D01*
G01D02*
X906658D01*
G01X907613Y173481D02*
X908566Y174434D01*
G01D02*
X909202D01*
G01X910157Y176025D02*
X911111Y176979D01*
G01X902220Y169591D02*
X915137Y182508D01*
G01X903280Y160602D02*
Y161951D01*
G01Y164201D02*
Y165549D01*
G01Y167799D02*
Y169148D01*
G01X902220Y169591D02*
X915137Y182508D01*
G01X903280Y169148D02*
X906022Y171890D01*
G01X902220Y169591D02*
X915137Y182508D01*
G01X906022Y171890D02*
X906658D01*
G01X902220Y169591D02*
X915137Y182508D01*
G01X907613Y173481D02*
X908566Y174434D01*
G01X902220Y169591D02*
X915137Y182508D01*
G01X908566Y174434D02*
X909202D01*
G01X902220Y169591D02*
X915137Y182508D01*
G01X910157Y176025D02*
X911111Y176979D01*
G01X902220Y169591D02*
X915137Y182508D01*
G01X902220Y169591D02*
X915137Y182508D01*
G01X902220Y169591D02*
X915137Y182508D01*
G01X902220Y169591D02*
X915137Y182508D01*
G01X919150Y181018D02*
X906022Y167890D01*
G01X907080Y167448D02*
X912576Y172944D01*
G01X919150Y181018D02*
X906022Y167890D01*
G01X919150Y181018D02*
X906022Y167890D01*
G01X919150Y181018D02*
X906022Y167890D01*
G01X919150Y181018D02*
X906022Y167890D01*
G01X919150Y181018D02*
X906022Y167890D01*
G01X919150Y181018D02*
X906022Y167890D01*
G01X903280Y160602D02*
Y161951D01*
G01Y164201D02*
Y165549D01*
G01Y167799D02*
Y169148D01*
G01D02*
X906022Y171890D01*
G01D02*
X906658D01*
G01X907613Y173481D02*
X908566Y174434D01*
G01D02*
X909202D01*
G01X910157Y176025D02*
X911111Y176979D01*
G01X902220Y169591D02*
X915137Y182508D01*
G01X907080Y167448D02*
X912576Y172944D01*
G01X919150Y181018D02*
X906022Y167890D01*
G01X907080Y167448D02*
X912576Y172944D01*
G01X919150Y181018D02*
X906022Y167890D01*
G01X863361Y223310D02*
X865109D01*
G01X863801Y222250D02*
X865549D01*
G01X863361Y223310D02*
X865109D01*
G01D02*
X906039Y264240D01*
G01X865549Y222250D02*
X868312Y225013D01*
G01X865109Y223310D02*
X906039Y264240D01*
G01X869903Y226604D02*
X870856Y227557D01*
G01X865109Y223310D02*
X906039Y264240D01*
G01X872447Y229148D02*
X873401Y230102D01*
G01X865109Y223310D02*
X906039Y264240D01*
G01X874992Y231693D02*
X875945Y232646D01*
G01X865109Y223310D02*
X906039Y264240D01*
G01X877536Y234237D02*
X878490Y235191D01*
G01X865109Y223310D02*
X906039Y264240D01*
G01X880081Y236782D02*
X881034Y237735D01*
G01X865109Y223310D02*
X906039Y264240D01*
G01X882625Y239326D02*
X883579Y240280D01*
G01X865109Y223310D02*
X906039Y264240D01*
G01X885170Y241871D02*
X886123Y242824D01*
G01X865109Y223310D02*
X906039Y264240D01*
G01X887714Y244415D02*
X888668Y245369D01*
G01X865109Y223310D02*
X906039Y264240D01*
G01X890259Y246960D02*
X891212Y247913D01*
G01X865109Y223310D02*
X906039Y264240D01*
G01X892803Y249504D02*
X893757Y250458D01*
G01X865109Y223310D02*
X906039Y264240D01*
G01X895348Y252049D02*
X896301Y253002D01*
G01X865109Y223310D02*
X906039Y264240D01*
G01X897892Y254593D02*
X898846Y255547D01*
G01X865109Y223310D02*
X906039Y264240D01*
G01X900437Y257138D02*
X901390Y258091D01*
G01X865109Y223310D02*
X906039Y264240D01*
G01X902981Y259682D02*
X903935Y260636D01*
G01X865109Y223310D02*
X906039Y264240D01*
G01X905526Y262227D02*
X906479Y263180D01*
G01X906039Y264240D02*
X908000D01*
G01X906479Y263180D02*
X908000D01*
G01X863361Y223310D02*
X865109D01*
G01X863801Y222250D02*
X865549D01*
G01X863361Y223310D02*
X865109D01*
G01D02*
X906039Y264240D01*
G01X865549Y222250D02*
X868312Y225013D01*
G01X865109Y223310D02*
X906039Y264240D01*
G01X869903Y226604D02*
X870856Y227557D01*
G01X865109Y223310D02*
X906039Y264240D01*
G01X872447Y229148D02*
X873401Y230102D01*
G01X865109Y223310D02*
X906039Y264240D01*
G01X874992Y231693D02*
X875945Y232646D01*
G01X865109Y223310D02*
X906039Y264240D01*
G01X877536Y234237D02*
X878490Y235191D01*
G01X865109Y223310D02*
X906039Y264240D01*
G01X880081Y236782D02*
X881034Y237735D01*
G01X865109Y223310D02*
X906039Y264240D01*
G01X882625Y239326D02*
X883579Y240280D01*
G01X865109Y223310D02*
X906039Y264240D01*
G01X885170Y241871D02*
X886123Y242824D01*
G01X865109Y223310D02*
X906039Y264240D01*
G01X887714Y244415D02*
X888668Y245369D01*
G01X865109Y223310D02*
X906039Y264240D01*
G01X890259Y246960D02*
X891212Y247913D01*
G01X865109Y223310D02*
X906039Y264240D01*
G01X892803Y249504D02*
X893757Y250458D01*
G01X865109Y223310D02*
X906039Y264240D01*
G01X895348Y252049D02*
X896301Y253002D01*
G01X865109Y223310D02*
X906039Y264240D01*
G01X897892Y254593D02*
X898846Y255547D01*
G01X865109Y223310D02*
X906039Y264240D01*
G01X900437Y257138D02*
X901390Y258091D01*
G01X865109Y223310D02*
X906039Y264240D01*
G01X902981Y259682D02*
X903935Y260636D01*
G01X865109Y223310D02*
X906039Y264240D01*
G01X905526Y262227D02*
X906479Y263180D01*
G01X906039Y264240D02*
X908000D01*
G01X906479Y263180D02*
X908000D01*
G01X863801Y222250D02*
X865549D01*
G01X863801D02*
X865549D01*
G01D02*
X868312Y225013D01*
G01X863361Y223310D02*
X865109D01*
G01X865549Y222250D02*
X868312Y225013D01*
G01X869903Y226604D02*
X870856Y227557D01*
G01X872447Y229148D02*
X873401Y230102D01*
G01X874992Y231693D02*
X875945Y232646D01*
G01X877536Y234237D02*
X878490Y235191D01*
G01X880081Y236782D02*
X881034Y237735D01*
G01X882625Y239326D02*
X883579Y240280D01*
G01X885170Y241871D02*
X886123Y242824D01*
G01X887714Y244415D02*
X888668Y245369D01*
G01X890259Y246960D02*
X891212Y247913D01*
G01X892803Y249504D02*
X893757Y250458D01*
G01X895348Y252049D02*
X896301Y253002D01*
G01X897892Y254593D02*
X898846Y255547D01*
G01X900437Y257138D02*
X901390Y258091D01*
G01X902981Y259682D02*
X903935Y260636D01*
G01X905526Y262227D02*
X906479Y263180D01*
G01X865109Y223310D02*
X906039Y264240D01*
G01X906479Y263180D02*
X908000D01*
G01X906039Y264240D02*
X908000D01*
G01X863801Y222250D02*
X865549D01*
G01X863801D02*
X865549D01*
G01D02*
X868312Y225013D01*
G01X863361Y223310D02*
X865109D01*
G01X865549Y222250D02*
X868312Y225013D01*
G01X869903Y226604D02*
X870856Y227557D01*
G01X872447Y229148D02*
X873401Y230102D01*
G01X874992Y231693D02*
X875945Y232646D01*
G01X877536Y234237D02*
X878490Y235191D01*
G01X880081Y236782D02*
X881034Y237735D01*
G01X882625Y239326D02*
X883579Y240280D01*
G01X885170Y241871D02*
X886123Y242824D01*
G01X887714Y244415D02*
X888668Y245369D01*
G01X890259Y246960D02*
X891212Y247913D01*
G01X892803Y249504D02*
X893757Y250458D01*
G01X895348Y252049D02*
X896301Y253002D01*
G01X897892Y254593D02*
X898846Y255547D01*
G01X900437Y257138D02*
X901390Y258091D01*
G01X902981Y259682D02*
X903935Y260636D01*
G01X905526Y262227D02*
X906479Y263180D01*
G01X865109Y223310D02*
X906039Y264240D01*
G01X906479Y263180D02*
X908000D01*
G01X906039Y264240D02*
X908000D01*
G01X911363Y260340D02*
X907310D01*
G01X911363Y259280D02*
X907750D01*
G01X907310Y260340D02*
X892640Y245670D01*
G01X907750Y259280D02*
X906797Y258327D01*
G01X907310Y260340D02*
X892640Y245670D01*
G01X905842Y256736D02*
X905206D01*
G01X907310Y260340D02*
X892640Y245670D01*
G01X905206Y256736D02*
X904252Y255782D01*
G01X907310Y260340D02*
X892640Y245670D01*
G01X903297Y254191D02*
X902661D01*
G01X907310Y260340D02*
X892640Y245670D01*
G01X902661Y254191D02*
X901708Y253238D01*
G01X907310Y260340D02*
X892640Y245670D01*
G01X900753Y251647D02*
X900117D01*
G01X907310Y260340D02*
X892640Y245670D01*
G01X900117Y251647D02*
X899164Y250694D01*
G01X907310Y260340D02*
X892640Y245670D01*
G01X898209Y249103D02*
X897573D01*
G01X907310Y260340D02*
X892640Y245670D01*
G01X897573Y249103D02*
X896619Y248149D01*
G01X907310Y260340D02*
X892640Y245670D01*
G01X895664Y246558D02*
X895028D01*
G01X907310Y260340D02*
X892640Y245670D01*
G01X895028Y246558D02*
X893700Y245230D01*
G01X892640Y245670D02*
Y244340D01*
G01X893700Y245230D02*
Y243900D01*
G01X892640Y244340D02*
X867760Y219460D01*
G01X893700Y243900D02*
X868200Y218400D01*
G01X867760Y219460D02*
X865110D01*
G01X868200Y218400D02*
X865550D01*
G01X905790Y221005D02*
X909142Y224357D01*
G01X909892Y223607D02*
X906850Y220565D01*
G01X909892Y223607D02*
X906850Y220565D01*
G01X905790Y221005D02*
X909142Y224357D01*
G01X911363Y260340D02*
X907310D01*
G01X911363Y259280D02*
X907750D01*
G01X907310Y260340D02*
X892640Y245670D01*
G01X907750Y259280D02*
X906797Y258327D01*
G01X907310Y260340D02*
X892640Y245670D01*
G01X905842Y256736D02*
X905206D01*
G01X907310Y260340D02*
X892640Y245670D01*
G01X905206Y256736D02*
X904252Y255782D01*
G01X907310Y260340D02*
X892640Y245670D01*
G01X903297Y254191D02*
X902661D01*
G01X907310Y260340D02*
X892640Y245670D01*
G01X902661Y254191D02*
X901708Y253238D01*
G01X907310Y260340D02*
X892640Y245670D01*
G01X900753Y251647D02*
X900117D01*
G01X907310Y260340D02*
X892640Y245670D01*
G01X900117Y251647D02*
X899164Y250694D01*
G01X907310Y260340D02*
X892640Y245670D01*
G01X898209Y249103D02*
X897573D01*
G01X907310Y260340D02*
X892640Y245670D01*
G01X897573Y249103D02*
X896619Y248149D01*
G01X907310Y260340D02*
X892640Y245670D01*
G01X895664Y246558D02*
X895028D01*
G01X907310Y260340D02*
X892640Y245670D01*
G01X895028Y246558D02*
X893700Y245230D01*
G01X892640Y245670D02*
Y244340D01*
G01X893700Y245230D02*
Y243900D01*
G01X892640Y244340D02*
X867760Y219460D01*
G01X893700Y243900D02*
X868200Y218400D01*
G01X867760Y219460D02*
X865110D01*
G01X868200Y218400D02*
X865550D01*
G01X905790Y221005D02*
X909142Y224357D01*
G01X909892Y223607D02*
X906850Y220565D01*
G01X911363Y259280D02*
X907750D01*
G01X911363Y260340D02*
X907310D01*
G01X907750Y259280D02*
X906797Y258327D01*
G01X905842Y256736D02*
X905206D01*
G01D02*
X904252Y255782D01*
G01X903297Y254191D02*
X902661D01*
G01D02*
X901708Y253238D01*
G01X900753Y251647D02*
X900117D01*
G01D02*
X899164Y250694D01*
G01X898209Y249103D02*
X897573D01*
G01D02*
X896619Y248149D01*
G01X895664Y246558D02*
X895028D01*
G01D02*
X893700Y245230D01*
G01X907310Y260340D02*
X892640Y245670D01*
G01X893700Y245230D02*
Y243900D01*
G01X892640Y245670D02*
Y244340D01*
G01X893700Y243900D02*
X868200Y218400D01*
G01X892640Y244340D02*
X867760Y219460D01*
G01X868200Y218400D02*
X865550D01*
G01X867760Y219460D02*
X865110D01*
G01X911363Y259280D02*
X907750D01*
G01X911363Y260340D02*
X907310D01*
G01X907750Y259280D02*
X906797Y258327D01*
G01X905842Y256736D02*
X905206D01*
G01D02*
X904252Y255782D01*
G01X903297Y254191D02*
X902661D01*
G01D02*
X901708Y253238D01*
G01X900753Y251647D02*
X900117D01*
G01D02*
X899164Y250694D01*
G01X898209Y249103D02*
X897573D01*
G01D02*
X896619Y248149D01*
G01X895664Y246558D02*
X895028D01*
G01D02*
X893700Y245230D01*
G01X907310Y260340D02*
X892640Y245670D01*
G01X893700Y245230D02*
Y243900D01*
G01X892640Y245670D02*
Y244340D01*
G01X893700Y243900D02*
X868200Y218400D01*
G01X892640Y244340D02*
X867760Y219460D01*
G01X868200Y218400D02*
X865550D01*
G01X867760Y219460D02*
X865110D01*
G01X909892Y223607D02*
X906850Y220565D01*
G01X905790Y221005D02*
X909142Y224357D01*
G01X901350Y332920D02*
X910113D01*
G01Y333980D02*
X901790D01*
G01X867521Y366749D02*
X901350Y332920D01*
G01X901790Y333980D02*
X868581Y367189D01*
G01X901790Y333980D02*
X868581Y367189D01*
G01X867521Y366749D02*
X901350Y332920D01*
G01X910113Y333980D02*
X901790D01*
G01X901350Y332920D02*
X910113D01*
G01X901350D02*
X910113D01*
G01Y333980D02*
X901790D01*
G01X867521Y366749D02*
X901350Y332920D01*
G01X901790Y333980D02*
X868581Y367189D01*
G01X901790Y333980D02*
X868581Y367189D01*
G01X867521Y366749D02*
X901350Y332920D01*
G01X910113Y333980D02*
X901790D01*
G01X901350Y332920D02*
X910113D01*
G01X902811Y337989D02*
X871526Y369274D01*
G01X870466Y368834D02*
X902371Y336929D01*
G01X904992Y337989D02*
X902811D01*
G01X902371Y336929D02*
X904992D01*
G01X902371D02*
X904992D01*
G01Y337989D02*
X902811D01*
G01X870466Y368834D02*
X902371Y336929D01*
G01X902811Y337989D02*
X871526Y369274D01*
G01X902811Y337989D02*
X871526Y369274D01*
G01X870466Y368834D02*
X902371Y336929D01*
G01X904992Y337989D02*
X902811D01*
G01X902371Y336929D02*
X904992D01*
G01X902371D02*
X904992D01*
G01Y337989D02*
X902811D01*
G01X870466Y368834D02*
X902371Y336929D01*
G01X902811Y337989D02*
X871526Y369274D01*
G01X867521Y382278D02*
Y366749D01*
G01X868581Y367189D02*
Y382718D01*
G01Y367189D02*
Y382718D01*
G01X867521Y382278D02*
Y366749D01*
G01Y382278D02*
Y366749D01*
G01X868581Y367189D02*
Y382718D01*
G01Y367189D02*
Y382718D01*
G01X867521Y382278D02*
Y366749D01*
G01X871526Y369274D02*
Y383974D01*
G01X870466Y383534D02*
Y368834D01*
G01X891400Y384535D02*
X911261Y364674D01*
G01X912012Y365426D02*
X902235Y375202D01*
G01X891400Y384535D02*
X911261Y364674D01*
G01X902235Y375202D02*
X902233D01*
G01X891400Y384535D02*
X911261Y364674D01*
G01X902233Y375202D02*
X892460Y384975D01*
G01X891400Y390004D02*
Y384535D01*
G01X892460Y384975D02*
Y390444D01*
G01X871200Y410204D02*
X891400Y390004D01*
G01X892460Y390444D02*
X872260Y410644D01*
G01X875760Y412041D02*
X895960Y391841D01*
G01X874700Y411601D02*
X894900Y391401D01*
G01X895960Y391841D02*
Y386865D01*
G01X894900Y391401D02*
Y386423D01*
G01X895960Y386865D02*
X899260Y383565D01*
G01Y383564D02*
X910355Y372469D01*
G01X894900Y386423D02*
X909605Y371718D01*
G01X870466Y383534D02*
Y368834D01*
G01X871526Y369274D02*
Y383974D01*
G01X892460Y390444D02*
X872260Y410644D01*
G01X871200Y410204D02*
X891400Y390004D01*
G01X892460Y384975D02*
Y390444D01*
G01X891400Y390004D02*
Y384535D01*
G01X912012Y365426D02*
X902235Y375202D01*
G01D02*
X902233D01*
G01D02*
X892460Y384975D01*
G01X891400Y384535D02*
X911261Y364674D01*
G01X874700Y411601D02*
X894900Y391401D01*
G01X875760Y412041D02*
X895960Y391841D01*
G01X894900Y391401D02*
Y386423D01*
G01X895960Y391841D02*
Y386865D01*
G01X894900Y386423D02*
X909605Y371718D01*
G01X895960Y386865D02*
X899260Y383565D01*
G01X894900Y386423D02*
X909605Y371718D01*
G01X899260Y383564D02*
X910355Y372469D01*
G01X871526Y369274D02*
Y383974D01*
G01X870466Y383534D02*
Y368834D01*
G01X891400Y384535D02*
X911261Y364674D01*
G01X912012Y365426D02*
X902235Y375202D01*
G01X891400Y384535D02*
X911261Y364674D01*
G01X902235Y375202D02*
X902233D01*
G01X891400Y384535D02*
X911261Y364674D01*
G01X902233Y375202D02*
X892460Y384975D01*
G01X891400Y390004D02*
Y384535D01*
G01X892460Y384975D02*
Y390444D01*
G01X871200Y410204D02*
X891400Y390004D01*
G01X892460Y390444D02*
X872260Y410644D01*
G01X875760Y412041D02*
X895960Y391841D01*
G01X874700Y411601D02*
X894900Y391401D01*
G01X895960Y391841D02*
Y386865D01*
G01X894900Y391401D02*
Y386423D01*
G01X895960Y386865D02*
X899260Y383565D01*
G01Y383564D02*
X910355Y372469D01*
G01X894900Y386423D02*
X909605Y371718D01*
G01X870466Y383534D02*
Y368834D01*
G01X871526Y369274D02*
Y383974D01*
G01X892460Y390444D02*
X872260Y410644D01*
G01X871200Y410204D02*
X891400Y390004D01*
G01X892460Y384975D02*
Y390444D01*
G01X891400Y390004D02*
Y384535D01*
G01X912012Y365426D02*
X902235Y375202D01*
G01D02*
X902233D01*
G01D02*
X892460Y384975D01*
G01X891400Y384535D02*
X911261Y364674D01*
G01X874700Y411601D02*
X894900Y391401D01*
G01X875760Y412041D02*
X895960Y391841D01*
G01X894900Y391401D02*
Y386423D01*
G01X895960Y391841D02*
Y386865D01*
G01X894900Y386423D02*
X909605Y371718D01*
G01X895960Y386865D02*
X899260Y383565D01*
G01X894900Y386423D02*
X909605Y371718D01*
G01X899260Y383564D02*
X910355Y372469D01*
G01X871200Y419868D02*
Y410204D01*
G01X872260Y410644D02*
Y420308D01*
G01X849357Y456162D02*
X851468D01*
G01X849800Y455102D02*
X851025D01*
G01X851468Y456162D02*
X853861Y453769D01*
G01X851025Y455102D02*
X852801Y453326D01*
G01X853861Y453769D02*
Y451659D01*
G01X852801Y453326D02*
Y452102D01*
G01X853861Y451659D02*
X850799Y448598D01*
G01X852801Y452102D02*
X849739Y449041D01*
G01X850799Y448598D02*
Y447372D01*
G01X849739Y449041D02*
Y446929D01*
G01X850799Y447372D02*
X852570Y445601D01*
G01D02*
X853797D01*
G01X849739Y446929D02*
X852127Y444541D01*
G01X852570Y445601D02*
X853797D01*
G01X852127Y444541D02*
X854237D01*
G01X852570Y445601D02*
X853797D01*
G01D02*
X856859Y448662D01*
G01X854237Y444541D02*
X857299Y447602D01*
G01X853797Y445601D02*
X856859Y448662D01*
G01D02*
X858968D01*
G01X857299Y447602D02*
X858525D01*
G01X858968Y448662D02*
X861361Y446269D01*
G01X858525Y447602D02*
X860301Y445826D01*
G01X861361Y446269D02*
Y444159D01*
G01X860301Y445826D02*
Y444602D01*
G01X861361Y444159D02*
X859795Y442594D01*
G01X860301Y444602D02*
X859795Y444096D01*
G01X861361Y444159D02*
X859795Y442594D01*
G01D02*
X858299Y441098D01*
G01X859795Y444096D02*
X857239Y441541D01*
G01X858299Y441098D02*
Y439869D01*
G01X857239Y441541D02*
Y439429D01*
G01X858299Y439869D02*
X875760Y422408D01*
G01X857239Y439429D02*
X874700Y421968D01*
G01X875760Y422408D02*
Y412041D01*
G01X874700Y421968D02*
Y411601D01*
G01X872260Y410644D02*
Y420308D01*
G01X871200Y419868D02*
Y410204D01*
G01X849800Y455102D02*
X851025D01*
G01X849357Y456162D02*
X851468D01*
G01X851025Y455102D02*
X852801Y453326D01*
G01X851468Y456162D02*
X853861Y453769D01*
G01X852801Y453326D02*
Y452102D01*
G01X853861Y453769D02*
Y451659D01*
G01X852801Y452102D02*
X849739Y449041D01*
G01X853861Y451659D02*
X850799Y448598D01*
G01X849739Y449041D02*
Y446929D01*
G01X850799Y448598D02*
Y447372D01*
G01X849739Y446929D02*
X852127Y444541D01*
G01X850799Y447372D02*
X852570Y445601D01*
G01X849739Y446929D02*
X852127Y444541D01*
G01D02*
X854237D01*
G01D02*
X857299Y447602D01*
G01X852570Y445601D02*
X853797D01*
G01X854237Y444541D02*
X857299Y447602D01*
G01D02*
X858525D01*
G01X853797Y445601D02*
X856859Y448662D01*
G01X857299Y447602D02*
X858525D01*
G01X856859Y448662D02*
X858968D01*
G01X858525Y447602D02*
X860301Y445826D01*
G01X858968Y448662D02*
X861361Y446269D01*
G01X860301Y445826D02*
Y444602D01*
G01X861361Y446269D02*
Y444159D01*
G01X860301Y444602D02*
X859795Y444096D01*
G01D02*
X857239Y441541D01*
G01X861361Y444159D02*
X859795Y442594D01*
G01Y444096D02*
X857239Y441541D01*
G01X859795Y442594D02*
X858299Y441098D01*
G01X857239Y441541D02*
Y439429D01*
G01X858299Y441098D02*
Y439869D01*
G01X857239Y439429D02*
X874700Y421968D01*
G01X858299Y439869D02*
X875760Y422408D01*
G01X874700Y421968D02*
Y411601D01*
G01X875760Y422408D02*
Y412041D01*
G01X871200Y419868D02*
Y410204D01*
G01X872260Y410644D02*
Y420308D01*
G01X849357Y456162D02*
X851468D01*
G01X849800Y455102D02*
X851025D01*
G01X851468Y456162D02*
X853861Y453769D01*
G01X851025Y455102D02*
X852801Y453326D01*
G01X853861Y453769D02*
Y451659D01*
G01X852801Y453326D02*
Y452102D01*
G01X853861Y451659D02*
X850799Y448598D01*
G01X852801Y452102D02*
X849739Y449041D01*
G01X850799Y448598D02*
Y447372D01*
G01X849739Y449041D02*
Y446929D01*
G01X850799Y447372D02*
X852570Y445601D01*
G01D02*
X853797D01*
G01X849739Y446929D02*
X852127Y444541D01*
G01X852570Y445601D02*
X853797D01*
G01X852127Y444541D02*
X854237D01*
G01X852570Y445601D02*
X853797D01*
G01D02*
X856859Y448662D01*
G01X854237Y444541D02*
X857299Y447602D01*
G01X853797Y445601D02*
X856859Y448662D01*
G01D02*
X858968D01*
G01X857299Y447602D02*
X858525D01*
G01X858968Y448662D02*
X861361Y446269D01*
G01X858525Y447602D02*
X860301Y445826D01*
G01X861361Y446269D02*
Y444159D01*
G01X860301Y445826D02*
Y444602D01*
G01X861361Y444159D02*
X859795Y442594D01*
G01X860301Y444602D02*
X859795Y444096D01*
G01X861361Y444159D02*
X859795Y442594D01*
G01D02*
X858299Y441098D01*
G01X859795Y444096D02*
X857239Y441541D01*
G01X858299Y441098D02*
Y439869D01*
G01X857239Y441541D02*
Y439429D01*
G01X858299Y439869D02*
X875760Y422408D01*
G01X857239Y439429D02*
X874700Y421968D01*
G01X875760Y422408D02*
Y412041D01*
G01X874700Y421968D02*
Y411601D01*
G01X872260Y410644D02*
Y420308D01*
G01X871200Y419868D02*
Y410204D01*
G01X849800Y455102D02*
X851025D01*
G01X849357Y456162D02*
X851468D01*
G01X851025Y455102D02*
X852801Y453326D01*
G01X851468Y456162D02*
X853861Y453769D01*
G01X852801Y453326D02*
Y452102D01*
G01X853861Y453769D02*
Y451659D01*
G01X852801Y452102D02*
X849739Y449041D01*
G01X853861Y451659D02*
X850799Y448598D01*
G01X849739Y449041D02*
Y446929D01*
G01X850799Y448598D02*
Y447372D01*
G01X849739Y446929D02*
X852127Y444541D01*
G01X850799Y447372D02*
X852570Y445601D01*
G01X849739Y446929D02*
X852127Y444541D01*
G01D02*
X854237D01*
G01D02*
X857299Y447602D01*
G01X852570Y445601D02*
X853797D01*
G01X854237Y444541D02*
X857299Y447602D01*
G01D02*
X858525D01*
G01X853797Y445601D02*
X856859Y448662D01*
G01X857299Y447602D02*
X858525D01*
G01X856859Y448662D02*
X858968D01*
G01X858525Y447602D02*
X860301Y445826D01*
G01X858968Y448662D02*
X861361Y446269D01*
G01X860301Y445826D02*
Y444602D01*
G01X861361Y446269D02*
Y444159D01*
G01X860301Y444602D02*
X859795Y444096D01*
G01D02*
X857239Y441541D01*
G01X861361Y444159D02*
X859795Y442594D01*
G01Y444096D02*
X857239Y441541D01*
G01X859795Y442594D02*
X858299Y441098D01*
G01X857239Y441541D02*
Y439429D01*
G01X858299Y441098D02*
Y439869D01*
G01X857239Y439429D02*
X874700Y421968D01*
G01X858299Y439869D02*
X875760Y422408D01*
G01X874700Y421968D02*
Y411601D01*
G01X875760Y422408D02*
Y412041D01*
G01X903420Y430109D02*
X916400Y417129D01*
G01X917460Y417572D02*
X904480Y430552D01*
G01X903420Y448889D02*
Y430109D01*
G01X904480Y430552D02*
Y449329D01*
G01X866720Y485589D02*
X903420Y448889D01*
G01X904480Y449329D02*
X867780Y486029D01*
G01X896214Y468009D02*
Y463131D01*
G01X895154Y467569D02*
Y462691D01*
G01X896214Y463131D02*
X908280Y451065D01*
G01X895154Y462691D02*
X907220Y450625D01*
G01X908280Y451065D02*
Y432292D01*
G01X907220Y450625D02*
Y431849D01*
G01X908280Y432292D02*
X922617Y417955D01*
G01X907223Y431849D02*
X921557Y417515D01*
G01X904480Y449329D02*
X867780Y486029D01*
G01X866720Y485589D02*
X903420Y448889D01*
G01X904480Y430552D02*
Y449329D01*
G01X903420Y448889D02*
Y430109D01*
G01X917460Y417572D02*
X904480Y430552D01*
G01X903420Y430109D02*
X916400Y417129D01*
G01X895154Y467569D02*
Y462691D01*
G01X896214Y468009D02*
Y463131D01*
G01X895154Y462691D02*
X907220Y450625D01*
G01X896214Y463131D02*
X908280Y451065D01*
G01X907220Y450625D02*
Y431849D01*
G01X908280Y451065D02*
Y432292D01*
G01X907223Y431849D02*
X921557Y417515D01*
G01X908280Y432292D02*
X922617Y417955D01*
G01X903420Y430109D02*
X916400Y417129D01*
G01X917460Y417572D02*
X904480Y430552D01*
G01X903420Y448889D02*
Y430109D01*
G01X904480Y430552D02*
Y449329D01*
G01X866720Y485589D02*
X903420Y448889D01*
G01X904480Y449329D02*
X867780Y486029D01*
G01X896214Y468009D02*
Y463131D01*
G01X895154Y467569D02*
Y462691D01*
G01X896214Y463131D02*
X908280Y451065D01*
G01X895154Y462691D02*
X907220Y450625D01*
G01X908280Y451065D02*
Y432292D01*
G01X907220Y450625D02*
Y431849D01*
G01X908280Y432292D02*
X922617Y417955D01*
G01X907223Y431849D02*
X921557Y417515D01*
G01X904480Y449329D02*
X867780Y486029D01*
G01X866720Y485589D02*
X903420Y448889D01*
G01X904480Y430552D02*
Y449329D01*
G01X903420Y448889D02*
Y430109D01*
G01X917460Y417572D02*
X904480Y430552D01*
G01X903420Y430109D02*
X916400Y417129D01*
G01X895154Y467569D02*
Y462691D01*
G01X896214Y468009D02*
Y463131D01*
G01X895154Y462691D02*
X907220Y450625D01*
G01X896214Y463131D02*
X908280Y451065D01*
G01X907220Y450625D02*
Y431849D01*
G01X908280Y451065D02*
Y432292D01*
G01X907223Y431849D02*
X921557Y417515D01*
G01X908280Y432292D02*
X922617Y417955D01*
G01X866720Y503609D02*
Y485589D01*
G01X867780Y486029D02*
Y504049D01*
G01X862030Y508299D02*
X866720Y503609D01*
G01X867780Y504049D02*
X863090Y508739D01*
G01X862030Y541494D02*
Y508299D01*
G01X863090Y508739D02*
Y550020D01*
G01X868190Y550235D02*
Y509677D01*
G01Y550235D02*
Y509677D01*
G01Y550235D02*
Y509677D01*
G01Y550235D02*
Y509677D01*
G01Y550235D02*
Y509677D01*
G01Y550235D02*
Y509677D01*
G01Y550235D02*
Y509677D01*
G01X867130Y525467D02*
Y524467D01*
G01X868190Y550235D02*
Y509677D01*
G01X867130Y522227D02*
Y521227D01*
G01X868190Y550235D02*
Y509677D01*
G01X867130Y518987D02*
Y517724D01*
G01X868190Y550235D02*
Y509677D01*
G01X867130Y515936D02*
Y512499D01*
G01X868190Y550235D02*
Y509677D01*
G01X867130Y510553D02*
Y509237D01*
G01X868190Y509677D02*
X871686Y506181D01*
G01X867130Y509237D02*
X867882Y508485D01*
G01X868190Y509677D02*
X871686Y506181D01*
G01X868589Y506900D02*
X869467D01*
G01X868190Y509677D02*
X871686Y506181D01*
G01X869467Y506900D02*
X870626Y505741D01*
G01X871686Y506181D02*
Y487659D01*
G01X870626Y505741D02*
Y504476D01*
G01X871686Y506181D02*
Y487659D01*
G01X870626Y502236D02*
Y501236D01*
G01X871686Y506181D02*
Y487659D01*
G01X870626Y498996D02*
Y497996D01*
G01X871686Y506181D02*
Y487659D01*
G01X870626Y495756D02*
Y494756D01*
G01X871686Y506181D02*
Y487659D01*
G01X870626Y492516D02*
Y487219D01*
G01X871686Y487659D02*
X877692Y481653D01*
G01D02*
X878258D01*
G01X879553Y479792D02*
X881985Y477360D01*
G01X870626Y487219D02*
X881545Y476300D01*
G01X881985Y477360D02*
X884166D01*
G01X881545Y476300D02*
X884606D01*
G01X881985Y477360D02*
X884166D01*
G01D02*
X885003Y478197D01*
G01X884606Y476300D02*
X885443Y477137D01*
G01X884166Y477360D02*
X885003Y478197D01*
G01D02*
X887110D01*
G01X885443Y477137D02*
X886667D01*
G01X887110Y478197D02*
X889503Y475804D01*
G01X886667Y477137D02*
X888443Y475361D01*
G01X889503Y475804D02*
Y473693D01*
G01X888443Y475361D02*
Y474136D01*
G01X889503Y473693D02*
X888193Y472383D01*
G01X888443Y474136D02*
X887133Y472826D01*
G01X888193Y472383D02*
Y471155D01*
G01X887133Y472826D02*
Y470712D01*
G01X888193Y471155D02*
X889963Y469385D01*
G01D02*
X891188D01*
G01X887133Y470712D02*
X889520Y468325D01*
G01X889963Y469385D02*
X891188D01*
G01X889520Y468325D02*
X891628D01*
G01X891188Y469385D02*
X891950Y470147D01*
G01X891628Y468325D02*
X892390Y469087D01*
G01X891188Y469385D02*
X891950Y470147D01*
G01D02*
X894076D01*
G01X892390Y469087D02*
X893636D01*
G01X894076Y470147D02*
X896214Y468009D01*
G01X893636Y469087D02*
X895154Y467569D01*
G01X863090Y508739D02*
Y550020D01*
G01Y508739D02*
Y550020D01*
G01Y508739D02*
Y550020D01*
G01X862030Y541494D02*
Y508299D01*
G01X867780Y504049D02*
X863090Y508739D01*
G01X862030Y508299D02*
X866720Y503609D01*
G01X867780Y486029D02*
Y504049D01*
G01X866720Y503609D02*
Y485589D01*
G01X867130Y525467D02*
Y524467D01*
G01Y522227D02*
Y521227D01*
G01Y518987D02*
Y517724D01*
G01Y515936D02*
Y512499D01*
G01Y510553D02*
Y509237D01*
G01X868190Y550235D02*
Y509677D01*
G01X867130Y509237D02*
X867882Y508485D01*
G01X868589Y506900D02*
X869467D01*
G01D02*
X870626Y505741D01*
G01X868190Y509677D02*
X871686Y506181D01*
G01X870626Y505741D02*
Y504476D01*
G01Y502236D02*
Y501236D01*
G01Y498996D02*
Y497996D01*
G01Y495756D02*
Y494756D01*
G01Y492516D02*
Y487219D01*
G01X871686Y506181D02*
Y487659D01*
G01X870626Y487219D02*
X881545Y476300D01*
G01X871686Y487659D02*
X877692Y481653D01*
G01X870626Y487219D02*
X881545Y476300D01*
G01X877692Y481653D02*
X878258D01*
G01X870626Y487219D02*
X881545Y476300D01*
G01X879553Y479792D02*
X881985Y477360D01*
G01X881545Y476300D02*
X884606D01*
G01D02*
X885443Y477137D01*
G01X881985Y477360D02*
X884166D01*
G01X884606Y476300D02*
X885443Y477137D01*
G01D02*
X886667D01*
G01X884166Y477360D02*
X885003Y478197D01*
G01X885443Y477137D02*
X886667D01*
G01X885003Y478197D02*
X887110D01*
G01X886667Y477137D02*
X888443Y475361D01*
G01X887110Y478197D02*
X889503Y475804D01*
G01X888443Y475361D02*
Y474136D01*
G01X889503Y475804D02*
Y473693D01*
G01X888443Y474136D02*
X887133Y472826D01*
G01X889503Y473693D02*
X888193Y472383D01*
G01X887133Y472826D02*
Y470712D01*
G01X888193Y472383D02*
Y471155D01*
G01X887133Y470712D02*
X889520Y468325D01*
G01X888193Y471155D02*
X889963Y469385D01*
G01X887133Y470712D02*
X889520Y468325D01*
G01D02*
X891628D01*
G01X889963Y469385D02*
X891188D01*
G01X891628Y468325D02*
X892390Y469087D01*
G01D02*
X893636D01*
G01X891188Y469385D02*
X891950Y470147D01*
G01X892390Y469087D02*
X893636D01*
G01X891950Y470147D02*
X894076D01*
G01X893636Y469087D02*
X895154Y467569D01*
G01X894076Y470147D02*
X896214Y468009D01*
G01X895094Y498841D02*
X898841Y507888D01*
G01X897600Y502122D02*
X899901Y507677D01*
G01X898841Y507888D02*
Y549459D01*
G01X899901Y507677D02*
Y549899D01*
G01X903700Y501200D02*
X905001Y502501D01*
G01X900194Y499194D02*
X903941Y502941D01*
G01X905001Y502501D02*
Y521500D01*
G01X903941Y502941D02*
Y521060D01*
G01X905001Y521500D02*
X903500Y523001D01*
G01X903941Y521060D02*
X902440Y522561D01*
G01X903500Y523001D02*
Y525200D01*
G01X902440Y522561D02*
Y525640D01*
G01X903500Y525200D02*
X905001Y526701D01*
G01X902440Y525640D02*
X903941Y527141D01*
G01X897600Y502122D02*
X899901Y507677D01*
G01X895094Y498841D02*
X898841Y507888D01*
G01X899901Y507677D02*
Y549899D01*
G01X898841Y507888D02*
Y549459D01*
G01X900194Y499194D02*
X903941Y502941D01*
G01X903700Y501200D02*
X905001Y502501D01*
G01X903941Y502941D02*
Y521060D01*
G01X905001Y502501D02*
Y521500D01*
G01X903941Y521060D02*
X902440Y522561D01*
G01X905001Y521500D02*
X903500Y523001D01*
G01X902440Y522561D02*
Y525640D01*
G01X903500Y523001D02*
Y525200D01*
G01X902440Y525640D02*
X903941Y527141D01*
G01X903500Y525200D02*
X905001Y526701D01*
G01X866720Y503609D02*
Y485589D01*
G01X867780Y486029D02*
Y504049D01*
G01X862030Y508299D02*
X866720Y503609D01*
G01X867780Y504049D02*
X863090Y508739D01*
G01X862030Y541494D02*
Y508299D01*
G01X863090Y508739D02*
Y550020D01*
G01X895094Y498841D02*
X898841Y507888D01*
G01X897600Y502122D02*
X899901Y507677D01*
G01X898841Y507888D02*
Y549459D01*
G01X899901Y507677D02*
Y549899D01*
G01X868190Y550235D02*
Y509677D01*
G01Y550235D02*
Y509677D01*
G01Y550235D02*
Y509677D01*
G01Y550235D02*
Y509677D01*
G01Y550235D02*
Y509677D01*
G01Y550235D02*
Y509677D01*
G01Y550235D02*
Y509677D01*
G01X867130Y525467D02*
Y524467D01*
G01X868190Y550235D02*
Y509677D01*
G01X867130Y522227D02*
Y521227D01*
G01X868190Y550235D02*
Y509677D01*
G01X867130Y518987D02*
Y517724D01*
G01X868190Y550235D02*
Y509677D01*
G01X867130Y515936D02*
Y512499D01*
G01X868190Y550235D02*
Y509677D01*
G01X867130Y510553D02*
Y509237D01*
G01X868190Y509677D02*
X871686Y506181D01*
G01X867130Y509237D02*
X867882Y508485D01*
G01X868190Y509677D02*
X871686Y506181D01*
G01X868589Y506900D02*
X869467D01*
G01X868190Y509677D02*
X871686Y506181D01*
G01X869467Y506900D02*
X870626Y505741D01*
G01X871686Y506181D02*
Y487659D01*
G01X870626Y505741D02*
Y504476D01*
G01X871686Y506181D02*
Y487659D01*
G01X870626Y502236D02*
Y501236D01*
G01X871686Y506181D02*
Y487659D01*
G01X870626Y498996D02*
Y497996D01*
G01X871686Y506181D02*
Y487659D01*
G01X870626Y495756D02*
Y494756D01*
G01X871686Y506181D02*
Y487659D01*
G01X870626Y492516D02*
Y487219D01*
G01X871686Y487659D02*
X877692Y481653D01*
G01D02*
X878258D01*
G01X879553Y479792D02*
X881985Y477360D01*
G01X870626Y487219D02*
X881545Y476300D01*
G01X881985Y477360D02*
X884166D01*
G01X881545Y476300D02*
X884606D01*
G01X881985Y477360D02*
X884166D01*
G01D02*
X885003Y478197D01*
G01X884606Y476300D02*
X885443Y477137D01*
G01X884166Y477360D02*
X885003Y478197D01*
G01D02*
X887110D01*
G01X885443Y477137D02*
X886667D01*
G01X887110Y478197D02*
X889503Y475804D01*
G01X886667Y477137D02*
X888443Y475361D01*
G01X889503Y475804D02*
Y473693D01*
G01X888443Y475361D02*
Y474136D01*
G01X889503Y473693D02*
X888193Y472383D01*
G01X888443Y474136D02*
X887133Y472826D01*
G01X888193Y472383D02*
Y471155D01*
G01X887133Y472826D02*
Y470712D01*
G01X888193Y471155D02*
X889963Y469385D01*
G01D02*
X891188D01*
G01X887133Y470712D02*
X889520Y468325D01*
G01X889963Y469385D02*
X891188D01*
G01X889520Y468325D02*
X891628D01*
G01X891188Y469385D02*
X891950Y470147D01*
G01X891628Y468325D02*
X892390Y469087D01*
G01X891188Y469385D02*
X891950Y470147D01*
G01D02*
X894076D01*
G01X892390Y469087D02*
X893636D01*
G01X894076Y470147D02*
X896214Y468009D01*
G01X893636Y469087D02*
X895154Y467569D01*
G01X903700Y501200D02*
X905001Y502501D01*
G01X900194Y499194D02*
X903941Y502941D01*
G01X905001Y502501D02*
Y521500D01*
G01X903941Y502941D02*
Y521060D01*
G01X905001Y521500D02*
X903500Y523001D01*
G01X903941Y521060D02*
X902440Y522561D01*
G01X903500Y523001D02*
Y525200D01*
G01X902440Y522561D02*
Y525640D01*
G01X903500Y525200D02*
X905001Y526701D01*
G01X902440Y525640D02*
X903941Y527141D01*
G01X863090Y508739D02*
Y550020D01*
G01Y508739D02*
Y550020D01*
G01Y508739D02*
Y550020D01*
G01X862030Y541494D02*
Y508299D01*
G01X867780Y504049D02*
X863090Y508739D01*
G01X862030Y508299D02*
X866720Y503609D01*
G01X867780Y486029D02*
Y504049D01*
G01X866720Y503609D02*
Y485589D01*
G01X897600Y502122D02*
X899901Y507677D01*
G01X895094Y498841D02*
X898841Y507888D01*
G01X899901Y507677D02*
Y549899D01*
G01X898841Y507888D02*
Y549459D01*
G01X867130Y525467D02*
Y524467D01*
G01Y522227D02*
Y521227D01*
G01Y518987D02*
Y517724D01*
G01Y515936D02*
Y512499D01*
G01Y510553D02*
Y509237D01*
G01X868190Y550235D02*
Y509677D01*
G01X867130Y509237D02*
X867882Y508485D01*
G01X868589Y506900D02*
X869467D01*
G01D02*
X870626Y505741D01*
G01X868190Y509677D02*
X871686Y506181D01*
G01X870626Y505741D02*
Y504476D01*
G01Y502236D02*
Y501236D01*
G01Y498996D02*
Y497996D01*
G01Y495756D02*
Y494756D01*
G01Y492516D02*
Y487219D01*
G01X871686Y506181D02*
Y487659D01*
G01X870626Y487219D02*
X881545Y476300D01*
G01X871686Y487659D02*
X877692Y481653D01*
G01X870626Y487219D02*
X881545Y476300D01*
G01X877692Y481653D02*
X878258D01*
G01X870626Y487219D02*
X881545Y476300D01*
G01X879553Y479792D02*
X881985Y477360D01*
G01X881545Y476300D02*
X884606D01*
G01D02*
X885443Y477137D01*
G01X881985Y477360D02*
X884166D01*
G01X884606Y476300D02*
X885443Y477137D01*
G01D02*
X886667D01*
G01X884166Y477360D02*
X885003Y478197D01*
G01X885443Y477137D02*
X886667D01*
G01X885003Y478197D02*
X887110D01*
G01X886667Y477137D02*
X888443Y475361D01*
G01X887110Y478197D02*
X889503Y475804D01*
G01X888443Y475361D02*
Y474136D01*
G01X889503Y475804D02*
Y473693D01*
G01X888443Y474136D02*
X887133Y472826D01*
G01X889503Y473693D02*
X888193Y472383D01*
G01X887133Y472826D02*
Y470712D01*
G01X888193Y472383D02*
Y471155D01*
G01X887133Y470712D02*
X889520Y468325D01*
G01X888193Y471155D02*
X889963Y469385D01*
G01X887133Y470712D02*
X889520Y468325D01*
G01D02*
X891628D01*
G01X889963Y469385D02*
X891188D01*
G01X891628Y468325D02*
X892390Y469087D01*
G01D02*
X893636D01*
G01X891188Y469385D02*
X891950Y470147D01*
G01X892390Y469087D02*
X893636D01*
G01X891950Y470147D02*
X894076D01*
G01X893636Y469087D02*
X895154Y467569D01*
G01X894076Y470147D02*
X896214Y468009D01*
G01X900194Y499194D02*
X903941Y502941D01*
G01X903700Y501200D02*
X905001Y502501D01*
G01X903941Y502941D02*
Y521060D01*
G01X905001Y502501D02*
Y521500D01*
G01X903941Y521060D02*
X902440Y522561D01*
G01X905001Y521500D02*
X903500Y523001D01*
G01X902440Y522561D02*
Y525640D01*
G01X903500Y523001D02*
Y525200D01*
G01X902440Y525640D02*
X903941Y527141D01*
G01X903500Y525200D02*
X905001Y526701D01*
G01X858022Y570211D02*
Y552200D01*
G01X859082Y558090D02*
Y559460D01*
G01X858022Y570211D02*
Y552200D01*
G01X859082Y563140D02*
Y564560D01*
G01X862030Y549580D02*
Y546827D01*
G01Y544719D02*
Y543546D01*
G01X861110Y550500D02*
X862030Y549580D01*
G01X863090Y550020D02*
X860010Y553100D01*
G01X864406Y564800D02*
X863635Y564029D01*
G01X863405Y565300D02*
X862575Y564470D01*
G01X863635Y564029D02*
Y563138D01*
G01Y559648D02*
Y558371D01*
G01X862575Y564470D02*
Y557930D01*
G01X863635Y558371D02*
X864306Y557700D01*
G01X862575Y557930D02*
X863405Y557100D01*
G01X865111Y553314D02*
X868190Y550235D01*
G01X866211Y550714D02*
X867130Y549795D01*
G01D02*
Y546880D01*
G01Y544640D02*
Y543640D01*
G01Y541400D02*
Y540400D01*
G01Y538160D02*
Y536326D01*
G01Y534496D02*
Y531209D01*
G01Y529337D02*
Y527707D01*
G01X859082Y558090D02*
Y559460D01*
G01Y563140D02*
Y564560D01*
G01X858022Y570211D02*
Y552200D01*
G01X863090Y550020D02*
X860010Y553100D01*
G01X861110Y550500D02*
X862030Y549580D01*
G01D02*
Y546827D01*
G01Y544719D02*
Y543546D01*
G01X863405Y565300D02*
X862575Y564470D01*
G01X864406Y564800D02*
X863635Y564029D01*
G01X862575Y564470D02*
Y557930D01*
G01X863635Y564029D02*
Y563138D01*
G01X862575Y564470D02*
Y557930D01*
G01X863635Y559648D02*
Y558371D01*
G01X862575Y557930D02*
X863405Y557100D01*
G01X863635Y558371D02*
X864306Y557700D01*
G01X866211Y550714D02*
X867130Y549795D01*
G01X865111Y553314D02*
X868190Y550235D01*
G01X867130Y549795D02*
Y546880D01*
G01Y544640D02*
Y543640D01*
G01Y541400D02*
Y540400D01*
G01Y538160D02*
Y536326D01*
G01Y534496D02*
Y531209D01*
G01Y529337D02*
Y527707D01*
G01X894833Y552200D02*
Y570211D01*
G01X895893Y558090D02*
Y559460D01*
G01X894833Y552200D02*
Y570211D01*
G01X895893Y563140D02*
Y564560D01*
G01X898841Y549459D02*
X897800Y550500D01*
G01D02*
X896821D01*
G01X899901Y549899D02*
X896821Y552979D01*
G01X901117Y557700D02*
X900446Y558371D01*
G01X900216Y557100D02*
X899386Y557930D01*
G01X900446Y558371D02*
Y559648D01*
G01Y563138D02*
Y564029D01*
G01X899386Y557930D02*
Y564470D01*
G01X900446Y564029D02*
X901217Y564800D01*
G01X899386Y564470D02*
X900216Y565300D01*
G01X905001Y526701D02*
Y550235D01*
G01X903941Y527141D02*
Y548695D01*
G01X895893Y558090D02*
Y559460D01*
G01Y563140D02*
Y564560D01*
G01X894833Y552200D02*
Y570211D01*
G01X899901Y549899D02*
X896821Y552979D01*
G01X898841Y549459D02*
X897800Y550500D01*
G01X899901Y549899D02*
X896821Y552979D01*
G01X897800Y550500D02*
X896821D01*
G01X900216Y557100D02*
X899386Y557930D01*
G01X901117Y557700D02*
X900446Y558371D01*
G01X899386Y557930D02*
Y564470D01*
G01X900446Y558371D02*
Y559648D01*
G01X899386Y557930D02*
Y564470D01*
G01X900446Y563138D02*
Y564029D01*
G01X899386Y564470D02*
X900216Y565300D01*
G01X900446Y564029D02*
X901217Y564800D01*
G01X903941Y527141D02*
Y548695D01*
G01X905001Y526701D02*
Y550235D01*
G01X858022Y570211D02*
Y552200D01*
G01X859082Y558090D02*
Y559460D01*
G01X858022Y570211D02*
Y552200D01*
G01X859082Y563140D02*
Y564560D01*
G01X862030Y549580D02*
Y546827D01*
G01Y544719D02*
Y543546D01*
G01X861110Y550500D02*
X862030Y549580D01*
G01X863090Y550020D02*
X860010Y553100D01*
G01X894833Y552200D02*
Y570211D01*
G01X895893Y558090D02*
Y559460D01*
G01X894833Y552200D02*
Y570211D01*
G01X895893Y563140D02*
Y564560D01*
G01X898841Y549459D02*
X897800Y550500D01*
G01D02*
X896821D01*
G01X899901Y549899D02*
X896821Y552979D01*
G01X864406Y564800D02*
X863635Y564029D01*
G01X863405Y565300D02*
X862575Y564470D01*
G01X863635Y564029D02*
Y563138D01*
G01Y559648D02*
Y558371D01*
G01X862575Y564470D02*
Y557930D01*
G01X863635Y558371D02*
X864306Y557700D01*
G01X862575Y557930D02*
X863405Y557100D01*
G01X865111Y553314D02*
X868190Y550235D01*
G01X866211Y550714D02*
X867130Y549795D01*
G01D02*
Y546880D01*
G01Y544640D02*
Y543640D01*
G01Y541400D02*
Y540400D01*
G01Y538160D02*
Y536326D01*
G01Y534496D02*
Y531209D01*
G01Y529337D02*
Y527707D01*
G01X901117Y557700D02*
X900446Y558371D01*
G01X900216Y557100D02*
X899386Y557930D01*
G01X900446Y558371D02*
Y559648D01*
G01Y563138D02*
Y564029D01*
G01X899386Y557930D02*
Y564470D01*
G01X900446Y564029D02*
X901217Y564800D01*
G01X899386Y564470D02*
X900216Y565300D01*
G01X905001Y526701D02*
Y550235D01*
G01X903941Y527141D02*
Y548695D01*
G01X859082Y558090D02*
Y559460D01*
G01Y563140D02*
Y564560D01*
G01X858022Y570211D02*
Y552200D01*
G01X863090Y550020D02*
X860010Y553100D01*
G01X861110Y550500D02*
X862030Y549580D01*
G01D02*
Y546827D01*
G01Y544719D02*
Y543546D01*
G01X895893Y558090D02*
Y559460D01*
G01Y563140D02*
Y564560D01*
G01X894833Y552200D02*
Y570211D01*
G01X899901Y549899D02*
X896821Y552979D01*
G01X898841Y549459D02*
X897800Y550500D01*
G01X899901Y549899D02*
X896821Y552979D01*
G01X897800Y550500D02*
X896821D01*
G01X863405Y565300D02*
X862575Y564470D01*
G01X864406Y564800D02*
X863635Y564029D01*
G01X862575Y564470D02*
Y557930D01*
G01X863635Y564029D02*
Y563138D01*
G01X862575Y564470D02*
Y557930D01*
G01X863635Y559648D02*
Y558371D01*
G01X862575Y557930D02*
X863405Y557100D01*
G01X863635Y558371D02*
X864306Y557700D01*
G01X866211Y550714D02*
X867130Y549795D01*
G01X865111Y553314D02*
X868190Y550235D01*
G01X867130Y549795D02*
Y546880D01*
G01Y544640D02*
Y543640D01*
G01Y541400D02*
Y540400D01*
G01Y538160D02*
Y536326D01*
G01Y534496D02*
Y531209D01*
G01Y529337D02*
Y527707D01*
G01X900216Y557100D02*
X899386Y557930D01*
G01X901117Y557700D02*
X900446Y558371D01*
G01X899386Y557930D02*
Y564470D01*
G01X900446Y558371D02*
Y559648D01*
G01X899386Y557930D02*
Y564470D01*
G01X900446Y563138D02*
Y564029D01*
G01X899386Y564470D02*
X900216Y565300D01*
G01X900446Y564029D02*
X901217Y564800D01*
G01X903941Y527141D02*
Y548695D01*
G01X905001Y526701D02*
Y550235D01*
G01X935652Y117732D02*
Y25885D01*
G01Y117732D02*
Y25885D01*
G01Y117732D02*
Y25885D01*
G01X936712Y55680D02*
Y25442D01*
G01X935652Y25885D02*
X931778Y22011D01*
G01X936712Y25442D02*
X932838Y21568D01*
G01X931778Y22011D02*
Y13554D01*
G01X932838Y21568D02*
Y19620D01*
G01X940752Y24505D02*
Y116842D01*
G01X941812Y116402D02*
Y24062D01*
G01X937478Y21231D02*
X940752Y24505D01*
G01X941812Y24062D02*
X941096Y23346D01*
G01X937478Y21231D02*
X940752Y24505D01*
G01X939512Y21762D02*
X938538Y20788D01*
G01X937478Y18479D02*
Y21231D01*
G01X938538Y20788D02*
Y19920D01*
G01X936712Y55680D02*
Y25442D01*
G01X935652Y117732D02*
Y25885D01*
G01X936712Y25442D02*
X932838Y21568D01*
G01X935652Y25885D02*
X931778Y22011D01*
G01X932838Y21568D02*
Y19620D01*
G01X931778Y22011D02*
Y13554D01*
G01X938538Y20788D02*
Y19920D01*
G01X937478Y18479D02*
Y21231D01*
G01X941812Y24062D02*
X941096Y23346D01*
G01X939512Y21762D02*
X938538Y20788D01*
G01X937478Y21231D02*
X940752Y24505D01*
G01X941812Y116402D02*
Y24062D01*
G01X940752Y24505D02*
Y116842D01*
G01X936712Y117292D02*
Y60920D01*
G01Y58680D02*
Y57920D01*
G01Y117292D02*
Y60920D01*
G01Y58680D02*
Y57920D01*
G01X946600Y172400D02*
Y137482D01*
G01X947660Y171960D02*
Y137042D01*
G01X946600Y137482D02*
X946128Y137010D01*
G01X947660Y137042D02*
X946568Y135950D01*
G01X946128Y137010D02*
X942292D01*
G01X946568Y135950D02*
X942732D01*
G01X942292Y137010D02*
X941200Y135918D01*
G01X942732Y135950D02*
X942260Y135478D01*
G01X941200Y135918D02*
Y133292D01*
G01X942260Y135478D02*
Y133732D01*
G01X941200Y133292D02*
X942292Y132200D01*
G01X942260Y133732D02*
X942732Y133260D01*
G01X942292Y132200D02*
X946128D01*
G01X942732Y133260D02*
X946568D01*
G01X946128Y132200D02*
X946600Y131728D01*
G01X946568Y133260D02*
X947660Y132168D01*
G01X946600Y131728D02*
Y128680D01*
G01X947660Y132168D02*
Y128240D01*
G01X946600Y128680D02*
X935652Y117732D01*
G01X947660Y128240D02*
X936712Y117292D01*
G01X950940Y127030D02*
Y170492D01*
G01X952000Y170052D02*
Y126590D01*
G01X940752Y116842D02*
X950940Y127030D01*
G01X952000Y126590D02*
X941812Y116402D01*
G01X947660Y171960D02*
Y137042D01*
G01X946600Y172400D02*
Y137482D01*
G01X947660Y137042D02*
X946568Y135950D01*
G01X946600Y137482D02*
X946128Y137010D01*
G01X946568Y135950D02*
X942732D01*
G01X946128Y137010D02*
X942292D01*
G01X942732Y135950D02*
X942260Y135478D01*
G01X942292Y137010D02*
X941200Y135918D01*
G01X942260Y135478D02*
Y133732D01*
G01X941200Y135918D02*
Y133292D01*
G01X942260Y133732D02*
X942732Y133260D01*
G01X941200Y133292D02*
X942292Y132200D01*
G01X942732Y133260D02*
X946568D01*
G01X942292Y132200D02*
X946128D01*
G01X946568Y133260D02*
X947660Y132168D01*
G01X946128Y132200D02*
X946600Y131728D01*
G01X947660Y132168D02*
Y128240D01*
G01X946600Y131728D02*
Y128680D01*
G01X947660Y128240D02*
X936712Y117292D01*
G01X946600Y128680D02*
X935652Y117732D01*
G01X952000Y126590D02*
X941812Y116402D01*
G01X940752Y116842D02*
X950940Y127030D01*
G01X952000Y170052D02*
Y126590D01*
G01X950940Y127030D02*
Y170492D01*
G01X911111Y176979D02*
X911747D01*
G01X912702Y178570D02*
X913655Y179523D01*
G01D02*
X914291D01*
G01X915137Y182508D02*
X915140D01*
G01X915246Y181114D02*
X916200Y182068D01*
G01X915140Y182508D02*
Y185384D01*
G01X916200Y182068D02*
Y184944D01*
G01X915140Y185384D02*
X917821Y188065D01*
G01X916200Y184944D02*
X918572Y187316D01*
G01X912576Y172944D02*
X913094D01*
G01X914167Y174535D02*
X915121Y175489D01*
G01D02*
X915757D01*
G01X916712Y177080D02*
X917665Y178033D01*
G01D02*
X918301D01*
G01X919256Y179624D02*
X920210Y180578D01*
G01X919150Y182732D02*
Y181018D01*
G01X920210Y180578D02*
Y182292D01*
G01X922377Y185959D02*
X919150Y182732D01*
G01X920210Y182292D02*
X923127Y185209D01*
G01X911111Y176979D02*
X911747D01*
G01X912702Y178570D02*
X913655Y179523D01*
G01D02*
X914291D01*
G01X915246Y181114D02*
X916200Y182068D01*
G01X915246Y181114D02*
X916200Y182068D01*
G01X915137Y182508D02*
X915140D01*
G01X916200Y182068D02*
Y184944D01*
G01X915140Y182508D02*
Y185384D01*
G01X916200Y184944D02*
X918572Y187316D01*
G01X915140Y185384D02*
X917821Y188065D01*
G01X911111Y176979D02*
X911747D01*
G01X912702Y178570D02*
X913655Y179523D01*
G01D02*
X914291D01*
G01X915137Y182508D02*
X915140D01*
G01X915246Y181114D02*
X916200Y182068D01*
G01X915140Y182508D02*
Y185384D01*
G01X916200Y182068D02*
Y184944D01*
G01X915140Y185384D02*
X917821Y188065D01*
G01X916200Y184944D02*
X918572Y187316D01*
G01X912576Y172944D02*
X913094D01*
G01X914167Y174535D02*
X915121Y175489D01*
G01D02*
X915757D01*
G01X916712Y177080D02*
X917665Y178033D01*
G01D02*
X918301D01*
G01X919256Y179624D02*
X920210Y180578D01*
G01X919150Y182732D02*
Y181018D01*
G01X920210Y180578D02*
Y182292D01*
G01X922377Y185959D02*
X919150Y182732D01*
G01X920210Y182292D02*
X923127Y185209D01*
G01X911111Y176979D02*
X911747D01*
G01X912702Y178570D02*
X913655Y179523D01*
G01D02*
X914291D01*
G01X915246Y181114D02*
X916200Y182068D01*
G01X915246Y181114D02*
X916200Y182068D01*
G01X915137Y182508D02*
X915140D01*
G01X916200Y182068D02*
Y184944D01*
G01X915140Y182508D02*
Y185384D01*
G01X916200Y184944D02*
X918572Y187316D01*
G01X915140Y185384D02*
X917821Y188065D01*
G01X920210Y182292D02*
X923127Y185209D01*
G01X922377Y185959D02*
X919150Y182732D01*
G01X920210Y180578D02*
Y182292D01*
G01X919150Y182732D02*
Y181018D01*
G01X912576Y172944D02*
X913094D01*
G01X914167Y174535D02*
X915121Y175489D01*
G01D02*
X915757D01*
G01X916712Y177080D02*
X917665Y178033D01*
G01D02*
X918301D01*
G01X919256Y179624D02*
X920210Y180578D01*
G01Y182292D02*
X923127Y185209D01*
G01X922377Y185959D02*
X919150Y182732D01*
G01X920210Y180578D02*
Y182292D01*
G01X919150Y182732D02*
Y181018D01*
G01X912576Y172944D02*
X913094D01*
G01X914167Y174535D02*
X915121Y175489D01*
G01D02*
X915757D01*
G01X916712Y177080D02*
X917665Y178033D01*
G01D02*
X918301D01*
G01X919256Y179624D02*
X920210Y180578D01*
G01X963521Y194250D02*
Y189321D01*
G01X964581Y194250D02*
Y193050D01*
G01X963521Y194250D02*
Y189321D01*
G01X964581Y191150D02*
Y188881D01*
G01X963521Y189321D02*
X946600Y172400D01*
G01X964581Y188881D02*
X963945Y188245D01*
G01X963521Y189321D02*
X946600Y172400D01*
G01X962601Y186901D02*
X961897Y186197D01*
G01X963521Y189321D02*
X946600Y172400D01*
G01X960553Y184853D02*
X959917Y184217D01*
G01X963521Y189321D02*
X946600Y172400D01*
G01X958573Y182873D02*
X957937Y182237D01*
G01X963521Y189321D02*
X946600Y172400D01*
G01X956593Y180893D02*
X955922Y180222D01*
G01X963521Y189321D02*
X946600Y172400D01*
G01X954578Y178878D02*
X953942Y178242D01*
G01X963521Y189321D02*
X946600Y172400D01*
G01X952598Y176898D02*
X951962Y176262D01*
G01X963521Y189321D02*
X946600Y172400D01*
G01X950618Y174918D02*
X949982Y174282D01*
G01X963521Y189321D02*
X946600Y172400D01*
G01X948638Y172938D02*
X947660Y171960D01*
G01X968989Y185839D02*
Y196613D01*
G01X970049D02*
Y185399D01*
G01X968260Y185110D02*
X968989Y185839D01*
G01X970049Y185399D02*
X968700Y184050D01*
G01X965558Y185110D02*
X968260D01*
G01X968700Y184050D02*
X965998D01*
G01X950940Y170492D02*
X965558Y185110D01*
G01X965998Y184050D02*
X952000Y170052D01*
G01X964581Y194250D02*
Y193050D01*
G01Y191150D02*
Y188881D01*
G01X963521Y194250D02*
Y189321D01*
G01X964581Y188881D02*
X963945Y188245D01*
G01X962601Y186901D02*
X961897Y186197D01*
G01X960553Y184853D02*
X959917Y184217D01*
G01X958573Y182873D02*
X957937Y182237D01*
G01X956593Y180893D02*
X955922Y180222D01*
G01X954578Y178878D02*
X953942Y178242D01*
G01X952598Y176898D02*
X951962Y176262D01*
G01X950618Y174918D02*
X949982Y174282D01*
G01X948638Y172938D02*
X947660Y171960D01*
G01X963521Y189321D02*
X946600Y172400D01*
G01X965998Y184050D02*
X952000Y170052D01*
G01X950940Y170492D02*
X965558Y185110D01*
G01X968700Y184050D02*
X965998D01*
G01X965558Y185110D02*
X968260D01*
G01X970049Y185399D02*
X968700Y184050D01*
G01X968260Y185110D02*
X968989Y185839D01*
G01X970049Y196613D02*
Y185399D01*
G01X968989Y185839D02*
Y196613D01*
G01X918783Y223477D02*
X919419D01*
G01X920374Y225068D02*
X922311Y227005D01*
G01X921251Y230644D02*
Y227445D01*
G01X922311Y227005D02*
Y230644D01*
G01X918783Y223477D02*
X919419D01*
G01X920374Y225068D02*
X922311Y227005D01*
G01X921251Y230644D02*
Y227445D01*
G01X922311Y227005D02*
Y230644D01*
G01Y227005D02*
Y230644D01*
G01X921251D02*
Y227445D01*
G01X918783Y223477D02*
X919419D01*
G01X920374Y225068D02*
X922311Y227005D01*
G01D02*
Y230644D01*
G01X921251D02*
Y227445D01*
G01X918783Y223477D02*
X919419D01*
G01X920374Y225068D02*
X922311Y227005D01*
G01X916400Y410654D02*
X918521Y408533D01*
G01X919271Y409283D02*
X917460Y411094D01*
G01X916400Y417129D02*
Y410654D01*
G01X917460Y411094D02*
Y417572D01*
G01X922617Y417955D02*
Y411297D01*
G01X921557Y417515D02*
Y410857D01*
G01X922617Y411297D02*
X923851Y410063D01*
G01X921557Y410857D02*
X923101Y409313D01*
G01X917460Y411094D02*
Y417572D01*
G01X916400Y417129D02*
Y410654D01*
G01X919271Y409283D02*
X917460Y411094D01*
G01X916400Y410654D02*
X918521Y408533D01*
G01X921557Y417515D02*
Y410857D01*
G01X922617Y417955D02*
Y411297D01*
G01X921557Y410857D02*
X923101Y409313D01*
G01X922617Y411297D02*
X923851Y410063D01*
G01X916400Y410654D02*
X918521Y408533D01*
G01X919271Y409283D02*
X917460Y411094D01*
G01X916400Y417129D02*
Y410654D01*
G01X917460Y411094D02*
Y417572D01*
G01X922617Y417955D02*
Y411297D01*
G01X921557Y417515D02*
Y410857D01*
G01X922617Y411297D02*
X923851Y410063D01*
G01X921557Y410857D02*
X923101Y409313D01*
G01X917460Y411094D02*
Y417572D01*
G01X916400Y417129D02*
Y410654D01*
G01X919271Y409283D02*
X917460Y411094D01*
G01X916400Y410654D02*
X918521Y408533D01*
G01X921557Y417515D02*
Y410857D01*
G01X922617Y417955D02*
Y411297D01*
G01X921557Y410857D02*
X923101Y409313D01*
G01X922617Y411297D02*
X923851Y410063D01*
G01X964783Y413361D02*
Y405512D01*
G01X965843D02*
Y413801D01*
G01X939922Y438222D02*
X964783Y413361D01*
G01X965843Y413801D02*
X940980Y438664D01*
G01X939920Y449609D02*
Y438222D01*
G01X940980Y438664D02*
Y450052D01*
G01X933520Y456009D02*
X939920Y449609D01*
G01X940980Y450052D02*
X937734Y453298D01*
G01X933520Y456009D02*
X939920Y449609D01*
G01X935874Y455158D02*
X934580Y456452D01*
G01X933520Y485449D02*
Y456009D01*
G01X934580Y456452D02*
Y461378D01*
G01X933520Y485449D02*
Y456009D01*
G01X934580Y464008D02*
Y485009D01*
G01X969846Y409187D02*
Y415262D01*
G01X968786Y409187D02*
Y414822D01*
G01X969846Y415262D02*
X945109Y439998D01*
G01X968786Y414822D02*
X944049Y439558D01*
G01X945109Y439998D02*
Y455015D01*
G01X944049Y439558D02*
Y454575D01*
G01X945109Y455015D02*
X943568Y456556D01*
G01X944049Y454575D02*
X943128Y455496D01*
G01X943568Y456556D02*
X940952D01*
G01X943128Y455496D02*
X940512D01*
G01X940952Y456556D02*
X940080Y457428D01*
G01X940512Y455496D02*
X939020Y456988D01*
G01X940080Y457428D02*
Y459124D01*
G01X939020Y456988D02*
Y459564D01*
G01X940080Y459124D02*
X940952Y459996D01*
G01X939020Y459564D02*
X940512Y461056D01*
G01X940952Y459996D02*
X943117D01*
G01X940512Y461056D02*
X942677D01*
G01X943117Y459996D02*
X944237Y461116D01*
G01X942677Y461056D02*
X943177Y461556D01*
G01X944237Y461116D02*
Y464660D01*
G01X943177Y461556D02*
Y464220D01*
G01X944237Y464660D02*
X943117Y465780D01*
G01X943177Y464220D02*
X942677Y464720D01*
G01D02*
X939112D01*
G01D02*
X937420Y466412D01*
G01X934580Y456452D02*
Y461378D01*
G01Y464008D02*
Y485009D01*
G01X933520Y485449D02*
Y456009D01*
G01X940980Y450052D02*
X937734Y453298D01*
G01X935874Y455158D02*
X934580Y456452D01*
G01X933520Y456009D02*
X939920Y449609D01*
G01X940980Y438664D02*
Y450052D01*
G01X939920Y449609D02*
Y438222D01*
G01X965843Y413801D02*
X940980Y438664D01*
G01X939922Y438222D02*
X964783Y413361D01*
G01X965843Y405512D02*
Y413801D01*
G01X964783Y413361D02*
Y405512D01*
G01X968786Y409187D02*
Y414822D01*
G01X969846Y409187D02*
Y415262D01*
G01X968786Y414822D02*
X944049Y439558D01*
G01X969846Y415262D02*
X945109Y439998D01*
G01X944049Y439558D02*
Y454575D01*
G01X945109Y439998D02*
Y455015D01*
G01X944049Y454575D02*
X943128Y455496D01*
G01X945109Y455015D02*
X943568Y456556D01*
G01X943128Y455496D02*
X940512D01*
G01X943568Y456556D02*
X940952D01*
G01X940512Y455496D02*
X939020Y456988D01*
G01X940952Y456556D02*
X940080Y457428D01*
G01X939020Y456988D02*
Y459564D01*
G01X940080Y457428D02*
Y459124D01*
G01X939020Y459564D02*
X940512Y461056D01*
G01X940080Y459124D02*
X940952Y459996D01*
G01X940512Y461056D02*
X942677D01*
G01X940952Y459996D02*
X943117D01*
G01X942677Y461056D02*
X943177Y461556D01*
G01X943117Y459996D02*
X944237Y461116D01*
G01X943177Y461556D02*
Y464220D01*
G01X944237Y461116D02*
Y464660D01*
G01X943177Y464220D02*
X942677Y464720D01*
G01X944237Y464660D02*
X943117Y465780D01*
G01X942677Y464720D02*
X939112D01*
G01D02*
X937420Y466412D01*
G01X935652Y487581D02*
X933520Y485449D01*
G01X934580Y485009D02*
X936712Y487141D01*
G01X935652Y559472D02*
Y487581D01*
G01X936712Y487141D02*
Y587820D01*
G01X943117Y465780D02*
X939552D01*
G01D02*
X938480Y466852D01*
G01D02*
Y483409D01*
G01X937420Y466412D02*
Y483852D01*
G01X938480Y483409D02*
X941812Y486741D01*
G01X937420Y483852D02*
X940752Y487184D01*
G01X941812Y486741D02*
Y588034D01*
G01X940752Y487184D02*
Y519146D01*
G01X941812Y486741D02*
Y588034D01*
G01X940752Y521386D02*
Y522386D01*
G01X941812Y486741D02*
Y588034D01*
G01X940752Y524626D02*
Y525626D01*
G01X941812Y486741D02*
Y588034D01*
G01Y486741D02*
Y588034D01*
G01Y486741D02*
Y588034D01*
G01Y486741D02*
Y588034D01*
G01Y486741D02*
Y588034D01*
G01Y486741D02*
Y588034D01*
G01Y486741D02*
Y588034D01*
G01Y486741D02*
Y588034D01*
G01Y486741D02*
Y588034D01*
G01Y486741D02*
Y588034D01*
G01Y486741D02*
Y588034D01*
G01X936712Y487141D02*
Y587820D01*
G01Y487141D02*
Y587820D01*
G01Y487141D02*
Y587820D01*
G01Y487141D02*
Y587820D01*
G01Y487141D02*
Y587820D01*
G01Y487141D02*
Y587820D01*
G01X935652Y559472D02*
Y487581D01*
G01X934580Y485009D02*
X936712Y487141D01*
G01X935652Y487581D02*
X933520Y485449D01*
G01X943117Y465780D02*
X939552D01*
G01D02*
X938480Y466852D01*
G01X937420Y466412D02*
Y483852D01*
G01X938480Y466852D02*
Y483409D01*
G01X937420Y483852D02*
X940752Y487184D01*
G01X938480Y483409D02*
X941812Y486741D01*
G01X940752Y487184D02*
Y519146D01*
G01Y521386D02*
Y522386D01*
G01Y524626D02*
Y525626D01*
G01X941812Y486741D02*
Y588034D01*
G01X935652Y587380D02*
Y584403D01*
G01Y582163D02*
Y581163D01*
G01Y578923D02*
Y577711D01*
G01Y575895D02*
Y564765D01*
G01Y562659D02*
Y561500D01*
G01X934732Y588300D02*
X935652Y587380D01*
G01X936712Y587820D02*
X933632Y590900D01*
G01X940752Y527866D02*
Y538293D01*
G01Y540533D02*
Y541533D01*
G01Y543773D02*
Y544773D01*
G01Y547013D02*
Y556987D01*
G01Y559227D02*
Y560227D01*
G01Y562467D02*
Y563626D01*
G01Y565574D02*
Y572284D01*
G01Y574154D02*
Y576292D01*
G01Y578054D02*
Y579293D01*
G01Y581533D02*
Y582533D01*
G01Y584773D02*
Y587594D01*
G01X941812Y588034D02*
X938732Y591114D01*
G01X940752Y587594D02*
X939832Y588514D01*
G01X941812Y588034D02*
X938732Y591114D01*
G01X936712Y587820D02*
X933632Y590900D01*
G01X936712Y587820D02*
X933632Y590900D01*
G01X934732Y588300D02*
X935652Y587380D01*
G01D02*
Y584403D01*
G01Y582163D02*
Y581163D01*
G01Y578923D02*
Y577711D01*
G01Y575895D02*
Y564765D01*
G01Y562659D02*
Y561500D01*
G01X940752Y527866D02*
Y538293D01*
G01Y540533D02*
Y541533D01*
G01Y543773D02*
Y544773D01*
G01Y547013D02*
Y556987D01*
G01Y559227D02*
Y560227D01*
G01Y562467D02*
Y563626D01*
G01Y565574D02*
Y572284D01*
G01Y574154D02*
Y576292D01*
G01Y578054D02*
Y579293D01*
G01Y581533D02*
Y582533D01*
G01Y584773D02*
Y587594D01*
G01D02*
X939832Y588514D01*
G01X941812Y588034D02*
X938732Y591114D01*
G01X933632Y588300D02*
X934732D01*
G01X939832Y588514D02*
X938732D01*
G01X933632Y588300D02*
X934732D01*
G01X939832Y588514D02*
X938732D01*
G01X1027140Y40325D02*
X1019594Y32779D01*
G01X1028200Y39885D02*
X1020034Y31719D01*
G01X1019594Y32779D02*
X1013750D01*
G01X1020034Y31719D02*
X1014190D01*
G01X1013750Y32779D02*
X1011894Y30923D01*
G01X1014190Y31719D02*
X1012954Y30483D01*
G01X1011894Y30923D02*
Y29082D01*
G01X1012954Y30483D02*
Y29233D01*
G01X1028200Y39885D02*
X1020034Y31719D01*
G01X1027140Y40325D02*
X1019594Y32779D01*
G01X1020034Y31719D02*
X1014190D01*
G01X1019594Y32779D02*
X1013750D01*
G01X1014190Y31719D02*
X1012954Y30483D01*
G01X1013750Y32779D02*
X1011894Y30923D01*
G01X1012954Y30483D02*
Y29233D01*
G01X1011894Y30923D02*
Y29082D01*
G01X1030220Y103286D02*
Y80380D01*
G01X1031280Y103726D02*
Y80820D01*
G01X1030220Y80380D02*
X1032340Y78260D01*
G01X1031280Y80820D02*
X1033400Y78700D01*
G01X1032340Y78260D02*
Y54340D01*
G01X1033400Y78700D02*
Y53900D01*
G01X1032340Y54340D02*
X1030220Y52220D01*
G01X1033400Y53900D02*
X1031280Y51780D01*
G01X1030220Y52220D02*
Y46432D01*
G01X1031280Y51780D02*
Y45992D01*
G01X1030220Y46432D02*
X1027140Y43352D01*
G01X1031280Y45992D02*
X1028200Y42912D01*
G01X1027140Y43352D02*
Y40325D01*
G01X1028200Y42912D02*
Y39885D01*
G01X1031280Y103726D02*
Y80820D01*
G01X1030220Y103286D02*
Y80380D01*
G01X1031280Y80820D02*
X1033400Y78700D01*
G01X1030220Y80380D02*
X1032340Y78260D01*
G01X1033400Y78700D02*
Y53900D01*
G01X1032340Y78260D02*
Y54340D01*
G01X1033400Y53900D02*
X1031280Y51780D01*
G01X1032340Y54340D02*
X1030220Y52220D01*
G01X1031280Y51780D02*
Y45992D01*
G01X1030220Y52220D02*
Y46432D01*
G01X1031280Y45992D02*
X1028200Y42912D01*
G01X1030220Y46432D02*
X1027140Y43352D01*
G01X1028200Y42912D02*
Y39885D01*
G01X1027140Y43352D02*
Y40325D01*
G01X1018279Y102147D02*
X1010338Y94206D01*
G01X1009278Y91384D02*
Y94646D01*
G01X1010338Y94206D02*
Y90944D01*
G01X1009200Y85831D02*
Y91306D01*
G01X1010260Y90866D02*
Y86271D01*
G01X1011500Y83531D02*
X1009200Y85831D01*
G01X1010260Y86271D02*
X1012560Y83971D01*
G01X1011500Y82151D02*
Y83531D01*
G01X1012560Y83971D02*
Y82591D01*
G01X1012730Y80921D02*
X1011500Y82151D01*
G01X1012560Y82591D02*
X1013170Y81981D01*
G01X1016198Y80921D02*
X1012730D01*
G01X1013170Y81981D02*
X1016638D01*
G01X1016837Y80282D02*
X1016198Y80921D01*
G01X1016638Y81981D02*
X1017897Y80722D01*
G01X1016837Y78892D02*
Y80282D01*
G01X1017897Y80722D02*
Y78452D01*
G01X1016256Y78311D02*
X1016837Y78892D01*
G01X1017897Y78452D02*
X1016696Y77251D01*
G01X1012730Y78311D02*
X1016256D01*
G01X1016696Y77251D02*
X1013170D01*
G01X1011500Y77081D02*
X1012730Y78311D01*
G01X1013170Y77251D02*
X1012560Y76641D01*
G01X1011500Y71736D02*
Y77081D01*
G01X1012560Y76641D02*
Y72176D01*
G01X1013936Y69300D02*
X1011500Y71736D01*
G01X1012560Y72176D02*
X1014376Y70360D01*
G01X1016640Y69300D02*
X1013936D01*
G01X1014376Y70360D02*
X1017080D01*
G01X1018396Y67544D02*
X1016640Y69300D01*
G01X1017080Y70360D02*
X1019456Y67984D01*
G01X1018396Y63286D02*
Y67544D01*
G01X1019456Y67984D02*
Y62846D01*
G01X1016426Y61316D02*
X1018396Y63286D01*
G01X1019456Y62846D02*
X1016866Y60256D01*
G01X1014459Y61316D02*
X1016426D01*
G01X1016866Y60256D02*
X1014899D01*
G01X1011994Y58851D02*
X1014459Y61316D01*
G01X1014899Y60256D02*
X1013054Y58411D01*
G01X1011994Y56010D02*
Y58851D01*
G01X1013054Y58411D02*
Y55961D01*
G01X1026920Y101413D02*
Y50192D01*
G01X1027980Y101853D02*
Y49752D01*
G01X1026920Y50192D02*
X1022392Y45664D01*
G01X1027980Y49752D02*
X1023452Y45224D01*
G01X1022392Y45664D02*
Y43039D01*
G01X1023452Y45224D02*
Y42599D01*
G01X1022392Y43039D02*
X1020923Y41570D01*
G01X1023452Y42599D02*
X1021363Y40510D01*
G01X1020923Y41570D02*
X1018929D01*
G01X1021363Y40510D02*
X1018489D01*
G01X1018929Y41570D02*
X1018429Y42070D01*
G01X1018489Y40510D02*
X1017369Y41630D01*
G01X1018429Y42070D02*
Y43035D01*
G01X1017369Y41630D02*
Y42595D01*
G01X1018429Y43035D02*
X1017073Y44391D01*
G01X1017369Y42595D02*
X1016633Y43331D01*
G01X1017073Y44391D02*
X1013709D01*
G01X1016633Y43331D02*
X1014149D01*
G01X1013709Y44391D02*
X1011894Y42576D01*
G01X1014149Y43331D02*
X1012954Y42136D01*
G01X1011894Y42576D02*
Y37010D01*
G01X1012954Y42136D02*
Y37161D01*
G01X1020820Y102892D02*
Y71880D01*
G01X1021880Y102452D02*
Y72320D01*
G01X1020820Y71880D02*
X1023020Y69680D01*
G01X1021880Y72320D02*
X1024080Y70120D01*
G01X1023020Y69680D02*
Y57931D01*
G01X1024080Y70120D02*
Y57491D01*
G01X1023020Y57931D02*
X1017549Y52460D01*
G01X1024080Y57491D02*
X1017989Y51400D01*
G01X1017549Y52460D02*
X1015559D01*
G01X1017989Y51400D02*
X1015999D01*
G01X1015559Y52460D02*
X1011894Y48795D01*
G01X1015999Y51400D02*
X1012954Y48355D01*
G01X1011894Y48795D02*
Y47682D01*
G01X1012954Y48355D02*
Y47833D01*
G01X1013054Y58411D02*
Y55961D01*
G01X1011994Y56010D02*
Y58851D01*
G01X1014899Y60256D02*
X1013054Y58411D01*
G01X1011994Y58851D02*
X1014459Y61316D01*
G01X1016866Y60256D02*
X1014899D01*
G01X1014459Y61316D02*
X1016426D01*
G01X1019456Y62846D02*
X1016866Y60256D01*
G01X1016426Y61316D02*
X1018396Y63286D01*
G01X1019456Y67984D02*
Y62846D01*
G01X1018396Y63286D02*
Y67544D01*
G01X1017080Y70360D02*
X1019456Y67984D01*
G01X1018396Y67544D02*
X1016640Y69300D01*
G01X1014376Y70360D02*
X1017080D01*
G01X1016640Y69300D02*
X1013936D01*
G01X1012560Y72176D02*
X1014376Y70360D01*
G01X1013936Y69300D02*
X1011500Y71736D01*
G01X1012560Y76641D02*
Y72176D01*
G01X1011500Y71736D02*
Y77081D01*
G01X1013170Y77251D02*
X1012560Y76641D01*
G01X1011500Y77081D02*
X1012730Y78311D01*
G01X1016696Y77251D02*
X1013170D01*
G01X1012730Y78311D02*
X1016256D01*
G01X1017897Y78452D02*
X1016696Y77251D01*
G01X1016256Y78311D02*
X1016837Y78892D01*
G01X1017897Y80722D02*
Y78452D01*
G01X1016837Y78892D02*
Y80282D01*
G01X1016638Y81981D02*
X1017897Y80722D01*
G01X1016837Y80282D02*
X1016198Y80921D01*
G01X1013170Y81981D02*
X1016638D01*
G01X1016198Y80921D02*
X1012730D01*
G01X1012560Y82591D02*
X1013170Y81981D01*
G01X1012730Y80921D02*
X1011500Y82151D01*
G01X1012560Y83971D02*
Y82591D01*
G01X1011500Y82151D02*
Y83531D01*
G01X1010260Y86271D02*
X1012560Y83971D01*
G01X1011500Y83531D02*
X1009200Y85831D01*
G01X1010260Y90866D02*
Y86271D01*
G01X1009200Y85831D02*
Y91306D01*
G01X1010338Y94206D02*
Y90944D01*
G01X1009278Y91384D02*
Y94646D01*
G01X1018279Y102147D02*
X1010338Y94206D01*
G01X1027980Y101853D02*
Y49752D01*
G01X1026920Y101413D02*
Y50192D01*
G01X1027980Y49752D02*
X1023452Y45224D01*
G01X1026920Y50192D02*
X1022392Y45664D01*
G01X1023452Y45224D02*
Y42599D01*
G01X1022392Y45664D02*
Y43039D01*
G01X1023452Y42599D02*
X1021363Y40510D01*
G01X1022392Y43039D02*
X1020923Y41570D01*
G01X1021363Y40510D02*
X1018489D01*
G01X1020923Y41570D02*
X1018929D01*
G01X1018489Y40510D02*
X1017369Y41630D01*
G01X1018929Y41570D02*
X1018429Y42070D01*
G01X1017369Y41630D02*
Y42595D01*
G01X1018429Y42070D02*
Y43035D01*
G01X1017369Y42595D02*
X1016633Y43331D01*
G01X1018429Y43035D02*
X1017073Y44391D01*
G01X1016633Y43331D02*
X1014149D01*
G01X1017073Y44391D02*
X1013709D01*
G01X1014149Y43331D02*
X1012954Y42136D01*
G01X1013709Y44391D02*
X1011894Y42576D01*
G01X1012954Y42136D02*
Y37161D01*
G01X1011894Y42576D02*
Y37010D01*
G01X1021880Y102452D02*
Y72320D01*
G01X1020820Y102892D02*
Y71880D01*
G01X1021880Y72320D02*
X1024080Y70120D01*
G01X1020820Y71880D02*
X1023020Y69680D01*
G01X1024080Y70120D02*
Y57491D01*
G01X1023020Y69680D02*
Y57931D01*
G01X1024080Y57491D02*
X1017989Y51400D01*
G01X1023020Y57931D02*
X1017549Y52460D01*
G01X1017989Y51400D02*
X1015999D01*
G01X1017549Y52460D02*
X1015559D01*
G01X1015999Y51400D02*
X1012954Y48355D01*
G01X1015559Y52460D02*
X1011894Y48795D01*
G01X1012954Y48355D02*
Y47833D01*
G01X1011894Y48795D02*
Y47682D01*
G01X1029430Y191170D02*
Y104076D01*
G01X1030490Y191050D02*
Y104516D01*
G01X1029430Y104076D02*
X1030220Y103286D01*
G01X1030490Y104516D02*
X1031280Y103726D01*
G01X1030490Y191050D02*
Y104516D01*
G01X1029430Y191170D02*
Y104076D01*
G01X1030490Y104516D02*
X1031280Y103726D01*
G01X1029430Y104076D02*
X1030220Y103286D01*
G01X1019894Y106866D02*
Y188926D01*
G01X1020954Y189046D02*
Y106423D01*
G01X1017219Y104191D02*
X1019894Y106866D01*
G01X1020954Y106423D02*
X1019310Y104779D01*
G01X1017219Y104191D02*
X1019894Y106866D01*
G01X1019307Y104779D02*
X1018279Y103751D01*
G01X1017219Y102587D02*
Y104191D01*
G01X1018279Y103751D02*
Y102147D01*
G01X1009278Y94646D02*
X1017219Y102587D01*
G01X1026494Y188926D02*
Y101839D01*
G01X1027554Y189046D02*
Y102279D01*
G01X1026494Y101839D02*
X1026920Y101413D01*
G01X1027554Y102279D02*
X1027980Y101853D01*
G01X1023194Y188726D02*
Y105266D01*
G01X1024254Y188846D02*
Y104826D01*
G01X1023194Y105266D02*
X1020820Y102892D01*
G01X1024254Y104826D02*
X1021880Y102452D01*
G01X1009278Y94646D02*
X1017219Y102587D01*
G01X1018279Y103751D02*
Y102147D01*
G01X1017219Y102587D02*
Y104191D01*
G01X1020954Y106423D02*
X1019310Y104779D01*
G01X1019307D02*
X1018279Y103751D01*
G01X1017219Y104191D02*
X1019894Y106866D01*
G01X1020954Y189046D02*
Y106423D01*
G01X1019894Y106866D02*
Y188926D01*
G01X1027554Y189046D02*
Y102279D01*
G01X1026494Y188926D02*
Y101839D01*
G01X1027554Y102279D02*
X1027980Y101853D01*
G01X1026494Y101839D02*
X1026920Y101413D01*
G01X1024254Y188846D02*
Y104826D01*
G01X1023194Y188726D02*
Y105266D01*
G01X1024254Y104826D02*
X1021880Y102452D01*
G01X1023194Y105266D02*
X1020820Y102892D01*
G01X1025912Y409402D02*
Y504529D01*
G01X1024852Y409402D02*
Y504969D01*
G01X1022880Y409466D02*
Y519779D01*
G01X1021820Y409466D02*
Y520219D01*
G01X1029334Y409186D02*
Y499157D01*
G01X1028274Y409306D02*
Y485929D01*
G01X1029334Y409186D02*
Y499157D01*
G01Y409186D02*
Y499157D01*
G01Y409186D02*
Y499157D01*
G01X1019578Y516404D02*
Y409511D01*
G01X1018518Y409472D02*
Y502296D01*
G01X1019578Y516404D02*
Y409511D01*
G01Y516404D02*
Y409511D01*
G01Y516404D02*
Y409511D01*
G01X1024852Y409402D02*
Y504969D01*
G01X1025912Y409402D02*
Y504529D01*
G01X1021820Y409466D02*
Y520219D01*
G01X1022880Y409466D02*
Y519779D01*
G01X1028274Y409306D02*
Y485929D01*
G01X1029334Y409186D02*
Y499157D01*
G01X1018518Y409472D02*
Y502296D01*
G01X1019578Y516404D02*
Y409511D01*
G01X1025912Y504529D02*
X1028987Y507604D01*
G01X1024852Y504969D02*
X1027927Y508044D01*
G01X1028987Y507604D02*
Y509786D01*
G01X1027927Y508044D02*
Y509346D01*
G01X1028987Y509786D02*
X1027559Y511214D01*
G01X1027927Y509346D02*
X1027119Y510154D01*
G01X1027559Y511214D02*
X1026650D01*
G01X1027119Y510154D02*
X1026210D01*
G01X1027559Y511214D02*
X1026650D01*
G01D02*
X1026150Y511714D01*
G01X1026210Y510154D02*
X1025090Y511274D01*
G01X1026150Y511714D02*
Y513324D01*
G01X1025090Y511274D02*
Y513764D01*
G01X1026150Y513324D02*
X1026650Y513824D01*
G01D02*
X1027506D01*
G01X1025090Y513764D02*
X1026210Y514884D01*
G01X1026650Y513824D02*
X1027506D01*
G01X1026210Y514884D02*
X1027066D01*
G01X1027506Y513824D02*
X1029280Y515598D01*
G01X1027066Y514884D02*
X1028220Y516038D01*
G01X1029280Y515598D02*
Y550100D01*
G01X1028220Y516038D02*
Y520772D01*
G01X1029280Y515598D02*
Y550100D01*
G01X1028220Y523498D02*
Y525328D01*
G01X1029280Y515598D02*
Y550100D01*
G01Y515598D02*
Y550100D01*
G01Y515598D02*
Y550100D01*
G01X1022880Y519779D02*
X1024604Y521503D01*
G01X1021820Y520219D02*
X1023544Y521943D01*
G01X1024604Y521503D02*
Y556768D01*
G01X1023544Y521943D02*
Y524433D01*
G01X1024604Y521503D02*
Y556768D01*
G01Y521503D02*
Y556768D01*
G01Y521503D02*
Y556768D01*
G01Y521503D02*
Y556768D01*
G01Y521503D02*
Y556768D01*
G01Y521503D02*
Y556768D01*
G01Y521503D02*
Y556768D01*
G01X1028274Y488655D02*
Y490485D01*
G01Y493211D02*
Y495041D01*
G01Y497767D02*
Y499597D01*
G01X1029334Y499157D02*
X1032484Y502307D01*
G01X1028274Y499597D02*
X1031424Y502747D01*
G01X1032484Y502307D02*
Y556600D01*
G01X1031424Y502747D02*
Y504613D01*
G01X1032484Y502307D02*
Y556600D01*
G01X1031424Y507267D02*
Y511551D01*
G01X1032484Y502307D02*
Y556600D01*
G01X1031424Y514135D02*
Y551730D01*
G01X1032484Y502307D02*
Y556600D01*
G01X1018518Y505022D02*
Y506852D01*
G01Y509578D02*
Y511408D01*
G01Y514134D02*
Y515964D01*
G01X1017601Y518381D02*
X1019578Y516404D01*
G01X1018518Y515964D02*
X1017161Y517321D01*
G01X1014915Y518381D02*
X1017601D01*
G01X1017161Y517321D02*
X1014475D01*
G01X1014101Y519195D02*
X1014915Y518381D01*
G01X1014475Y517321D02*
X1013041Y518755D01*
G01X1014101Y521610D02*
Y519195D01*
G01X1013041Y518755D02*
Y522050D01*
G01X1014806Y522315D02*
X1014101Y521610D01*
G01X1013041Y522050D02*
X1014366Y523375D01*
G01X1019292Y522315D02*
X1014806D01*
G01X1014366Y523375D02*
X1015271D01*
G01X1019292Y522315D02*
X1014806D01*
G01X1017941Y523375D02*
X1018852D01*
G01X1020780Y523803D02*
X1019292Y522315D01*
G01X1018852Y523375D02*
X1019720Y524243D01*
G01X1020780Y538890D02*
Y523803D01*
G01X1019720Y524243D02*
Y525540D01*
G01X1020780Y538890D02*
Y523803D01*
G01Y538890D02*
Y523803D01*
G01Y538890D02*
Y523803D01*
G01X1024852Y504969D02*
X1027927Y508044D01*
G01X1025912Y504529D02*
X1028987Y507604D01*
G01X1027927Y508044D02*
Y509346D01*
G01X1028987Y507604D02*
Y509786D01*
G01X1027927Y509346D02*
X1027119Y510154D01*
G01X1028987Y509786D02*
X1027559Y511214D01*
G01X1027119Y510154D02*
X1026210D01*
G01D02*
X1025090Y511274D01*
G01X1027559Y511214D02*
X1026650D01*
G01X1026210Y510154D02*
X1025090Y511274D01*
G01X1026650Y511214D02*
X1026150Y511714D01*
G01X1025090Y511274D02*
Y513764D01*
G01X1026150Y511714D02*
Y513324D01*
G01X1025090Y513764D02*
X1026210Y514884D01*
G01X1026150Y513324D02*
X1026650Y513824D01*
G01X1025090Y513764D02*
X1026210Y514884D01*
G01D02*
X1027066D01*
G01X1026650Y513824D02*
X1027506D01*
G01X1027066Y514884D02*
X1028220Y516038D01*
G01X1027506Y513824D02*
X1029280Y515598D01*
G01X1028220Y516038D02*
Y520772D01*
G01Y523498D02*
Y525328D01*
G01X1029280Y515598D02*
Y550100D01*
G01X1021820Y520219D02*
X1023544Y521943D01*
G01X1022880Y519779D02*
X1024604Y521503D01*
G01X1023544Y521943D02*
Y524433D01*
G01X1024604Y521503D02*
Y556768D01*
G01X1028274Y488655D02*
Y490485D01*
G01Y493211D02*
Y495041D01*
G01Y497767D02*
Y499597D01*
G01D02*
X1031424Y502747D01*
G01X1029334Y499157D02*
X1032484Y502307D01*
G01X1031424Y502747D02*
Y504613D01*
G01Y507267D02*
Y511551D01*
G01Y514135D02*
Y551730D01*
G01X1032484Y502307D02*
Y556600D01*
G01X1019720Y524243D02*
Y525540D01*
G01X1020780Y538890D02*
Y523803D01*
G01X1018852Y523375D02*
X1019720Y524243D01*
G01X1020780Y523803D02*
X1019292Y522315D01*
G01X1014366Y523375D02*
X1015271D01*
G01X1017941D02*
X1018852D01*
G01X1019292Y522315D02*
X1014806D01*
G01X1013041Y522050D02*
X1014366Y523375D01*
G01X1014806Y522315D02*
X1014101Y521610D01*
G01X1013041Y518755D02*
Y522050D01*
G01X1014101Y521610D02*
Y519195D01*
G01X1014475Y517321D02*
X1013041Y518755D01*
G01X1014101Y519195D02*
X1014915Y518381D01*
G01X1017161Y517321D02*
X1014475D01*
G01X1014915Y518381D02*
X1017601D01*
G01X1018518Y515964D02*
X1017161Y517321D01*
G01X1017601Y518381D02*
X1019578Y516404D01*
G01X1018518Y505022D02*
Y506852D01*
G01Y509578D02*
Y511408D01*
G01Y514134D02*
Y515964D01*
G01X1028220Y528054D02*
Y529884D01*
G01Y532610D02*
Y534440D01*
G01Y537166D02*
Y549660D01*
G01X1029280Y550100D02*
X1028400Y550980D01*
G01X1028220Y549660D02*
X1027340Y550540D01*
G01X1028400Y550980D02*
Y564372D01*
G01X1027340Y550540D02*
Y554820D01*
G01X1028400Y550980D02*
Y564372D01*
G01X1027340Y557546D02*
Y559376D01*
G01X1028400Y550980D02*
Y564372D01*
G01X1027340Y562102D02*
Y563932D01*
G01X1028400Y564372D02*
X1021092Y571680D01*
G01X1027340Y563932D02*
X1026547Y564725D01*
G01X1028400Y564372D02*
X1021092Y571680D01*
G01X1024625Y566647D02*
X1023342Y567930D01*
G01X1028400Y564372D02*
X1021092Y571680D01*
G01X1021441Y569831D02*
X1020652Y570620D01*
G01X1021092Y571680D02*
X1013374D01*
G01X1020652Y570620D02*
X1018586D01*
G01X1021092Y571680D02*
X1013374D01*
G01X1015862Y570620D02*
X1013814D01*
G01X1013374Y571680D02*
X1011881Y570187D01*
G01X1013814Y570620D02*
X1012941Y569747D01*
G01X1011881Y570187D02*
Y567869D01*
G01X1012941Y569747D02*
Y568046D01*
G01X1023544Y527159D02*
Y528989D01*
G01Y531715D02*
Y533545D01*
G01Y536271D02*
Y538101D01*
G01Y540827D02*
Y542657D01*
G01Y545383D02*
Y547213D01*
G01Y549939D02*
Y551769D01*
G01Y554495D02*
Y556325D01*
G01X1024604Y556768D02*
X1020792Y560580D01*
G01X1023544Y556325D02*
X1022724Y557145D01*
G01X1024604Y556768D02*
X1020792Y560580D01*
G01X1022724Y557145D02*
X1022211Y557146D01*
G01X1024604Y556768D02*
X1020792Y560580D01*
G01X1021081Y558788D02*
X1020349Y559520D01*
G01X1024604Y556768D02*
X1020792Y560580D01*
G01D02*
X1013615D01*
G01X1020349Y559520D02*
X1018891D01*
G01X1020792Y560580D02*
X1013615D01*
G01X1016169Y559520D02*
X1014055D01*
G01X1013615Y560580D02*
X1011843Y558808D01*
G01X1014055Y559520D02*
X1012903Y558368D01*
G01X1011843Y558808D02*
Y556859D01*
G01X1012903Y558368D02*
Y557112D01*
G01X1031424Y554384D02*
Y556160D01*
G01X1032484Y556600D02*
X1031300Y557784D01*
G01X1031424Y556160D02*
X1030240Y557344D01*
G01X1031300Y557784D02*
Y570072D01*
G01X1030240Y557344D02*
Y565502D01*
G01X1031300Y557784D02*
Y570072D01*
G01X1030240Y567978D02*
Y569629D01*
G01X1031300Y570072D02*
X1021592Y579780D01*
G01X1030240Y569629D02*
X1027593Y572276D01*
G01X1031300Y570072D02*
X1021592Y579780D01*
G01X1025665Y574204D02*
X1024371Y575498D01*
G01X1031300Y570072D02*
X1021592Y579780D01*
G01X1022443Y577426D02*
X1021149Y578720D01*
G01X1021592Y579780D02*
X1013965D01*
G01X1021149Y578720D02*
X1018961D01*
G01X1021592Y579780D02*
X1013965D01*
G01X1016235Y578720D02*
X1014405D01*
G01X1013965Y579780D02*
X1012052Y577867D01*
G01X1014405Y578720D02*
X1013112Y577427D01*
G01X1012052Y577867D02*
Y575968D01*
G01X1013112Y577427D02*
Y575803D01*
G01X1019720Y528264D02*
Y529840D01*
G01Y532566D02*
Y534396D01*
G01Y537122D02*
Y538450D01*
G01X1019550Y540120D02*
X1020780Y538890D01*
G01X1019720Y538450D02*
X1019110Y539060D01*
G01X1014549Y540120D02*
X1019550D01*
G01X1019110Y539060D02*
X1018055D01*
G01X1014549Y540120D02*
X1019550D01*
G01X1015331Y539060D02*
X1014109D01*
G01X1013903Y540766D02*
X1014549Y540120D01*
G01X1014109Y539060D02*
X1012843Y540326D01*
G01X1013903Y542156D02*
Y540766D01*
G01X1012843Y540326D02*
Y542596D01*
G01X1014477Y542730D02*
X1013903Y542156D01*
G01X1012843Y542596D02*
X1014037Y543790D01*
G01X1019550Y542730D02*
X1014477D01*
G01X1014037Y543790D02*
X1015276D01*
G01X1019550Y542730D02*
X1014477D01*
G01X1017998Y543790D02*
X1019110D01*
G01X1020780Y543960D02*
X1019550Y542730D01*
G01X1019110Y543790D02*
X1019720Y544400D01*
G01X1020780Y548620D02*
Y543960D01*
G01X1019720Y544400D02*
Y548180D01*
G01X1016900Y552500D02*
X1020780Y548620D01*
G01X1019720Y548180D02*
X1016460Y551440D01*
G01X1013196Y552500D02*
X1016900D01*
G01X1016460Y551440D02*
X1013636D01*
G01X1011620Y550924D02*
X1013196Y552500D01*
G01X1013636Y551440D02*
X1012680Y550484D01*
G01X1011620Y548408D02*
Y550924D01*
G01X1012680Y550484D02*
Y549107D01*
G01X1028220Y528054D02*
Y529884D01*
G01Y532610D02*
Y534440D01*
G01Y537166D02*
Y549660D01*
G01D02*
X1027340Y550540D01*
G01X1029280Y550100D02*
X1028400Y550980D01*
G01X1027340Y550540D02*
Y554820D01*
G01Y557546D02*
Y559376D01*
G01Y562102D02*
Y563932D01*
G01X1028400Y550980D02*
Y564372D01*
G01X1027340Y563932D02*
X1026547Y564725D01*
G01X1024625Y566647D02*
X1023342Y567930D01*
G01X1021441Y569831D02*
X1020652Y570620D01*
G01X1028400Y564372D02*
X1021092Y571680D01*
G01X1020652Y570620D02*
X1018586D01*
G01X1015862D02*
X1013814D01*
G01X1021092Y571680D02*
X1013374D01*
G01X1013814Y570620D02*
X1012941Y569747D01*
G01X1013374Y571680D02*
X1011881Y570187D01*
G01X1012941Y569747D02*
Y568046D01*
G01X1011881Y570187D02*
Y567869D01*
G01X1023544Y527159D02*
Y528989D01*
G01Y531715D02*
Y533545D01*
G01Y536271D02*
Y538101D01*
G01Y540827D02*
Y542657D01*
G01Y545383D02*
Y547213D01*
G01Y549939D02*
Y551769D01*
G01Y554495D02*
Y556325D01*
G01D02*
X1022724Y557145D01*
G01D02*
X1022211Y557146D01*
G01X1021081Y558788D02*
X1020349Y559520D01*
G01D02*
X1018891D01*
G01X1024604Y556768D02*
X1020792Y560580D01*
G01X1020349Y559520D02*
X1018891D01*
G01X1016169D02*
X1014055D01*
G01X1020792Y560580D02*
X1013615D01*
G01X1014055Y559520D02*
X1012903Y558368D01*
G01X1013615Y560580D02*
X1011843Y558808D01*
G01X1012903Y558368D02*
Y557112D01*
G01X1011843Y558808D02*
Y556859D01*
G01X1031424Y554384D02*
Y556160D01*
G01D02*
X1030240Y557344D01*
G01X1032484Y556600D02*
X1031300Y557784D01*
G01X1030240Y557344D02*
Y565502D01*
G01Y567978D02*
Y569629D01*
G01X1031300Y557784D02*
Y570072D01*
G01X1030240Y569629D02*
X1027593Y572276D01*
G01X1025665Y574204D02*
X1024371Y575498D01*
G01X1022443Y577426D02*
X1021149Y578720D01*
G01X1031300Y570072D02*
X1021592Y579780D01*
G01X1021149Y578720D02*
X1018961D01*
G01X1016235D02*
X1014405D01*
G01X1021592Y579780D02*
X1013965D01*
G01X1014405Y578720D02*
X1013112Y577427D01*
G01X1013965Y579780D02*
X1012052Y577867D01*
G01X1013112Y577427D02*
Y575803D01*
G01X1012052Y577867D02*
Y575968D01*
G01X1012680Y550484D02*
Y549107D01*
G01X1011620Y548408D02*
Y550924D01*
G01X1013636Y551440D02*
X1012680Y550484D01*
G01X1011620Y550924D02*
X1013196Y552500D01*
G01X1016460Y551440D02*
X1013636D01*
G01X1013196Y552500D02*
X1016900D01*
G01X1019720Y548180D02*
X1016460Y551440D01*
G01X1016900Y552500D02*
X1020780Y548620D01*
G01X1019720Y544400D02*
Y548180D01*
G01X1020780Y548620D02*
Y543960D01*
G01X1019110Y543790D02*
X1019720Y544400D01*
G01X1020780Y543960D02*
X1019550Y542730D01*
G01X1014037Y543790D02*
X1015276D01*
G01X1017998D02*
X1019110D01*
G01X1019550Y542730D02*
X1014477D01*
G01X1012843Y542596D02*
X1014037Y543790D01*
G01X1014477Y542730D02*
X1013903Y542156D01*
G01X1012843Y540326D02*
Y542596D01*
G01X1013903Y542156D02*
Y540766D01*
G01X1014109Y539060D02*
X1012843Y540326D01*
G01X1013903Y540766D02*
X1014549Y540120D01*
G01X1019110Y539060D02*
X1018055D01*
G01X1015331D02*
X1014109D01*
G01X1014549Y540120D02*
X1019550D01*
G01X1019720Y538450D02*
X1019110Y539060D01*
G01X1019550Y540120D02*
X1020780Y538890D01*
G01X1019720Y528264D02*
Y529840D01*
G01Y532566D02*
Y534396D01*
G01Y537122D02*
Y538450D01*
G01X1077329Y179041D02*
Y147243D01*
G01Y179041D02*
Y147243D01*
G01X1078389Y174959D02*
Y147683D01*
G01X1077329Y147243D02*
X1099320Y125252D01*
G01X1078389Y147683D02*
X1100380Y125692D01*
G01X1082727Y179495D02*
Y148905D01*
G01Y179495D02*
Y148905D01*
G01Y179495D02*
Y148905D01*
G01X1081667Y171906D02*
Y148465D01*
G01X1082727Y148905D02*
X1104580Y127052D01*
G01X1081667Y148465D02*
X1103520Y126612D01*
G01X1078389Y174959D02*
Y147683D01*
G01X1077329Y179041D02*
Y147243D01*
G01X1078389Y147683D02*
X1100380Y125692D01*
G01X1077329Y147243D02*
X1099320Y125252D01*
G01X1081667Y171906D02*
Y148465D01*
G01X1082727Y179495D02*
Y148905D01*
G01X1081667Y148465D02*
X1103520Y126612D01*
G01X1082727Y148905D02*
X1104580Y127052D01*
G01X1077329Y179041D02*
Y147243D01*
G01Y179041D02*
Y147243D01*
G01X1078389Y174959D02*
Y147683D01*
G01X1077329Y147243D02*
X1099320Y125252D01*
G01X1078389Y147683D02*
X1100380Y125692D01*
G01X1078389Y174959D02*
Y147683D01*
G01X1077329Y179041D02*
Y147243D01*
G01X1078389Y147683D02*
X1100380Y125692D01*
G01X1077329Y147243D02*
X1099320Y125252D01*
G01X1081667Y171906D02*
Y148465D01*
G01X1082727Y179495D02*
Y148905D01*
G01X1081667Y148465D02*
X1103520Y126612D01*
G01X1082727Y148905D02*
X1104580Y127052D01*
G01X1082727Y179495D02*
Y148905D01*
G01Y179495D02*
Y148905D01*
G01Y179495D02*
Y148905D01*
G01X1081667Y171906D02*
Y148465D01*
G01X1082727Y148905D02*
X1104580Y127052D01*
G01X1081667Y148465D02*
X1103520Y126612D01*
G01X1078389Y179041D02*
Y176959D01*
G01X1081667Y179495D02*
Y177155D01*
G01Y175155D02*
Y173906D01*
G01X1078389Y179041D02*
Y176959D01*
G01X1081667Y179495D02*
Y177155D01*
G01Y175155D02*
Y173906D01*
G01X1078389Y179041D02*
Y176959D01*
G01Y179041D02*
Y176959D01*
G01X1081667Y179495D02*
Y177155D01*
G01Y175155D02*
Y173906D01*
G01Y179495D02*
Y177155D01*
G01Y175155D02*
Y173906D01*
G01X1079281Y419187D02*
Y460309D01*
G01X1080341Y419187D02*
Y459869D01*
G01X1079281Y460309D02*
X1114137Y495165D01*
G01X1080341Y459869D02*
X1115197Y494725D01*
G01X1083791Y419537D02*
Y457862D01*
G01X1082731Y419537D02*
Y458302D01*
G01X1083791Y457862D02*
X1118141Y492212D01*
G01X1082731Y458302D02*
X1111500Y487071D01*
G01X1083791Y457862D02*
X1118141Y492212D01*
G01X1083791Y457862D02*
X1118141Y492212D01*
G01X1080341Y419187D02*
Y459869D01*
G01X1079281Y419187D02*
Y460309D01*
G01X1080341Y459869D02*
X1115197Y494725D01*
G01X1079281Y460309D02*
X1114137Y495165D01*
G01X1082731Y419537D02*
Y458302D01*
G01X1083791Y419537D02*
Y457862D01*
G01X1082731Y458302D02*
X1111500Y487071D01*
G01X1083791Y457862D02*
X1118141Y492212D01*
G01X1079281Y419187D02*
Y460309D01*
G01X1080341Y419187D02*
Y459869D01*
G01X1079281Y460309D02*
X1114137Y495165D01*
G01X1080341Y459869D02*
X1115197Y494725D01*
G01X1079281Y419187D02*
Y460309D01*
G01X1080341Y419187D02*
Y459869D01*
G01X1079281Y460309D02*
X1114137Y495165D01*
G01X1080341Y459869D02*
X1115197Y494725D01*
G01X1083791Y419537D02*
Y457862D01*
G01X1082731Y419537D02*
Y458302D01*
G01X1083791Y457862D02*
X1118141Y492212D01*
G01X1082731Y458302D02*
X1111500Y487071D01*
G01X1083791Y457862D02*
X1118141Y492212D01*
G01X1083791Y457862D02*
X1118141Y492212D01*
G01X1080341Y419187D02*
Y459869D01*
G01X1079281Y419187D02*
Y460309D01*
G01X1080341Y459869D02*
X1115197Y494725D01*
G01X1079281Y460309D02*
X1114137Y495165D01*
G01X1082731Y419537D02*
Y458302D01*
G01X1083791Y419537D02*
Y457862D01*
G01X1082731Y458302D02*
X1111500Y487071D01*
G01X1083791Y457862D02*
X1118141Y492212D01*
G01X1082731Y419537D02*
Y458302D01*
G01X1083791Y419537D02*
Y457862D01*
G01X1082731Y458302D02*
X1111500Y487071D01*
G01X1083791Y457862D02*
X1118141Y492212D01*
G01X1116386Y33291D02*
X1115675Y32580D01*
G01X1117446Y32848D02*
X1116118Y31520D01*
G01X1115675Y32580D02*
X1115159D01*
G01X1116118Y31520D02*
X1115136D01*
G01X1122632Y33732D02*
X1119440Y30540D01*
G01X1122632Y33732D02*
X1119440Y30540D01*
G01X1117446Y32848D02*
X1116118Y31520D01*
G01X1116386Y33291D02*
X1115675Y32580D01*
G01X1116118Y31520D02*
X1115136D01*
G01X1115675Y32580D02*
X1115159D01*
G01X1122632Y33732D02*
X1119440Y30540D01*
G01X1116386Y33291D02*
X1115675Y32580D01*
G01X1117446Y32848D02*
X1116118Y31520D01*
G01X1115675Y32580D02*
X1115159D01*
G01X1116118Y31520D02*
X1115136D01*
G01X1117446Y32848D02*
X1116118Y31520D01*
G01X1116386Y33291D02*
X1115675Y32580D01*
G01X1116118Y31520D02*
X1115136D01*
G01X1115675Y32580D02*
X1115159D01*
G01X1122632Y33732D02*
X1119440Y30540D01*
G01X1149298Y21131D02*
Y13554D01*
G01X1150358Y19620D02*
Y20688D01*
G01X1153172Y25005D02*
X1149298Y21131D01*
G01X1150358Y20688D02*
X1154232Y24562D01*
G01X1153172Y119138D02*
Y25005D01*
G01X1154232Y24562D02*
Y36580D01*
G01X1153172Y119138D02*
Y25005D01*
G01Y119138D02*
Y25005D01*
G01X1154998Y18999D02*
Y21231D01*
G01X1156058Y19920D02*
Y20788D01*
G01X1154998Y21231D02*
X1158437Y24670D01*
G01X1156058Y20788D02*
X1157032Y21762D01*
G01X1154998Y21231D02*
X1158437Y24670D01*
G01X1154998Y21231D02*
X1158437Y24670D01*
G01X1154232Y24562D02*
Y36580D01*
G01X1153172Y119138D02*
Y25005D01*
G01X1150358Y20688D02*
X1154232Y24562D01*
G01X1153172Y25005D02*
X1149298Y21131D01*
G01X1150358Y19620D02*
Y20688D01*
G01X1149298Y21131D02*
Y13554D01*
G01X1156058Y19920D02*
Y20788D01*
G01X1154998Y18999D02*
Y21231D01*
G01X1156058Y20788D02*
X1157032Y21762D01*
G01X1154998Y21231D02*
X1158437Y24670D01*
G01X1122632Y33732D02*
X1119440Y30540D01*
G01X1122632Y33732D02*
X1119440Y30540D01*
G01X1115439Y49500D02*
X1116386Y48553D01*
G01X1114340Y52100D02*
X1117446Y48994D01*
G01X1116386Y48553D02*
Y46020D01*
G01Y41880D02*
Y40920D01*
G01Y36580D02*
Y33291D01*
G01X1117446Y48994D02*
Y32848D01*
G01X1116360Y97809D02*
Y63931D01*
G01X1117421Y98251D02*
Y82820D01*
G01X1116360Y97809D02*
Y63931D01*
G01X1117421Y80580D02*
Y79820D01*
G01X1116360Y97809D02*
Y63931D01*
G01X1117421Y77580D02*
Y76820D01*
G01X1116360Y97809D02*
Y63931D01*
G01X1117420Y74579D02*
Y63488D01*
G01X1116360Y63931D02*
X1112486Y60057D01*
G01X1117420Y63488D02*
X1113546Y59614D01*
G01X1112486Y60057D02*
Y51354D01*
G01X1113546Y59614D02*
Y57420D01*
G01X1119440Y52314D02*
X1122632Y49122D01*
G01X1119440Y49715D02*
X1120538D01*
G01X1119440Y52314D02*
X1122632Y49122D01*
G01X1120538Y49715D02*
X1121572Y48681D01*
G01X1122632Y49122D02*
Y33732D01*
G01X1121572Y48681D02*
Y45906D01*
G01X1122632Y49122D02*
Y33732D01*
G01X1121572Y42080D02*
Y40707D01*
G01X1122632Y49122D02*
Y33732D01*
G01X1121572Y36793D02*
Y34172D01*
G01D02*
X1120549Y33149D01*
G01D02*
X1119440D01*
G01X1122521Y105676D02*
Y77120D01*
G01Y74880D02*
Y62751D01*
G01X1121461Y105233D02*
Y63194D01*
G01X1122521Y62751D02*
X1121627Y61857D01*
G01X1120043Y60273D02*
X1118746Y58976D01*
G01X1121461Y63194D02*
X1117686Y59419D01*
G01X1118746Y58976D02*
Y57554D01*
G01X1117686Y59419D02*
Y51468D01*
G01X1114340Y52100D02*
X1117446Y48994D01*
G01X1115439Y49500D02*
X1116386Y48553D01*
G01X1117446Y48994D02*
Y32848D01*
G01X1116386Y48553D02*
Y46020D01*
G01X1117446Y48994D02*
Y32848D01*
G01X1116386Y41880D02*
Y40920D01*
G01X1117446Y48994D02*
Y32848D01*
G01X1116386Y36580D02*
Y33291D01*
G01X1117421Y98251D02*
Y82820D01*
G01Y80580D02*
Y79820D01*
G01Y77580D02*
Y76820D01*
G01X1117420Y74579D02*
Y63488D01*
G01X1116360Y97809D02*
Y63931D01*
G01X1117420Y63488D02*
X1113546Y59614D01*
G01X1116360Y63931D02*
X1112486Y60057D01*
G01X1113546Y59614D02*
Y57420D01*
G01X1112486Y60057D02*
Y51354D01*
G01X1119440Y49715D02*
X1120538D01*
G01D02*
X1121572Y48681D01*
G01X1119440Y52314D02*
X1122632Y49122D01*
G01X1121572Y48681D02*
Y45906D01*
G01Y42080D02*
Y40707D01*
G01Y36793D02*
Y34172D01*
G01X1122632Y49122D02*
Y33732D01*
G01X1121572Y34172D02*
X1120549Y33149D01*
G01D02*
X1119440D01*
G01X1121461Y105233D02*
Y63194D01*
G01X1122521Y105676D02*
Y77120D01*
G01X1121461Y105233D02*
Y63194D01*
G01X1122521Y74880D02*
Y62751D01*
G01X1121461Y63194D02*
X1117686Y59419D01*
G01X1122521Y62751D02*
X1121627Y61857D01*
G01X1121461Y63194D02*
X1117686Y59419D01*
G01X1120043Y60273D02*
X1118746Y58976D01*
G01X1117686Y59419D02*
Y51468D01*
G01X1118746Y58976D02*
Y57554D01*
G01X1115439Y49500D02*
X1116386Y48553D01*
G01X1114340Y52100D02*
X1117446Y48994D01*
G01X1116386Y48553D02*
Y46020D01*
G01Y41880D02*
Y40920D01*
G01Y36580D02*
Y33291D01*
G01X1117446Y48994D02*
Y32848D01*
G01X1116360Y97809D02*
Y63931D01*
G01X1117421Y98251D02*
Y82820D01*
G01X1116360Y97809D02*
Y63931D01*
G01X1117421Y80580D02*
Y79820D01*
G01X1116360Y97809D02*
Y63931D01*
G01X1117421Y77580D02*
Y76820D01*
G01X1116360Y97809D02*
Y63931D01*
G01X1117420Y74579D02*
Y63488D01*
G01X1116360Y63931D02*
X1112486Y60057D01*
G01X1117420Y63488D02*
X1113546Y59614D01*
G01X1112486Y60057D02*
Y51354D01*
G01X1113546Y59614D02*
Y57420D01*
G01X1114340Y52100D02*
X1117446Y48994D01*
G01X1115439Y49500D02*
X1116386Y48553D01*
G01X1117446Y48994D02*
Y32848D01*
G01X1116386Y48553D02*
Y46020D01*
G01X1117446Y48994D02*
Y32848D01*
G01X1116386Y41880D02*
Y40920D01*
G01X1117446Y48994D02*
Y32848D01*
G01X1116386Y36580D02*
Y33291D01*
G01X1117421Y98251D02*
Y82820D01*
G01Y80580D02*
Y79820D01*
G01Y77580D02*
Y76820D01*
G01X1117420Y74579D02*
Y63488D01*
G01X1116360Y97809D02*
Y63931D01*
G01X1117420Y63488D02*
X1113546Y59614D01*
G01X1116360Y63931D02*
X1112486Y60057D01*
G01X1113546Y59614D02*
Y57420D01*
G01X1112486Y60057D02*
Y51354D01*
G01X1119440Y49715D02*
X1120538D01*
G01D02*
X1121572Y48681D01*
G01X1119440Y52314D02*
X1122632Y49122D01*
G01X1121572Y48681D02*
Y45906D01*
G01Y42080D02*
Y40707D01*
G01Y36793D02*
Y34172D01*
G01X1122632Y49122D02*
Y33732D01*
G01X1121572Y34172D02*
X1120549Y33149D01*
G01D02*
X1119440D01*
G01X1121461Y105233D02*
Y63194D01*
G01X1122521Y105676D02*
Y77120D01*
G01X1121461Y105233D02*
Y63194D01*
G01X1122521Y74880D02*
Y62751D01*
G01X1121461Y63194D02*
X1117686Y59419D01*
G01X1122521Y62751D02*
X1121627Y61857D01*
G01X1121461Y63194D02*
X1117686Y59419D01*
G01X1120043Y60273D02*
X1118746Y58976D01*
G01X1117686Y59419D02*
Y51468D01*
G01X1118746Y58976D02*
Y57554D01*
G01X1154232Y38820D02*
Y39580D01*
G01Y41820D02*
Y118695D01*
G01Y38820D02*
Y39580D01*
G01Y41820D02*
Y118695D01*
G01X1119440Y52314D02*
X1122632Y49122D01*
G01X1119440Y49715D02*
X1120538D01*
G01X1119440Y52314D02*
X1122632Y49122D01*
G01X1120538Y49715D02*
X1121572Y48681D01*
G01X1122632Y49122D02*
Y33732D01*
G01X1121572Y48681D02*
Y45906D01*
G01X1122632Y49122D02*
Y33732D01*
G01X1121572Y42080D02*
Y40707D01*
G01X1122632Y49122D02*
Y33732D01*
G01X1121572Y36793D02*
Y34172D01*
G01D02*
X1120549Y33149D01*
G01D02*
X1119440D01*
G01X1122521Y105676D02*
Y77120D01*
G01Y74880D02*
Y62751D01*
G01X1121461Y105233D02*
Y63194D01*
G01X1122521Y62751D02*
X1121627Y61857D01*
G01X1120043Y60273D02*
X1118746Y58976D01*
G01X1121461Y63194D02*
X1117686Y59419D01*
G01X1118746Y58976D02*
Y57554D01*
G01X1117686Y59419D02*
Y51468D01*
G01X1099320Y125252D02*
Y121910D01*
G01X1100380Y125692D02*
Y122350D01*
G01X1099320Y121910D02*
X1100830Y120400D01*
G01X1100380Y122350D02*
X1101581Y121149D01*
G01X1100830Y120397D02*
X1101720Y119507D01*
G01X1101581Y121146D02*
X1102780Y119947D01*
G01X1101720Y119507D02*
Y116097D01*
G01X1102780Y119947D02*
Y116537D01*
G01X1101720Y116097D02*
X1104611Y113206D01*
G01X1102780Y116537D02*
X1105051Y114266D01*
G01X1104611Y113206D02*
X1107593D01*
G01X1105051Y114266D02*
X1108033D01*
G01X1107593Y113206D02*
X1108934Y111865D01*
G01X1108033Y114266D02*
X1109994Y112305D01*
G01X1108934Y111865D02*
Y110642D01*
G01X1109994Y112305D02*
Y110202D01*
G01X1108934Y110642D02*
X1107716Y109424D01*
G01X1109994Y110202D02*
X1108776Y108984D01*
G01X1107716Y109424D02*
Y107312D01*
G01X1108776Y108984D02*
Y107752D01*
G01X1107716Y107312D02*
X1110103Y104925D01*
G01X1108776Y107752D02*
X1110543Y105985D01*
G01X1107716Y107312D02*
X1110103Y104925D01*
G01D02*
X1112217D01*
G01X1110543Y105985D02*
X1111774D01*
G01X1112217Y104925D02*
X1113647Y106355D01*
G01D02*
X1114872D01*
G01X1111774Y105985D02*
X1113204Y107415D01*
G01X1113647Y106355D02*
X1114872D01*
G01X1113204Y107415D02*
X1115315D01*
G01X1113647Y106355D02*
X1114872D01*
G01D02*
X1116648Y104579D01*
G01X1115315Y107415D02*
X1117708Y105022D01*
G01X1116648Y104579D02*
Y103356D01*
G01X1117708Y105022D02*
Y102912D01*
G01X1116648Y103356D02*
X1115216Y101924D01*
G01X1117708Y102912D02*
X1116276Y101481D01*
G01X1115216Y101924D02*
Y98953D01*
G01X1116276Y101481D02*
Y99396D01*
G01X1115216Y98953D02*
X1116360Y97809D01*
G01X1116276Y99396D02*
X1117421Y98251D01*
G01X1104580Y127052D02*
Y123617D01*
G01X1103520Y126612D02*
Y123174D01*
G01X1104580Y123617D02*
X1122521Y105676D01*
G01X1103520Y123174D02*
X1121461Y105233D01*
G01X1100380Y125692D02*
Y122350D01*
G01X1099320Y125252D02*
Y121910D01*
G01X1100380Y122350D02*
X1101581Y121149D01*
G01X1099320Y121910D02*
X1100830Y120400D01*
G01X1101581Y121146D02*
X1102780Y119947D01*
G01X1100830Y120397D02*
X1101720Y119507D01*
G01X1102780Y119947D02*
Y116537D01*
G01X1101720Y119507D02*
Y116097D01*
G01X1102780Y116537D02*
X1105051Y114266D01*
G01X1101720Y116097D02*
X1104611Y113206D01*
G01X1105051Y114266D02*
X1108033D01*
G01X1104611Y113206D02*
X1107593D01*
G01X1108033Y114266D02*
X1109994Y112305D01*
G01X1107593Y113206D02*
X1108934Y111865D01*
G01X1109994Y112305D02*
Y110202D01*
G01X1108934Y111865D02*
Y110642D01*
G01X1109994Y110202D02*
X1108776Y108984D01*
G01X1108934Y110642D02*
X1107716Y109424D01*
G01X1108776Y108984D02*
Y107752D01*
G01X1107716Y109424D02*
Y107312D01*
G01X1108776Y107752D02*
X1110543Y105985D01*
G01D02*
X1111774D01*
G01X1107716Y107312D02*
X1110103Y104925D01*
G01X1110543Y105985D02*
X1111774D01*
G01X1110103Y104925D02*
X1112217D01*
G01X1111774Y105985D02*
X1113204Y107415D01*
G01X1112217Y104925D02*
X1113647Y106355D01*
G01X1111774Y105985D02*
X1113204Y107415D01*
G01D02*
X1115315D01*
G01D02*
X1117708Y105022D01*
G01X1113647Y106355D02*
X1114872D01*
G01X1115315Y107415D02*
X1117708Y105022D01*
G01X1114872Y106355D02*
X1116648Y104579D01*
G01X1117708Y105022D02*
Y102912D01*
G01X1116648Y104579D02*
Y103356D01*
G01X1117708Y102912D02*
X1116276Y101481D01*
G01X1116648Y103356D02*
X1115216Y101924D01*
G01X1116276Y101481D02*
Y99396D01*
G01X1115216Y101924D02*
Y98953D01*
G01X1116276Y99396D02*
X1117421Y98251D01*
G01X1115216Y98953D02*
X1116360Y97809D01*
G01X1103520Y126612D02*
Y123174D01*
G01X1104580Y127052D02*
Y123617D01*
G01X1103520Y123174D02*
X1121461Y105233D01*
G01X1104580Y123617D02*
X1122521Y105676D01*
G01X1099320Y125252D02*
Y121910D01*
G01X1100380Y125692D02*
Y122350D01*
G01X1099320Y121910D02*
X1100830Y120400D01*
G01X1100380Y122350D02*
X1101581Y121149D01*
G01X1100830Y120397D02*
X1101720Y119507D01*
G01X1101581Y121146D02*
X1102780Y119947D01*
G01X1101720Y119507D02*
Y116097D01*
G01X1102780Y119947D02*
Y116537D01*
G01X1101720Y116097D02*
X1104611Y113206D01*
G01X1102780Y116537D02*
X1105051Y114266D01*
G01X1104611Y113206D02*
X1107593D01*
G01X1105051Y114266D02*
X1108033D01*
G01X1107593Y113206D02*
X1108934Y111865D01*
G01X1108033Y114266D02*
X1109994Y112305D01*
G01X1108934Y111865D02*
Y110642D01*
G01X1109994Y112305D02*
Y110202D01*
G01X1108934Y110642D02*
X1107716Y109424D01*
G01X1109994Y110202D02*
X1108776Y108984D01*
G01X1107716Y109424D02*
Y107312D01*
G01X1108776Y108984D02*
Y107752D01*
G01X1107716Y107312D02*
X1110103Y104925D01*
G01X1108776Y107752D02*
X1110543Y105985D01*
G01X1107716Y107312D02*
X1110103Y104925D01*
G01D02*
X1112217D01*
G01X1110543Y105985D02*
X1111774D01*
G01X1112217Y104925D02*
X1113647Y106355D01*
G01D02*
X1114872D01*
G01X1111774Y105985D02*
X1113204Y107415D01*
G01X1113647Y106355D02*
X1114872D01*
G01X1113204Y107415D02*
X1115315D01*
G01X1113647Y106355D02*
X1114872D01*
G01D02*
X1116648Y104579D01*
G01X1115315Y107415D02*
X1117708Y105022D01*
G01X1116648Y104579D02*
Y103356D01*
G01X1117708Y105022D02*
Y102912D01*
G01X1116648Y103356D02*
X1115216Y101924D01*
G01X1117708Y102912D02*
X1116276Y101481D01*
G01X1115216Y101924D02*
Y98953D01*
G01X1116276Y101481D02*
Y99396D01*
G01X1115216Y98953D02*
X1116360Y97809D01*
G01X1116276Y99396D02*
X1117421Y98251D01*
G01X1100380Y125692D02*
Y122350D01*
G01X1099320Y125252D02*
Y121910D01*
G01X1100380Y122350D02*
X1101581Y121149D01*
G01X1099320Y121910D02*
X1100830Y120400D01*
G01X1101581Y121146D02*
X1102780Y119947D01*
G01X1100830Y120397D02*
X1101720Y119507D01*
G01X1102780Y119947D02*
Y116537D01*
G01X1101720Y119507D02*
Y116097D01*
G01X1102780Y116537D02*
X1105051Y114266D01*
G01X1101720Y116097D02*
X1104611Y113206D01*
G01X1105051Y114266D02*
X1108033D01*
G01X1104611Y113206D02*
X1107593D01*
G01X1108033Y114266D02*
X1109994Y112305D01*
G01X1107593Y113206D02*
X1108934Y111865D01*
G01X1109994Y112305D02*
Y110202D01*
G01X1108934Y111865D02*
Y110642D01*
G01X1109994Y110202D02*
X1108776Y108984D01*
G01X1108934Y110642D02*
X1107716Y109424D01*
G01X1108776Y108984D02*
Y107752D01*
G01X1107716Y109424D02*
Y107312D01*
G01X1108776Y107752D02*
X1110543Y105985D01*
G01D02*
X1111774D01*
G01X1107716Y107312D02*
X1110103Y104925D01*
G01X1110543Y105985D02*
X1111774D01*
G01X1110103Y104925D02*
X1112217D01*
G01X1111774Y105985D02*
X1113204Y107415D01*
G01X1112217Y104925D02*
X1113647Y106355D01*
G01X1111774Y105985D02*
X1113204Y107415D01*
G01D02*
X1115315D01*
G01D02*
X1117708Y105022D01*
G01X1113647Y106355D02*
X1114872D01*
G01X1115315Y107415D02*
X1117708Y105022D01*
G01X1114872Y106355D02*
X1116648Y104579D01*
G01X1117708Y105022D02*
Y102912D01*
G01X1116648Y104579D02*
Y103356D01*
G01X1117708Y102912D02*
X1116276Y101481D01*
G01X1116648Y103356D02*
X1115216Y101924D01*
G01X1116276Y101481D02*
Y99396D01*
G01X1115216Y101924D02*
Y98953D01*
G01X1116276Y99396D02*
X1117421Y98251D01*
G01X1115216Y98953D02*
X1116360Y97809D01*
G01X1103520Y126612D02*
Y123174D01*
G01X1104580Y127052D02*
Y123617D01*
G01X1103520Y123174D02*
X1121461Y105233D01*
G01X1104580Y123617D02*
X1122521Y105676D01*
G01X1153738Y119704D02*
X1153172Y119138D01*
G01X1154232Y118695D02*
X1154798Y119261D01*
G01X1153738Y121050D02*
Y119704D01*
G01X1154798Y119261D02*
Y121490D01*
G01X1152083Y122705D02*
X1153738Y121050D01*
G01X1154798Y121490D02*
X1152523Y123765D01*
G01X1150738Y122705D02*
X1152083D01*
G01X1152523Y123765D02*
X1150298D01*
G01X1148711Y120678D02*
X1150738Y122705D01*
G01D02*
X1152083D01*
G01X1150298Y123765D02*
X1148271Y121738D01*
G01X1146790Y120678D02*
X1148711D01*
G01X1148271Y121738D02*
X1147230D01*
G01X1144307Y123161D02*
X1146790Y120678D01*
G01X1147230Y121738D02*
X1145367Y123601D01*
G01X1144307Y125270D02*
Y123161D01*
G01X1145367Y123601D02*
Y124830D01*
G01X1146418Y127381D02*
X1144307Y125270D01*
G01X1145367Y124830D02*
X1147478Y126941D01*
G01X1146418Y128714D02*
Y127381D01*
G01X1147478Y126941D02*
Y129154D01*
G01X1109403Y165729D02*
X1146418Y128714D01*
G01X1147478Y129154D02*
X1121307Y155325D01*
G01X1109403Y165729D02*
X1146418Y128714D01*
G01X1109403Y165729D02*
X1146418Y128714D01*
G01X1109403Y165729D02*
X1146418Y128714D01*
G01X1109403Y165729D02*
X1146418Y128714D01*
G01X1109403Y165729D02*
X1146418Y128714D01*
G01X1157620Y122909D02*
X1113312Y167217D01*
G01X1158680Y123352D02*
X1114372Y167660D01*
G01X1147478Y129154D02*
X1121307Y155325D01*
G01X1109403Y165729D02*
X1146418Y128714D01*
G01X1147478Y126941D02*
Y129154D01*
G01X1146418Y128714D02*
Y127381D01*
G01X1145367Y124830D02*
X1147478Y126941D01*
G01X1146418Y127381D02*
X1144307Y125270D01*
G01X1145367Y123601D02*
Y124830D01*
G01X1144307Y125270D02*
Y123161D01*
G01X1147230Y121738D02*
X1145367Y123601D01*
G01X1144307Y123161D02*
X1146790Y120678D01*
G01X1148271Y121738D02*
X1147230D01*
G01X1146790Y120678D02*
X1148711D01*
G01X1150298Y123765D02*
X1148271Y121738D01*
G01X1148711Y120678D02*
X1150738Y122705D01*
G01X1152523Y123765D02*
X1150298D01*
G01D02*
X1148271Y121738D01*
G01X1150738Y122705D02*
X1152083D01*
G01X1154798Y121490D02*
X1152523Y123765D01*
G01X1152083Y122705D02*
X1153738Y121050D01*
G01X1154798Y119261D02*
Y121490D01*
G01X1153738Y121050D02*
Y119704D01*
G01X1154232Y118695D02*
X1154798Y119261D01*
G01X1153738Y119704D02*
X1153172Y119138D01*
G01X1158680Y123352D02*
X1114372Y167660D01*
G01X1157620Y122909D02*
X1113312Y167217D01*
G01X1104580Y127052D02*
Y123617D01*
G01X1103520Y126612D02*
Y123174D01*
G01X1104580Y123617D02*
X1122521Y105676D01*
G01X1103520Y123174D02*
X1121461Y105233D01*
G01X1119963Y156669D02*
X1119256Y157376D01*
G01X1117912Y158720D02*
X1116981Y159651D01*
G01X1115637Y160995D02*
X1114901Y161731D01*
G01X1113557Y163075D02*
X1112514Y164118D01*
G01X1111170Y165462D02*
X1110463Y166169D01*
G01X1109403Y186124D02*
Y165729D01*
G01X1110463Y166169D02*
Y170112D01*
G01X1109403Y186124D02*
Y165729D01*
G01X1110463Y172012D02*
Y173012D01*
G01X1109403Y186124D02*
Y165729D01*
G01X1110463Y174912D02*
Y175912D01*
G01X1109403Y186124D02*
Y165729D01*
G01X1110463Y177812D02*
Y178812D01*
G01X1109403Y186124D02*
Y165729D01*
G01X1110463Y180712D02*
Y182127D01*
G01X1109403Y186124D02*
Y165729D01*
G01X1110463Y184027D02*
Y186124D01*
G01X1113312Y167217D02*
Y186124D01*
G01X1114372Y167660D02*
Y186124D01*
G01X1110463Y166169D02*
Y170112D01*
G01Y172012D02*
Y173012D01*
G01Y174912D02*
Y175912D01*
G01Y177812D02*
Y178812D01*
G01Y180712D02*
Y182127D01*
G01Y184027D02*
Y186124D01*
G01X1109403D02*
Y165729D01*
G01X1119963Y156669D02*
X1119256Y157376D01*
G01X1117912Y158720D02*
X1116981Y159651D01*
G01X1115637Y160995D02*
X1114901Y161731D01*
G01X1113557Y163075D02*
X1112514Y164118D01*
G01X1111170Y165462D02*
X1110463Y166169D01*
G01X1114372Y167660D02*
Y186124D01*
G01X1113312Y167217D02*
Y186124D01*
G01X1135420Y199020D02*
X1152640Y181800D01*
G01X1136169Y199771D02*
X1136876Y199064D01*
G01X1135420Y199020D02*
X1152640Y181800D01*
G01X1138220Y197720D02*
X1138986Y196954D01*
G01X1135420Y199020D02*
X1152640Y181800D01*
G01X1140330Y195610D02*
X1141037Y194903D01*
G01X1135420Y199020D02*
X1152640Y181800D01*
G01X1142381Y193559D02*
X1143178Y192762D01*
G01X1135420Y199020D02*
X1152640Y181800D01*
G01X1144523Y191417D02*
X1145388Y190552D01*
G01X1135420Y199020D02*
X1152640Y181800D01*
G01X1146732Y189208D02*
X1147439Y188501D01*
G01X1135420Y199020D02*
X1152640Y181800D01*
G01X1148783Y187157D02*
X1149727Y186213D01*
G01X1135420Y199020D02*
X1152640Y181800D01*
G01X1151071Y184869D02*
X1153080Y182860D01*
G01X1152640Y181800D02*
X1162017D01*
G01X1153080Y182860D02*
X1162457D01*
G01X1138511Y203089D02*
X1139232Y202368D01*
G01X1139940Y201023D02*
X1140577D01*
G01D02*
X1141767Y199833D01*
G01X1142475Y198488D02*
X1143112D01*
G01D02*
X1143977Y197623D01*
G01X1144685Y196279D02*
X1145321D01*
G01D02*
X1156855Y184745D01*
G01X1139260Y203840D02*
X1157295Y185805D01*
G01X1156855Y184745D02*
X1164472D01*
G01X1136169Y199771D02*
X1136876Y199064D01*
G01X1138220Y197720D02*
X1138986Y196954D01*
G01X1140330Y195610D02*
X1141037Y194903D01*
G01X1142381Y193559D02*
X1143178Y192762D01*
G01X1144523Y191417D02*
X1145388Y190552D01*
G01X1146732Y189208D02*
X1147439Y188501D01*
G01X1148783Y187157D02*
X1149727Y186213D01*
G01X1151071Y184869D02*
X1153080Y182860D01*
G01X1135420Y199020D02*
X1152640Y181800D01*
G01X1153080Y182860D02*
X1162457D01*
G01X1152640Y181800D02*
X1162017D01*
G01X1139260Y203840D02*
X1157295Y185805D01*
G01X1138511Y203089D02*
X1139232Y202368D01*
G01X1139260Y203840D02*
X1157295Y185805D01*
G01X1139940Y201023D02*
X1140577D01*
G01X1139260Y203840D02*
X1157295Y185805D01*
G01X1140577Y201023D02*
X1141767Y199833D01*
G01X1139260Y203840D02*
X1157295Y185805D01*
G01X1142475Y198488D02*
X1143112D01*
G01X1139260Y203840D02*
X1157295Y185805D01*
G01X1143112Y198488D02*
X1143977Y197623D01*
G01X1139260Y203840D02*
X1157295Y185805D01*
G01X1144685Y196279D02*
X1145321D01*
G01X1139260Y203840D02*
X1157295Y185805D01*
G01X1145321Y196279D02*
X1156855Y184745D01*
G01D02*
X1164472D01*
G01X1135420Y199020D02*
X1152640Y181800D01*
G01X1136169Y199771D02*
X1136876Y199064D01*
G01X1135420Y199020D02*
X1152640Y181800D01*
G01X1138220Y197720D02*
X1138986Y196954D01*
G01X1135420Y199020D02*
X1152640Y181800D01*
G01X1140330Y195610D02*
X1141037Y194903D01*
G01X1135420Y199020D02*
X1152640Y181800D01*
G01X1142381Y193559D02*
X1143178Y192762D01*
G01X1135420Y199020D02*
X1152640Y181800D01*
G01X1144523Y191417D02*
X1145388Y190552D01*
G01X1135420Y199020D02*
X1152640Y181800D01*
G01X1146732Y189208D02*
X1147439Y188501D01*
G01X1135420Y199020D02*
X1152640Y181800D01*
G01X1148783Y187157D02*
X1149727Y186213D01*
G01X1135420Y199020D02*
X1152640Y181800D01*
G01X1151071Y184869D02*
X1153080Y182860D01*
G01X1152640Y181800D02*
X1162017D01*
G01X1153080Y182860D02*
X1162457D01*
G01X1138511Y203089D02*
X1139232Y202368D01*
G01X1139940Y201023D02*
X1140577D01*
G01D02*
X1141767Y199833D01*
G01X1142475Y198488D02*
X1143112D01*
G01D02*
X1143977Y197623D01*
G01X1144685Y196279D02*
X1145321D01*
G01D02*
X1156855Y184745D01*
G01X1139260Y203840D02*
X1157295Y185805D01*
G01X1156855Y184745D02*
X1164472D01*
G01X1136169Y199771D02*
X1136876Y199064D01*
G01X1138220Y197720D02*
X1138986Y196954D01*
G01X1140330Y195610D02*
X1141037Y194903D01*
G01X1142381Y193559D02*
X1143178Y192762D01*
G01X1144523Y191417D02*
X1145388Y190552D01*
G01X1146732Y189208D02*
X1147439Y188501D01*
G01X1148783Y187157D02*
X1149727Y186213D01*
G01X1151071Y184869D02*
X1153080Y182860D01*
G01X1135420Y199020D02*
X1152640Y181800D01*
G01X1153080Y182860D02*
X1162457D01*
G01X1152640Y181800D02*
X1162017D01*
G01X1139260Y203840D02*
X1157295Y185805D01*
G01X1138511Y203089D02*
X1139232Y202368D01*
G01X1139260Y203840D02*
X1157295Y185805D01*
G01X1139940Y201023D02*
X1140577D01*
G01X1139260Y203840D02*
X1157295Y185805D01*
G01X1140577Y201023D02*
X1141767Y199833D01*
G01X1139260Y203840D02*
X1157295Y185805D01*
G01X1142475Y198488D02*
X1143112D01*
G01X1139260Y203840D02*
X1157295Y185805D01*
G01X1143112Y198488D02*
X1143977Y197623D01*
G01X1139260Y203840D02*
X1157295Y185805D01*
G01X1144685Y196279D02*
X1145321D01*
G01X1139260Y203840D02*
X1157295Y185805D01*
G01X1145321Y196279D02*
X1156855Y184745D01*
G01D02*
X1164472D01*
G01X1140815Y422445D02*
X1144170Y425800D01*
G01X1141566Y421696D02*
X1144610Y424740D01*
G01X1144170Y425800D02*
X1157830D01*
G01X1144610Y424740D02*
X1158270D01*
G01X1149787Y421345D02*
X1159542D01*
G01X1149787Y422405D02*
X1159102D01*
G01X1141566Y421696D02*
X1144610Y424740D01*
G01X1140815Y422445D02*
X1144170Y425800D01*
G01X1144610Y424740D02*
X1158270D01*
G01X1144170Y425800D02*
X1157830D01*
G01X1149787Y422405D02*
X1159102D01*
G01X1149787Y421345D02*
X1159542D01*
G01X1108901Y422387D02*
Y444756D01*
G01X1109961Y422387D02*
Y444316D01*
G01X1108901Y444756D02*
X1153172Y489027D01*
G01X1109961Y444316D02*
X1154232Y488587D01*
G01X1113661Y423137D02*
Y443403D01*
G01X1112601Y423137D02*
Y443843D01*
G01X1113661Y443403D02*
X1151950Y481692D01*
G01X1112601Y443843D02*
X1151510Y482752D01*
G01X1109961Y422387D02*
Y444316D01*
G01X1108901Y422387D02*
Y444756D01*
G01X1109961Y444316D02*
X1154232Y488587D01*
G01X1108901Y444756D02*
X1153172Y489027D01*
G01X1112601Y423137D02*
Y443843D01*
G01X1113661Y423137D02*
Y443403D01*
G01X1112601Y443843D02*
X1151510Y482752D01*
G01X1113661Y443403D02*
X1151950Y481692D01*
G01X1140815Y422445D02*
X1144170Y425800D01*
G01X1141566Y421696D02*
X1144610Y424740D01*
G01X1144170Y425800D02*
X1157830D01*
G01X1144610Y424740D02*
X1158270D01*
G01X1149787Y421345D02*
X1159542D01*
G01X1149787Y422405D02*
X1159102D01*
G01X1141566Y421696D02*
X1144610Y424740D01*
G01X1140815Y422445D02*
X1144170Y425800D01*
G01X1144610Y424740D02*
X1158270D01*
G01X1144170Y425800D02*
X1157830D01*
G01X1149787Y422405D02*
X1159102D01*
G01X1149787Y421345D02*
X1159542D01*
G01X1114137Y495165D02*
Y507005D01*
G01X1115197Y494725D02*
Y506565D01*
G01X1114137Y507005D02*
X1116361Y509229D01*
G01X1115197Y506565D02*
X1117421Y508789D01*
G01X1116361Y509229D02*
Y538696D01*
G01X1117421Y508789D02*
Y550020D01*
G01X1113085Y488656D02*
X1113792Y489363D01*
G01X1115377Y490948D02*
X1117081Y492652D01*
G01X1118141Y492212D02*
Y494639D01*
G01X1117081Y492652D02*
Y495079D01*
G01X1118141Y494639D02*
X1119019Y495517D01*
G01X1117081Y495079D02*
X1118579Y496577D01*
G01X1119019Y495517D02*
X1121088D01*
G01X1118579Y496577D02*
X1120648D01*
G01X1121088Y495517D02*
X1122580Y497009D01*
G01X1120648Y496577D02*
X1121520Y497449D01*
G01X1122580Y497009D02*
Y499585D01*
G01X1121520Y497449D02*
Y499145D01*
G01X1122580Y499585D02*
X1121088Y501077D01*
G01X1121520Y499145D02*
X1120648Y500017D01*
G01X1121088Y501077D02*
X1119297D01*
G01X1120648Y500017D02*
X1118857D01*
G01X1119297Y501077D02*
X1118534Y501840D01*
G01X1118857Y500017D02*
X1117474Y501400D01*
G01X1118534Y501840D02*
Y504342D01*
G01X1117474Y501400D02*
Y504782D01*
G01X1118534Y504342D02*
X1119362Y505170D01*
G01X1117474Y504782D02*
X1118922Y506230D01*
G01X1119362Y505170D02*
X1121300D01*
G01X1118922Y506230D02*
X1120860D01*
G01X1121300Y505170D02*
X1122721Y506591D01*
G01X1120860Y506230D02*
X1121661Y507031D01*
G01X1122721Y506591D02*
Y550034D01*
G01X1121661Y507031D02*
Y508840D01*
G01X1122721Y506591D02*
Y550034D01*
G01X1121661Y511080D02*
Y512496D01*
G01X1122721Y506591D02*
Y550034D01*
G01X1121661Y514444D02*
Y515604D01*
G01X1122721Y506591D02*
Y550034D01*
G01X1121661Y517710D02*
Y518934D01*
G01X1122721Y506591D02*
Y550034D01*
G01X1121661Y521174D02*
Y522174D01*
G01X1122721Y506591D02*
Y550034D01*
G01X1121661Y524414D02*
Y525414D01*
G01X1122721Y506591D02*
Y550034D01*
G01Y506591D02*
Y550034D01*
G01Y506591D02*
Y550034D01*
G01Y506591D02*
Y550034D01*
G01Y506591D02*
Y550034D01*
G01Y506591D02*
Y550034D01*
G01X1115197Y494725D02*
Y506565D01*
G01X1114137Y495165D02*
Y507005D01*
G01X1115197Y506565D02*
X1117421Y508789D01*
G01X1114137Y507005D02*
X1116361Y509229D01*
G01X1117421Y508789D02*
Y550020D01*
G01X1116361Y509229D02*
Y538696D01*
G01X1117421Y508789D02*
Y550020D01*
G01Y508789D02*
Y550020D01*
G01Y508789D02*
Y550020D01*
G01X1113085Y488656D02*
X1113792Y489363D01*
G01X1115377Y490948D02*
X1117081Y492652D01*
G01D02*
Y495079D01*
G01X1118141Y492212D02*
Y494639D01*
G01X1117081Y495079D02*
X1118579Y496577D01*
G01X1118141Y494639D02*
X1119019Y495517D01*
G01X1118579Y496577D02*
X1120648D01*
G01X1119019Y495517D02*
X1121088D01*
G01X1120648Y496577D02*
X1121520Y497449D01*
G01X1121088Y495517D02*
X1122580Y497009D01*
G01X1121520Y497449D02*
Y499145D01*
G01X1122580Y497009D02*
Y499585D01*
G01X1121520Y499145D02*
X1120648Y500017D01*
G01X1122580Y499585D02*
X1121088Y501077D01*
G01X1120648Y500017D02*
X1118857D01*
G01X1121088Y501077D02*
X1119297D01*
G01X1118857Y500017D02*
X1117474Y501400D01*
G01X1119297Y501077D02*
X1118534Y501840D01*
G01X1117474Y501400D02*
Y504782D01*
G01X1118534Y501840D02*
Y504342D01*
G01X1117474Y504782D02*
X1118922Y506230D01*
G01X1118534Y504342D02*
X1119362Y505170D01*
G01X1118922Y506230D02*
X1120860D01*
G01X1119362Y505170D02*
X1121300D01*
G01X1120860Y506230D02*
X1121661Y507031D01*
G01X1121300Y505170D02*
X1122721Y506591D01*
G01X1121661Y507031D02*
Y508840D01*
G01Y511080D02*
Y512496D01*
G01Y514444D02*
Y515604D01*
G01Y517710D02*
Y518934D01*
G01Y521174D02*
Y522174D01*
G01Y524414D02*
Y525414D01*
G01X1122721Y506591D02*
Y550034D01*
G01X1153172Y489027D02*
Y575949D01*
G01X1154232Y488587D02*
Y587820D01*
G01X1151950Y481692D02*
X1153531D01*
G01X1151510Y482752D02*
X1153971D01*
G01X1151950Y481692D02*
X1153531D01*
G01D02*
X1154952Y480271D01*
G01X1153971Y482752D02*
X1155392Y481331D01*
G01X1153531Y481692D02*
X1154952Y480271D01*
G01D02*
X1156883D01*
G01X1155392Y481331D02*
X1156443D01*
G01X1156883Y480271D02*
X1158763Y482151D01*
G01X1156443Y481331D02*
X1157703Y482591D01*
G01X1158763Y483736D02*
X1156602Y485897D01*
G01X1157703Y483296D02*
X1155542Y485457D01*
G01X1156602Y485897D02*
Y486802D01*
G01X1155542Y485457D02*
Y487242D01*
G01X1156602Y486802D02*
X1159332Y489532D01*
G01X1155542Y487242D02*
X1158272Y489972D01*
G01X1154232Y488587D02*
Y587820D01*
G01X1153172Y489027D02*
Y575949D01*
G01X1154232Y488587D02*
Y587820D01*
G01Y488587D02*
Y587820D01*
G01Y488587D02*
Y587820D01*
G01X1151510Y482752D02*
X1153971D01*
G01D02*
X1155392Y481331D01*
G01X1151950Y481692D02*
X1153531D01*
G01X1153971Y482752D02*
X1155392Y481331D01*
G01D02*
X1156443D01*
G01X1153531Y481692D02*
X1154952Y480271D01*
G01X1155392Y481331D02*
X1156443D01*
G01X1154952Y480271D02*
X1156883D01*
G01X1156443Y481331D02*
X1157703Y482591D01*
G01X1156883Y480271D02*
X1158763Y482151D01*
G01X1157703Y483296D02*
X1155542Y485457D01*
G01X1158763Y483736D02*
X1156602Y485897D01*
G01X1155542Y485457D02*
Y487242D01*
G01X1156602Y485897D02*
Y486802D01*
G01X1155542Y487242D02*
X1158272Y489972D01*
G01X1156602Y486802D02*
X1159332Y489532D01*
G01X1114137Y495165D02*
Y507005D01*
G01X1115197Y494725D02*
Y506565D01*
G01X1114137Y507005D02*
X1116361Y509229D01*
G01X1115197Y506565D02*
X1117421Y508789D01*
G01X1116361Y509229D02*
Y538696D01*
G01X1117421Y508789D02*
Y550020D01*
G01X1114137Y495165D02*
Y507005D01*
G01X1115197Y494725D02*
Y506565D01*
G01X1114137Y507005D02*
X1116361Y509229D01*
G01X1115197Y506565D02*
X1117421Y508789D01*
G01X1116361Y509229D02*
Y538696D01*
G01X1117421Y508789D02*
Y550020D01*
G01X1113085Y488656D02*
X1113792Y489363D01*
G01X1115377Y490948D02*
X1117081Y492652D01*
G01X1118141Y492212D02*
Y494639D01*
G01X1117081Y492652D02*
Y495079D01*
G01X1118141Y494639D02*
X1119019Y495517D01*
G01X1117081Y495079D02*
X1118579Y496577D01*
G01X1119019Y495517D02*
X1121088D01*
G01X1118579Y496577D02*
X1120648D01*
G01X1121088Y495517D02*
X1122580Y497009D01*
G01X1120648Y496577D02*
X1121520Y497449D01*
G01X1122580Y497009D02*
Y499585D01*
G01X1121520Y497449D02*
Y499145D01*
G01X1122580Y499585D02*
X1121088Y501077D01*
G01X1121520Y499145D02*
X1120648Y500017D01*
G01X1121088Y501077D02*
X1119297D01*
G01X1120648Y500017D02*
X1118857D01*
G01X1119297Y501077D02*
X1118534Y501840D01*
G01X1118857Y500017D02*
X1117474Y501400D01*
G01X1118534Y501840D02*
Y504342D01*
G01X1117474Y501400D02*
Y504782D01*
G01X1118534Y504342D02*
X1119362Y505170D01*
G01X1117474Y504782D02*
X1118922Y506230D01*
G01X1119362Y505170D02*
X1121300D01*
G01X1118922Y506230D02*
X1120860D01*
G01X1121300Y505170D02*
X1122721Y506591D01*
G01X1120860Y506230D02*
X1121661Y507031D01*
G01X1122721Y506591D02*
Y550034D01*
G01X1121661Y507031D02*
Y508840D01*
G01X1122721Y506591D02*
Y550034D01*
G01X1121661Y511080D02*
Y512496D01*
G01X1122721Y506591D02*
Y550034D01*
G01X1121661Y514444D02*
Y515604D01*
G01X1122721Y506591D02*
Y550034D01*
G01X1121661Y517710D02*
Y518934D01*
G01X1122721Y506591D02*
Y550034D01*
G01X1121661Y521174D02*
Y522174D01*
G01X1122721Y506591D02*
Y550034D01*
G01X1121661Y524414D02*
Y525414D01*
G01X1122721Y506591D02*
Y550034D01*
G01Y506591D02*
Y550034D01*
G01Y506591D02*
Y550034D01*
G01Y506591D02*
Y550034D01*
G01Y506591D02*
Y550034D01*
G01Y506591D02*
Y550034D01*
G01X1115197Y494725D02*
Y506565D01*
G01X1114137Y495165D02*
Y507005D01*
G01X1115197Y506565D02*
X1117421Y508789D01*
G01X1114137Y507005D02*
X1116361Y509229D01*
G01X1117421Y508789D02*
Y550020D01*
G01X1116361Y509229D02*
Y538696D01*
G01X1117421Y508789D02*
Y550020D01*
G01Y508789D02*
Y550020D01*
G01Y508789D02*
Y550020D01*
G01X1113085Y488656D02*
X1113792Y489363D01*
G01X1115377Y490948D02*
X1117081Y492652D01*
G01D02*
Y495079D01*
G01X1118141Y492212D02*
Y494639D01*
G01X1117081Y495079D02*
X1118579Y496577D01*
G01X1118141Y494639D02*
X1119019Y495517D01*
G01X1118579Y496577D02*
X1120648D01*
G01X1119019Y495517D02*
X1121088D01*
G01X1120648Y496577D02*
X1121520Y497449D01*
G01X1121088Y495517D02*
X1122580Y497009D01*
G01X1121520Y497449D02*
Y499145D01*
G01X1122580Y497009D02*
Y499585D01*
G01X1121520Y499145D02*
X1120648Y500017D01*
G01X1122580Y499585D02*
X1121088Y501077D01*
G01X1120648Y500017D02*
X1118857D01*
G01X1121088Y501077D02*
X1119297D01*
G01X1118857Y500017D02*
X1117474Y501400D01*
G01X1119297Y501077D02*
X1118534Y501840D01*
G01X1117474Y501400D02*
Y504782D01*
G01X1118534Y501840D02*
Y504342D01*
G01X1117474Y504782D02*
X1118922Y506230D01*
G01X1118534Y504342D02*
X1119362Y505170D01*
G01X1118922Y506230D02*
X1120860D01*
G01X1119362Y505170D02*
X1121300D01*
G01X1120860Y506230D02*
X1121661Y507031D01*
G01X1121300Y505170D02*
X1122721Y506591D01*
G01X1121661Y507031D02*
Y508840D01*
G01Y511080D02*
Y512496D01*
G01Y514444D02*
Y515604D01*
G01Y517710D02*
Y518934D01*
G01Y521174D02*
Y522174D01*
G01Y524414D02*
Y525414D01*
G01X1122721Y506591D02*
Y550034D01*
G01X1113085Y488656D02*
X1113792Y489363D01*
G01X1115377Y490948D02*
X1117081Y492652D01*
G01D02*
Y495079D01*
G01X1118141Y492212D02*
Y494639D01*
G01X1117081Y495079D02*
X1118579Y496577D01*
G01X1118141Y494639D02*
X1119019Y495517D01*
G01X1118579Y496577D02*
X1120648D01*
G01X1119019Y495517D02*
X1121088D01*
G01X1120648Y496577D02*
X1121520Y497449D01*
G01X1121088Y495517D02*
X1122580Y497009D01*
G01X1121520Y497449D02*
Y499145D01*
G01X1122580Y497009D02*
Y499585D01*
G01X1121520Y499145D02*
X1120648Y500017D01*
G01X1122580Y499585D02*
X1121088Y501077D01*
G01X1120648Y500017D02*
X1118857D01*
G01X1121088Y501077D02*
X1119297D01*
G01X1118857Y500017D02*
X1117474Y501400D01*
G01X1119297Y501077D02*
X1118534Y501840D01*
G01X1117474Y501400D02*
Y504782D01*
G01X1118534Y501840D02*
Y504342D01*
G01X1117474Y504782D02*
X1118922Y506230D01*
G01X1118534Y504342D02*
X1119362Y505170D01*
G01X1118922Y506230D02*
X1120860D01*
G01X1119362Y505170D02*
X1121300D01*
G01X1120860Y506230D02*
X1121661Y507031D01*
G01X1121300Y505170D02*
X1122721Y506591D01*
G01X1121661Y507031D02*
Y508840D01*
G01Y511080D02*
Y512496D01*
G01Y514444D02*
Y515604D01*
G01Y517710D02*
Y518934D01*
G01Y521174D02*
Y522174D01*
G01Y524414D02*
Y525414D01*
G01X1122721Y506591D02*
Y550034D01*
G01X1112353Y552200D02*
Y570212D01*
G01X1113413Y564560D02*
Y563140D01*
G01X1112353Y552200D02*
Y570212D01*
G01X1113413Y559460D02*
Y558090D01*
G01X1116361Y540626D02*
Y541626D01*
G01Y543556D02*
Y544556D01*
G01Y546486D02*
Y549580D01*
G01D02*
X1115441Y550500D01*
G01X1117421Y550020D02*
X1114341Y553100D01*
G01X1117966Y558371D02*
X1118637Y557700D01*
G01X1117735Y557101D02*
X1116906Y557930D01*
G01X1117966Y564029D02*
Y563138D01*
G01Y559648D02*
Y558371D01*
G01X1116906Y557930D02*
Y564470D01*
G01X1118737Y564800D02*
X1117966Y564029D01*
G01X1116906Y564470D02*
X1117735Y565299D01*
G01X1121661Y527654D02*
Y529233D01*
G01Y531473D02*
Y534152D01*
G01Y536392D02*
Y537947D01*
G01Y540187D02*
Y541187D01*
G01Y543427D02*
Y544427D01*
G01Y546667D02*
Y549594D01*
G01X1122721Y550034D02*
X1119441Y553314D01*
G01X1121661Y549594D02*
X1120541Y550714D01*
G01X1113413Y564560D02*
Y563140D01*
G01Y559460D02*
Y558090D01*
G01X1112353Y552200D02*
Y570212D01*
G01X1116361Y540626D02*
Y541626D01*
G01Y543556D02*
Y544556D01*
G01Y546486D02*
Y549580D01*
G01X1117421Y550020D02*
X1114341Y553100D01*
G01X1116361Y549580D02*
X1115441Y550500D01*
G01X1116906Y564470D02*
X1117735Y565299D01*
G01X1118737Y564800D02*
X1117966Y564029D01*
G01X1116906Y557930D02*
Y564470D01*
G01X1117966Y564029D02*
Y563138D01*
G01X1116906Y557930D02*
Y564470D01*
G01X1117966Y559648D02*
Y558371D01*
G01X1117735Y557101D02*
X1116906Y557930D01*
G01X1117966Y558371D02*
X1118637Y557700D01*
G01X1121661Y527654D02*
Y529233D01*
G01Y531473D02*
Y534152D01*
G01Y536392D02*
Y537947D01*
G01Y540187D02*
Y541187D01*
G01Y543427D02*
Y544427D01*
G01Y546667D02*
Y549594D01*
G01D02*
X1120541Y550714D01*
G01X1122721Y550034D02*
X1119441Y553314D01*
G01X1153172Y577659D02*
Y579070D01*
G01Y580964D02*
Y582137D01*
G01Y584377D02*
Y587380D01*
G01D02*
X1152252Y588300D01*
G01X1154232Y587820D02*
X1151152Y590900D01*
G01X1153172Y577659D02*
Y579070D01*
G01Y580964D02*
Y582137D01*
G01Y584377D02*
Y587380D01*
G01X1154232Y587820D02*
X1151152Y590900D01*
G01X1153172Y587380D02*
X1152252Y588300D01*
G01X1112353Y552200D02*
Y570212D01*
G01X1113413Y564560D02*
Y563140D01*
G01X1112353Y552200D02*
Y570212D01*
G01X1113413Y559460D02*
Y558090D01*
G01X1116361Y540626D02*
Y541626D01*
G01Y543556D02*
Y544556D01*
G01Y546486D02*
Y549580D01*
G01D02*
X1115441Y550500D01*
G01X1117421Y550020D02*
X1114341Y553100D01*
G01X1112353Y552200D02*
Y570212D01*
G01X1113413Y564560D02*
Y563140D01*
G01X1112353Y552200D02*
Y570212D01*
G01X1113413Y559460D02*
Y558090D01*
G01X1116361Y540626D02*
Y541626D01*
G01Y543556D02*
Y544556D01*
G01Y546486D02*
Y549580D01*
G01D02*
X1115441Y550500D01*
G01X1117421Y550020D02*
X1114341Y553100D01*
G01X1117966Y558371D02*
X1118637Y557700D01*
G01X1117735Y557101D02*
X1116906Y557930D01*
G01X1117966Y564029D02*
Y563138D01*
G01Y559648D02*
Y558371D01*
G01X1116906Y557930D02*
Y564470D01*
G01X1118737Y564800D02*
X1117966Y564029D01*
G01X1116906Y564470D02*
X1117735Y565299D01*
G01X1121661Y527654D02*
Y529233D01*
G01Y531473D02*
Y534152D01*
G01Y536392D02*
Y537947D01*
G01Y540187D02*
Y541187D01*
G01Y543427D02*
Y544427D01*
G01Y546667D02*
Y549594D01*
G01X1122721Y550034D02*
X1119441Y553314D01*
G01X1121661Y549594D02*
X1120541Y550714D01*
G01X1113413Y564560D02*
Y563140D01*
G01Y559460D02*
Y558090D01*
G01X1112353Y552200D02*
Y570212D01*
G01X1116361Y540626D02*
Y541626D01*
G01Y543556D02*
Y544556D01*
G01Y546486D02*
Y549580D01*
G01X1117421Y550020D02*
X1114341Y553100D01*
G01X1116361Y549580D02*
X1115441Y550500D01*
G01X1116906Y564470D02*
X1117735Y565299D01*
G01X1118737Y564800D02*
X1117966Y564029D01*
G01X1116906Y557930D02*
Y564470D01*
G01X1117966Y564029D02*
Y563138D01*
G01X1116906Y557930D02*
Y564470D01*
G01X1117966Y559648D02*
Y558371D01*
G01X1117735Y557101D02*
X1116906Y557930D01*
G01X1117966Y558371D02*
X1118637Y557700D01*
G01X1121661Y527654D02*
Y529233D01*
G01Y531473D02*
Y534152D01*
G01Y536392D02*
Y537947D01*
G01Y540187D02*
Y541187D01*
G01Y543427D02*
Y544427D01*
G01Y546667D02*
Y549594D01*
G01D02*
X1120541Y550714D01*
G01X1122721Y550034D02*
X1119441Y553314D01*
G01X1116906Y564470D02*
X1117735Y565299D01*
G01X1118737Y564800D02*
X1117966Y564029D01*
G01X1116906Y557930D02*
Y564470D01*
G01X1117966Y564029D02*
Y563138D01*
G01X1116906Y557930D02*
Y564470D01*
G01X1117966Y559648D02*
Y558371D01*
G01X1117735Y557101D02*
X1116906Y557930D01*
G01X1117966Y558371D02*
X1118637Y557700D01*
G01X1121661Y527654D02*
Y529233D01*
G01Y531473D02*
Y534152D01*
G01Y536392D02*
Y537947D01*
G01Y540187D02*
Y541187D01*
G01Y543427D02*
Y544427D01*
G01Y546667D02*
Y549594D01*
G01D02*
X1120541Y550714D01*
G01X1122721Y550034D02*
X1119441Y553314D01*
G01X1159332Y588034D02*
X1156252Y591114D01*
G01X1159332Y588034D02*
X1156252Y591114D01*
G01X1157032Y21762D02*
X1157908D01*
G01X1158616Y23346D02*
X1159497Y24227D01*
G01X1158437Y24670D02*
Y113491D01*
G01X1159497Y24227D02*
Y37080D01*
G01X1158437Y24670D02*
Y113491D01*
G01X1157032Y21762D02*
X1157908D01*
G01X1158616Y23346D02*
X1159497Y24227D01*
G01D02*
Y37080D01*
G01X1158437Y24670D02*
Y113491D01*
G01X1188782Y32580D02*
X1189298D01*
G01D02*
X1190009Y33291D01*
G01X1191069Y32851D02*
X1189738Y31520D01*
G01X1188782Y32580D02*
X1189298D01*
G01X1189738Y31520D02*
X1188759D01*
G01X1191069Y32851D02*
X1189738Y31520D01*
G01D02*
X1188759D01*
G01X1188782Y32580D02*
X1189298D01*
G01X1191069Y32851D02*
X1189738Y31520D01*
G01X1189298Y32580D02*
X1190009Y33291D01*
G01X1193063Y30540D02*
X1196255Y33732D01*
G01X1188782Y32580D02*
X1189298D01*
G01D02*
X1190009Y33291D01*
G01X1191069Y32851D02*
X1189738Y31520D01*
G01X1188782Y32580D02*
X1189298D01*
G01X1189738Y31520D02*
X1188759D01*
G01X1193063Y30540D02*
X1196255Y33732D01*
G01X1193063Y30540D02*
X1196255Y33732D01*
G01X1193063Y30540D02*
X1196255Y33732D01*
G01X1193063Y30540D02*
X1196255Y33732D01*
G01X1191069Y32851D02*
X1189738Y31520D01*
G01D02*
X1188759D01*
G01X1188782Y32580D02*
X1189298D01*
G01X1191069Y32851D02*
X1189738Y31520D01*
G01X1189298Y32580D02*
X1190009Y33291D01*
G01X1193063Y30540D02*
X1196255Y33732D01*
G01X1159497Y39320D02*
Y113934D01*
G01Y39320D02*
Y113934D01*
G01X1189920Y62190D02*
Y105934D01*
G01X1190980Y107497D02*
Y61747D01*
G01X1187920Y60190D02*
X1189920Y62190D01*
G01X1190980Y61747D02*
X1188980Y59747D01*
G01X1187920Y57320D02*
Y60190D01*
G01X1188980Y59747D02*
Y56781D01*
G01X1190009Y48553D02*
X1189062Y49500D01*
G01D02*
X1187963D01*
G01Y52100D02*
X1191069Y48994D01*
G01X1190009Y33291D02*
Y36580D01*
G01Y40920D02*
Y41880D01*
G01Y46020D02*
Y48553D01*
G01X1191069Y48994D02*
Y32851D01*
G01X1188980Y59747D02*
Y56781D01*
G01X1187920Y57320D02*
Y60190D01*
G01X1190980Y61747D02*
X1188980Y59747D01*
G01X1187920Y60190D02*
X1189920Y62190D01*
G01X1190980Y107497D02*
Y61747D01*
G01X1189920Y62190D02*
Y105934D01*
G01X1191069Y48994D02*
Y32851D01*
G01X1190009Y33291D02*
Y36580D01*
G01X1191069Y48994D02*
Y32851D01*
G01X1190009Y40920D02*
Y41880D01*
G01X1191069Y48994D02*
Y32851D01*
G01X1190009Y46020D02*
Y48553D01*
G01X1187963Y52100D02*
X1191069Y48994D01*
G01X1190009Y48553D02*
X1189062Y49500D01*
G01X1187963Y52100D02*
X1191069Y48994D01*
G01X1189062Y49500D02*
X1187963D01*
G01X1193120Y57520D02*
Y58192D01*
G01X1194180Y56620D02*
Y57749D01*
G01X1193120Y58192D02*
X1195020Y60092D01*
G01X1194180Y57749D02*
X1196080Y59649D01*
G01X1195020Y60092D02*
Y105698D01*
G01X1196080Y59649D02*
Y107247D01*
G01X1193063Y33149D02*
X1194172D01*
G01D02*
X1195195Y34172D01*
G01D02*
Y36793D01*
G01Y40707D02*
Y42080D01*
G01Y45906D02*
Y48681D01*
G01X1196255Y33732D02*
Y49122D01*
G01X1195195Y48681D02*
X1194161Y49715D01*
G01D02*
X1193063D01*
G01X1196255Y49122D02*
X1193063Y52314D01*
G01X1189920Y62190D02*
Y105934D01*
G01X1190980Y107497D02*
Y61747D01*
G01X1187920Y60190D02*
X1189920Y62190D01*
G01X1190980Y61747D02*
X1188980Y59747D01*
G01X1187920Y57320D02*
Y60190D01*
G01X1188980Y59747D02*
Y56781D01*
G01X1190009Y48553D02*
X1189062Y49500D01*
G01D02*
X1187963D01*
G01Y52100D02*
X1191069Y48994D01*
G01X1190009Y33291D02*
Y36580D01*
G01Y40920D02*
Y41880D01*
G01Y46020D02*
Y48553D01*
G01X1191069Y48994D02*
Y32851D01*
G01X1194180Y56620D02*
Y57749D01*
G01X1193120Y57520D02*
Y58192D01*
G01X1194180Y57749D02*
X1196080Y59649D01*
G01X1193120Y58192D02*
X1195020Y60092D01*
G01X1196080Y59649D02*
Y107247D01*
G01X1195020Y60092D02*
Y105698D01*
G01X1193063Y33149D02*
X1194172D01*
G01D02*
X1195195Y34172D01*
G01X1196255Y33732D02*
Y49122D01*
G01X1195195Y34172D02*
Y36793D01*
G01X1196255Y33732D02*
Y49122D01*
G01X1195195Y40707D02*
Y42080D01*
G01X1196255Y33732D02*
Y49122D01*
G01X1195195Y45906D02*
Y48681D01*
G01X1196255Y49122D02*
X1193063Y52314D01*
G01X1195195Y48681D02*
X1194161Y49715D01*
G01X1196255Y49122D02*
X1193063Y52314D01*
G01X1194161Y49715D02*
X1193063D01*
G01X1194180Y56620D02*
Y57749D01*
G01X1193120Y57520D02*
Y58192D01*
G01X1194180Y57749D02*
X1196080Y59649D01*
G01X1193120Y58192D02*
X1195020Y60092D01*
G01X1196080Y59649D02*
Y107247D01*
G01X1195020Y60092D02*
Y105698D01*
G01X1193063Y33149D02*
X1194172D01*
G01D02*
X1195195Y34172D01*
G01X1196255Y33732D02*
Y49122D01*
G01X1195195Y34172D02*
Y36793D01*
G01X1196255Y33732D02*
Y49122D01*
G01X1195195Y40707D02*
Y42080D01*
G01X1196255Y33732D02*
Y49122D01*
G01X1195195Y45906D02*
Y48681D01*
G01X1196255Y49122D02*
X1193063Y52314D01*
G01X1195195Y48681D02*
X1194161Y49715D01*
G01X1196255Y49122D02*
X1193063Y52314D01*
G01X1194161Y49715D02*
X1193063D01*
G01X1188980Y59747D02*
Y56781D01*
G01X1187920Y57320D02*
Y60190D01*
G01X1190980Y61747D02*
X1188980Y59747D01*
G01X1187920Y60190D02*
X1189920Y62190D01*
G01X1190980Y107497D02*
Y61747D01*
G01X1189920Y62190D02*
Y105934D01*
G01X1191069Y48994D02*
Y32851D01*
G01X1190009Y33291D02*
Y36580D01*
G01X1191069Y48994D02*
Y32851D01*
G01X1190009Y40920D02*
Y41880D01*
G01X1191069Y48994D02*
Y32851D01*
G01X1190009Y46020D02*
Y48553D01*
G01X1187963Y52100D02*
X1191069Y48994D01*
G01X1190009Y48553D02*
X1189062Y49500D01*
G01X1187963Y52100D02*
X1191069Y48994D01*
G01X1189062Y49500D02*
X1187963D01*
G01X1193120Y57520D02*
Y58192D01*
G01X1194180Y56620D02*
Y57749D01*
G01X1193120Y58192D02*
X1195020Y60092D01*
G01X1194180Y57749D02*
X1196080Y59649D01*
G01X1195020Y60092D02*
Y105698D01*
G01X1196080Y59649D02*
Y107247D01*
G01X1193063Y33149D02*
X1194172D01*
G01D02*
X1195195Y34172D01*
G01D02*
Y36793D01*
G01Y40707D02*
Y42080D01*
G01Y45906D02*
Y48681D01*
G01X1196255Y33732D02*
Y49122D01*
G01X1195195Y48681D02*
X1194161Y49715D01*
G01D02*
X1193063D01*
G01X1196255Y49122D02*
X1193063Y52314D01*
G01X1158437Y113491D02*
X1157620Y114308D01*
G01X1159497Y113934D02*
X1158680Y114751D01*
G01X1157620Y114308D02*
Y122909D01*
G01X1158680Y114751D02*
Y123352D01*
G01X1159497Y113934D02*
X1158680Y114751D01*
G01X1158437Y113491D02*
X1157620Y114308D01*
G01X1158680Y114751D02*
Y123352D01*
G01X1157620Y114308D02*
Y122909D01*
G01X1162017Y181800D02*
X1207352Y136465D01*
G01X1162457Y182860D02*
X1208412Y136905D01*
G01X1207352Y136465D02*
Y135234D01*
G01X1208412Y136905D02*
Y134794D01*
G01X1207352Y135234D02*
X1204941Y132823D01*
G01X1208412Y134794D02*
X1206001Y132383D01*
G01X1204941Y132823D02*
Y130816D01*
G01X1206001Y132383D02*
Y131256D01*
G01X1204941Y130816D02*
X1207344Y128413D01*
G01X1206001Y131256D02*
X1207784Y129473D01*
G01X1204941Y130816D02*
X1207344Y128413D01*
G01D02*
X1209534D01*
G01X1207784Y129473D02*
X1209094D01*
G01X1209534Y128413D02*
X1211580Y130459D01*
G01X1209094Y129473D02*
X1211140Y131519D01*
G01X1211580Y130459D02*
X1212809D01*
G01X1211140Y131519D02*
X1213249D01*
G01X1211580Y130459D02*
X1212809D01*
G01D02*
X1214577Y128691D01*
G01X1213249Y131519D02*
X1215637Y129131D01*
G01X1214577Y128691D02*
Y127462D01*
G01X1215637Y129131D02*
Y127019D01*
G01X1214577Y127462D02*
X1212697Y125582D01*
G01X1215637Y127019D02*
X1213757Y125139D01*
G01X1212697Y125582D02*
Y123470D01*
G01X1213757Y125139D02*
Y123913D01*
G01X1212697Y123470D02*
X1226794Y109373D01*
G01X1213757Y123913D02*
X1227854Y109816D01*
G01X1164472Y184745D02*
X1218720Y130497D01*
G01X1164912Y185805D02*
X1219780Y130937D01*
G01X1162457Y182860D02*
X1208412Y136905D01*
G01X1162017Y181800D02*
X1207352Y136465D01*
G01X1208412Y136905D02*
Y134794D01*
G01X1207352Y136465D02*
Y135234D01*
G01X1208412Y134794D02*
X1206001Y132383D01*
G01X1207352Y135234D02*
X1204941Y132823D01*
G01X1206001Y132383D02*
Y131256D01*
G01X1204941Y132823D02*
Y130816D01*
G01X1206001Y131256D02*
X1207784Y129473D01*
G01D02*
X1209094D01*
G01X1204941Y130816D02*
X1207344Y128413D01*
G01X1207784Y129473D02*
X1209094D01*
G01X1207344Y128413D02*
X1209534D01*
G01X1209094Y129473D02*
X1211140Y131519D01*
G01X1209534Y128413D02*
X1211580Y130459D01*
G01X1211140Y131519D02*
X1213249D01*
G01D02*
X1215637Y129131D01*
G01X1211580Y130459D02*
X1212809D01*
G01X1213249Y131519D02*
X1215637Y129131D01*
G01X1212809Y130459D02*
X1214577Y128691D01*
G01X1215637Y129131D02*
Y127019D01*
G01X1214577Y128691D02*
Y127462D01*
G01X1215637Y127019D02*
X1213757Y125139D01*
G01X1214577Y127462D02*
X1212697Y125582D01*
G01X1213757Y125139D02*
Y123913D01*
G01X1212697Y125582D02*
Y123470D01*
G01X1213757Y123913D02*
X1227854Y109816D01*
G01X1212697Y123470D02*
X1226794Y109373D01*
G01X1164912Y185805D02*
X1219780Y130937D01*
G01X1164472Y184745D02*
X1218720Y130497D01*
G01X1162017Y181800D02*
X1207352Y136465D01*
G01X1162457Y182860D02*
X1208412Y136905D01*
G01X1207352Y136465D02*
Y135234D01*
G01X1208412Y136905D02*
Y134794D01*
G01X1207352Y135234D02*
X1204941Y132823D01*
G01X1208412Y134794D02*
X1206001Y132383D01*
G01X1204941Y132823D02*
Y130816D01*
G01X1206001Y132383D02*
Y131256D01*
G01X1204941Y130816D02*
X1207344Y128413D01*
G01X1206001Y131256D02*
X1207784Y129473D01*
G01X1204941Y130816D02*
X1207344Y128413D01*
G01D02*
X1209534D01*
G01X1207784Y129473D02*
X1209094D01*
G01X1209534Y128413D02*
X1211580Y130459D01*
G01X1209094Y129473D02*
X1211140Y131519D01*
G01X1211580Y130459D02*
X1212809D01*
G01X1211140Y131519D02*
X1213249D01*
G01X1211580Y130459D02*
X1212809D01*
G01D02*
X1214577Y128691D01*
G01X1213249Y131519D02*
X1215637Y129131D01*
G01X1214577Y128691D02*
Y127462D01*
G01X1215637Y129131D02*
Y127019D01*
G01X1214577Y127462D02*
X1212697Y125582D01*
G01X1215637Y127019D02*
X1213757Y125139D01*
G01X1212697Y125582D02*
Y123470D01*
G01X1213757Y125139D02*
Y123913D01*
G01X1212697Y123470D02*
X1226794Y109373D01*
G01X1213757Y123913D02*
X1227854Y109816D01*
G01X1164472Y184745D02*
X1218720Y130497D01*
G01X1164912Y185805D02*
X1219780Y130937D01*
G01X1162457Y182860D02*
X1208412Y136905D01*
G01X1162017Y181800D02*
X1207352Y136465D01*
G01X1208412Y136905D02*
Y134794D01*
G01X1207352Y136465D02*
Y135234D01*
G01X1208412Y134794D02*
X1206001Y132383D01*
G01X1207352Y135234D02*
X1204941Y132823D01*
G01X1206001Y132383D02*
Y131256D01*
G01X1204941Y132823D02*
Y130816D01*
G01X1206001Y131256D02*
X1207784Y129473D01*
G01D02*
X1209094D01*
G01X1204941Y130816D02*
X1207344Y128413D01*
G01X1207784Y129473D02*
X1209094D01*
G01X1207344Y128413D02*
X1209534D01*
G01X1209094Y129473D02*
X1211140Y131519D01*
G01X1209534Y128413D02*
X1211580Y130459D01*
G01X1211140Y131519D02*
X1213249D01*
G01D02*
X1215637Y129131D01*
G01X1211580Y130459D02*
X1212809D01*
G01X1213249Y131519D02*
X1215637Y129131D01*
G01X1212809Y130459D02*
X1214577Y128691D01*
G01X1215637Y129131D02*
Y127019D01*
G01X1214577Y128691D02*
Y127462D01*
G01X1215637Y127019D02*
X1213757Y125139D01*
G01X1214577Y127462D02*
X1212697Y125582D01*
G01X1213757Y125139D02*
Y123913D01*
G01X1212697Y125582D02*
Y123470D01*
G01X1213757Y123913D02*
X1227854Y109816D01*
G01X1212697Y123470D02*
X1226794Y109373D01*
G01X1164912Y185805D02*
X1219780Y130937D01*
G01X1164472Y184745D02*
X1218720Y130497D01*
G01X1157295Y185805D02*
X1164912D01*
G01X1157295D02*
X1164912D01*
G01X1157295D02*
X1164912D01*
G01X1157295D02*
X1164912D01*
G01X1157830Y425800D02*
X1226794Y494764D01*
G01X1158270Y424740D02*
X1227854Y494324D01*
G01X1159542Y421345D02*
X1211775Y473578D01*
G01X1159102Y422405D02*
X1211335Y474638D01*
G01X1158270Y424740D02*
X1227854Y494324D01*
G01X1157830Y425800D02*
X1226794Y494764D01*
G01X1159102Y422405D02*
X1211335Y474638D01*
G01X1159542Y421345D02*
X1211775Y473578D01*
G01X1157830Y425800D02*
X1226794Y494764D01*
G01X1158270Y424740D02*
X1227854Y494324D01*
G01X1159542Y421345D02*
X1211775Y473578D01*
G01X1159102Y422405D02*
X1211335Y474638D01*
G01X1158270Y424740D02*
X1227854Y494324D01*
G01X1157830Y425800D02*
X1226794Y494764D01*
G01X1159102Y422405D02*
X1211335Y474638D01*
G01X1159542Y421345D02*
X1211775Y473578D01*
G01D02*
X1216706D01*
G01X1211335Y474638D02*
X1216266D01*
G01X1216706Y473578D02*
X1221348Y478220D01*
G01X1216266Y474638D02*
X1220288Y478660D01*
G01X1211335Y474638D02*
X1216266D01*
G01X1211775Y473578D02*
X1216706D01*
G01X1216266Y474638D02*
X1220288Y478660D01*
G01X1216706Y473578D02*
X1221348Y478220D01*
G01X1158763Y482151D02*
Y483736D01*
G01X1157703Y482591D02*
Y483296D01*
G01X1159332Y489532D02*
Y588034D01*
G01X1158272Y489972D02*
Y518908D01*
G01X1159332Y489532D02*
Y588034D01*
G01X1158272Y521148D02*
Y522148D01*
G01X1159332Y489532D02*
Y588034D01*
G01X1158272Y524388D02*
Y525388D01*
G01X1159332Y489532D02*
Y588034D01*
G01Y489532D02*
Y588034D01*
G01Y489532D02*
Y588034D01*
G01Y489532D02*
Y588034D01*
G01Y489532D02*
Y588034D01*
G01Y489532D02*
Y588034D01*
G01Y489532D02*
Y588034D01*
G01Y489532D02*
Y588034D01*
G01Y489532D02*
Y588034D01*
G01Y489532D02*
Y588034D01*
G01Y489532D02*
Y588034D01*
G01X1157703Y482591D02*
Y483296D01*
G01X1158763Y482151D02*
Y483736D01*
G01X1158272Y489972D02*
Y518908D01*
G01Y521148D02*
Y522148D01*
G01Y524388D02*
Y525388D01*
G01X1159332Y489532D02*
Y588034D01*
G01X1189983Y548674D02*
Y506529D01*
G01X1191043Y549532D02*
Y506089D01*
G01X1189983Y506529D02*
X1187740Y504286D01*
G01X1191043Y506089D02*
X1188800Y503846D01*
G01X1187740Y504286D02*
Y501040D01*
G01X1188800Y503846D02*
Y500600D01*
G01X1196143Y539230D02*
Y525985D01*
G01X1195083Y538790D02*
Y526425D01*
G01X1196143Y525985D02*
X1194779Y524621D01*
G01X1195083Y526425D02*
X1193719Y525061D01*
G01X1194779Y524621D02*
Y521289D01*
G01X1193719Y525061D02*
Y520849D01*
G01X1194779Y521289D02*
X1196143Y519925D01*
G01X1193719Y520849D02*
X1195083Y519485D01*
G01X1196143Y519925D02*
Y502943D01*
G01X1195083Y519485D02*
Y503383D01*
G01X1196143Y502943D02*
X1194800Y501600D01*
G01X1195083Y503383D02*
X1191300Y499600D01*
G01X1191043Y549532D02*
Y506089D01*
G01X1189983Y548674D02*
Y506529D01*
G01X1191043Y506089D02*
X1188800Y503846D01*
G01X1189983Y506529D02*
X1187740Y504286D01*
G01X1188800Y503846D02*
Y500600D01*
G01X1187740Y504286D02*
Y501040D01*
G01X1195083Y538790D02*
Y526425D01*
G01X1196143Y539230D02*
Y525985D01*
G01X1195083Y526425D02*
X1193719Y525061D01*
G01X1196143Y525985D02*
X1194779Y524621D01*
G01X1193719Y525061D02*
Y520849D01*
G01X1194779Y524621D02*
Y521289D01*
G01X1193719Y520849D02*
X1195083Y519485D01*
G01X1194779Y521289D02*
X1196143Y519925D01*
G01X1195083Y519485D02*
Y503383D01*
G01X1196143Y519925D02*
Y502943D01*
G01X1195083Y503383D02*
X1191300Y499600D01*
G01X1196143Y502943D02*
X1194800Y501600D01*
G01X1211775Y473578D02*
X1216706D01*
G01X1211335Y474638D02*
X1216266D01*
G01X1216706Y473578D02*
X1221348Y478220D01*
G01X1216266Y474638D02*
X1220288Y478660D01*
G01X1211335Y474638D02*
X1216266D01*
G01X1211775Y473578D02*
X1216706D01*
G01X1216266Y474638D02*
X1220288Y478660D01*
G01X1216706Y473578D02*
X1221348Y478220D01*
G01X1158272Y527628D02*
Y537842D01*
G01Y540082D02*
Y541082D01*
G01Y543322D02*
Y544322D01*
G01Y546562D02*
Y551124D01*
G01Y552860D02*
Y556881D01*
G01Y559121D02*
Y560121D01*
G01Y562361D02*
Y563361D01*
G01Y565601D02*
Y575921D01*
G01Y578161D02*
Y579161D01*
G01Y581401D02*
Y582401D01*
G01Y584641D02*
Y587594D01*
G01D02*
X1157352Y588514D01*
G01X1158272Y527628D02*
Y537842D01*
G01Y540082D02*
Y541082D01*
G01Y543322D02*
Y544322D01*
G01Y546562D02*
Y551124D01*
G01Y552860D02*
Y556881D01*
G01Y559121D02*
Y560121D01*
G01Y562361D02*
Y563361D01*
G01Y565601D02*
Y575921D01*
G01Y578161D02*
Y579161D01*
G01Y581401D02*
Y582401D01*
G01Y584641D02*
Y587594D01*
G01D02*
X1157352Y588514D01*
G01X1196143Y550234D02*
Y544967D01*
G01X1195083Y548694D02*
Y545407D01*
G01X1196143Y544967D02*
X1194576Y543400D01*
G01X1195083Y545407D02*
X1193516Y543840D01*
G01X1194576Y543400D02*
Y540797D01*
G01X1193516Y543840D02*
Y540357D01*
G01X1194576Y540797D02*
X1196143Y539230D01*
G01X1193516Y540357D02*
X1195083Y538790D01*
G01Y548694D02*
Y545407D01*
G01X1196143Y550234D02*
Y544967D01*
G01X1195083Y545407D02*
X1193516Y543840D01*
G01X1196143Y544967D02*
X1194576Y543400D01*
G01X1193516Y543840D02*
Y540357D01*
G01X1194576Y543400D02*
Y540797D01*
G01X1193516Y540357D02*
X1195083Y538790D01*
G01X1194576Y540797D02*
X1196143Y539230D01*
G01X1226820Y33291D02*
X1226109Y32580D01*
G01X1227880Y32848D02*
X1226552Y31520D01*
G01X1226109Y32580D02*
X1225593D01*
G01X1226552Y31520D02*
X1225570D01*
G01X1233066Y33732D02*
X1229874Y30540D01*
G01X1227880Y32848D02*
X1226552Y31520D01*
G01X1226820Y33291D02*
X1226109Y32580D01*
G01X1226552Y31520D02*
X1225570D01*
G01X1226109Y32580D02*
X1225593D01*
G01X1233066Y33732D02*
X1229874Y30540D01*
G01X1233066Y33732D02*
X1229874Y30540D01*
G01X1226820Y33291D02*
X1226109Y32580D01*
G01X1227880Y32848D02*
X1226552Y31520D01*
G01X1226109Y32580D02*
X1225593D01*
G01X1226552Y31520D02*
X1225570D01*
G01X1233066Y33732D02*
X1229874Y30540D01*
G01X1227880Y32848D02*
X1226552Y31520D01*
G01X1226820Y33291D02*
X1226109Y32580D01*
G01X1226552Y31520D02*
X1225570D01*
G01X1226109Y32580D02*
X1225593D01*
G01X1233066Y33732D02*
X1229874Y30540D01*
G01X1233066Y33732D02*
X1229874Y30540D01*
G01X1225873Y49500D02*
X1226820Y48553D01*
G01X1224774Y52100D02*
X1227880Y48994D01*
G01X1226820Y48553D02*
Y46020D01*
G01Y41880D02*
Y40920D01*
G01Y36580D02*
Y33291D01*
G01X1227880Y48994D02*
Y32848D01*
G01X1226794Y109373D02*
Y63565D01*
G01Y109373D02*
Y63565D01*
G01X1227854Y93780D02*
Y83320D01*
G01X1226794Y109373D02*
Y63565D01*
G01X1227854Y81080D02*
Y80320D01*
G01X1226794Y109373D02*
Y63565D01*
G01X1227854Y78080D02*
Y77320D01*
G01X1226794Y109373D02*
Y63565D01*
G01X1227854Y75080D02*
Y63122D01*
G01X1226794Y63565D02*
X1222920Y59691D01*
G01X1227854Y63122D02*
X1223980Y59248D01*
G01X1222920Y59691D02*
Y51354D01*
G01X1223980Y59248D02*
Y57420D01*
G01X1229874Y49715D02*
X1230972D01*
G01D02*
X1232006Y48681D01*
G01X1229874Y52314D02*
X1233066Y49122D01*
G01X1232006Y48681D02*
Y45906D01*
G01Y42080D02*
Y40707D01*
G01Y36793D02*
Y34172D01*
G01X1233066Y49122D02*
Y33732D01*
G01X1232006Y34172D02*
X1230983Y33149D01*
G01D02*
X1229874D01*
G01X1231894Y109676D02*
Y62825D01*
G01X1232954Y110117D02*
Y71620D01*
G01X1231894Y109676D02*
Y62825D01*
G01X1232954Y69380D02*
Y68620D01*
G01X1231894Y109676D02*
Y62825D01*
G01X1232954Y66380D02*
Y62382D01*
G01X1231894Y62825D02*
X1228120Y59051D01*
G01X1232954Y62382D02*
X1229180Y58608D01*
G01X1228120Y59051D02*
Y51468D01*
G01X1229180Y58608D02*
Y57620D01*
G01X1224774Y52100D02*
X1227880Y48994D01*
G01X1225873Y49500D02*
X1226820Y48553D01*
G01X1227880Y48994D02*
Y32848D01*
G01X1226820Y48553D02*
Y46020D01*
G01X1227880Y48994D02*
Y32848D01*
G01X1226820Y41880D02*
Y40920D01*
G01X1227880Y48994D02*
Y32848D01*
G01X1226820Y36580D02*
Y33291D01*
G01X1227854Y93780D02*
Y83320D01*
G01Y81080D02*
Y80320D01*
G01Y78080D02*
Y77320D01*
G01Y75080D02*
Y63122D01*
G01X1226794Y109373D02*
Y63565D01*
G01X1227854Y63122D02*
X1223980Y59248D01*
G01X1226794Y63565D02*
X1222920Y59691D01*
G01X1223980Y59248D02*
Y57420D01*
G01X1222920Y59691D02*
Y51354D01*
G01X1229874Y52314D02*
X1233066Y49122D01*
G01X1229874Y49715D02*
X1230972D01*
G01X1229874Y52314D02*
X1233066Y49122D01*
G01X1230972Y49715D02*
X1232006Y48681D01*
G01X1233066Y49122D02*
Y33732D01*
G01X1232006Y48681D02*
Y45906D01*
G01X1233066Y49122D02*
Y33732D01*
G01X1232006Y42080D02*
Y40707D01*
G01X1233066Y49122D02*
Y33732D01*
G01X1232006Y36793D02*
Y34172D01*
G01D02*
X1230983Y33149D01*
G01D02*
X1229874D01*
G01X1232954Y110117D02*
Y71620D01*
G01Y69380D02*
Y68620D01*
G01Y66380D02*
Y62382D01*
G01X1231894Y109676D02*
Y62825D01*
G01X1232954Y62382D02*
X1229180Y58608D01*
G01X1231894Y62825D02*
X1228120Y59051D01*
G01X1229180Y58608D02*
Y57620D01*
G01X1228120Y59051D02*
Y51468D01*
G01X1225873Y49500D02*
X1226820Y48553D01*
G01X1224774Y52100D02*
X1227880Y48994D01*
G01X1226820Y48553D02*
Y46020D01*
G01Y41880D02*
Y40920D01*
G01Y36580D02*
Y33291D01*
G01X1227880Y48994D02*
Y32848D01*
G01X1226794Y109373D02*
Y63565D01*
G01Y109373D02*
Y63565D01*
G01X1227854Y93780D02*
Y83320D01*
G01X1226794Y109373D02*
Y63565D01*
G01X1227854Y81080D02*
Y80320D01*
G01X1226794Y109373D02*
Y63565D01*
G01X1227854Y78080D02*
Y77320D01*
G01X1226794Y109373D02*
Y63565D01*
G01X1227854Y75080D02*
Y63122D01*
G01X1226794Y63565D02*
X1222920Y59691D01*
G01X1227854Y63122D02*
X1223980Y59248D01*
G01X1222920Y59691D02*
Y51354D01*
G01X1223980Y59248D02*
Y57420D01*
G01X1229874Y49715D02*
X1230972D01*
G01D02*
X1232006Y48681D01*
G01X1229874Y52314D02*
X1233066Y49122D01*
G01X1232006Y48681D02*
Y45906D01*
G01Y42080D02*
Y40707D01*
G01Y36793D02*
Y34172D01*
G01X1233066Y49122D02*
Y33732D01*
G01X1232006Y34172D02*
X1230983Y33149D01*
G01D02*
X1229874D01*
G01X1231894Y109676D02*
Y62825D01*
G01X1232954Y110117D02*
Y71620D01*
G01X1231894Y109676D02*
Y62825D01*
G01X1232954Y69380D02*
Y68620D01*
G01X1231894Y109676D02*
Y62825D01*
G01X1232954Y66380D02*
Y62382D01*
G01X1231894Y62825D02*
X1228120Y59051D01*
G01X1232954Y62382D02*
X1229180Y58608D01*
G01X1228120Y59051D02*
Y51468D01*
G01X1229180Y58608D02*
Y57620D01*
G01X1224774Y52100D02*
X1227880Y48994D01*
G01X1225873Y49500D02*
X1226820Y48553D01*
G01X1227880Y48994D02*
Y32848D01*
G01X1226820Y48553D02*
Y46020D01*
G01X1227880Y48994D02*
Y32848D01*
G01X1226820Y41880D02*
Y40920D01*
G01X1227880Y48994D02*
Y32848D01*
G01X1226820Y36580D02*
Y33291D01*
G01X1227854Y93780D02*
Y83320D01*
G01Y81080D02*
Y80320D01*
G01Y78080D02*
Y77320D01*
G01Y75080D02*
Y63122D01*
G01X1226794Y109373D02*
Y63565D01*
G01X1227854Y63122D02*
X1223980Y59248D01*
G01X1226794Y63565D02*
X1222920Y59691D01*
G01X1223980Y59248D02*
Y57420D01*
G01X1222920Y59691D02*
Y51354D01*
G01X1229874Y52314D02*
X1233066Y49122D01*
G01X1229874Y49715D02*
X1230972D01*
G01X1229874Y52314D02*
X1233066Y49122D01*
G01X1230972Y49715D02*
X1232006Y48681D01*
G01X1233066Y49122D02*
Y33732D01*
G01X1232006Y48681D02*
Y45906D01*
G01X1233066Y49122D02*
Y33732D01*
G01X1232006Y42080D02*
Y40707D01*
G01X1233066Y49122D02*
Y33732D01*
G01X1232006Y36793D02*
Y34172D01*
G01D02*
X1230983Y33149D01*
G01D02*
X1229874D01*
G01X1232954Y110117D02*
Y71620D01*
G01Y69380D02*
Y68620D01*
G01Y66380D02*
Y62382D01*
G01X1231894Y109676D02*
Y62825D01*
G01X1232954Y62382D02*
X1229180Y58608D01*
G01X1231894Y62825D02*
X1228120Y59051D01*
G01X1229180Y58608D02*
Y57620D01*
G01X1228120Y59051D02*
Y51468D01*
G01X1227854Y109816D02*
Y96020D01*
G01X1218720Y130497D02*
Y122851D01*
G01X1219780Y130937D02*
Y123291D01*
G01X1218720Y122851D02*
X1219300Y122271D01*
G01D02*
X1220936Y120636D01*
G01X1219780Y123291D02*
X1221686Y121386D01*
G01X1220936Y120636D02*
X1224536Y117036D01*
G01D02*
X1225617Y115954D01*
G01Y115953D02*
X1231894Y109676D01*
G01X1221686Y121386D02*
X1232954Y110117D01*
G01X1227854Y109816D02*
Y96020D01*
G01X1219780Y130937D02*
Y123291D01*
G01X1218720Y130497D02*
Y122851D01*
G01X1219780Y123291D02*
X1221686Y121386D01*
G01X1218720Y122851D02*
X1219300Y122271D01*
G01X1219780Y123291D02*
X1221686Y121386D01*
G01X1219300Y122271D02*
X1220936Y120636D01*
G01X1221686Y121386D02*
X1232954Y110117D01*
G01X1220936Y120636D02*
X1224536Y117036D01*
G01X1221686Y121386D02*
X1232954Y110117D01*
G01X1224536Y117036D02*
X1225617Y115954D01*
G01X1221686Y121386D02*
X1232954Y110117D01*
G01X1225617Y115953D02*
X1231894Y109676D01*
G01X1227854Y109816D02*
Y96020D01*
G01X1218720Y130497D02*
Y122851D01*
G01X1219780Y130937D02*
Y123291D01*
G01X1218720Y122851D02*
X1219300Y122271D01*
G01D02*
X1220936Y120636D01*
G01X1219780Y123291D02*
X1221686Y121386D01*
G01X1220936Y120636D02*
X1224536Y117036D01*
G01D02*
X1225617Y115954D01*
G01Y115953D02*
X1231894Y109676D01*
G01X1221686Y121386D02*
X1232954Y110117D01*
G01X1227854Y109816D02*
Y96020D01*
G01X1219780Y130937D02*
Y123291D01*
G01X1218720Y130497D02*
Y122851D01*
G01X1219780Y123291D02*
X1221686Y121386D01*
G01X1218720Y122851D02*
X1219300Y122271D01*
G01X1219780Y123291D02*
X1221686Y121386D01*
G01X1219300Y122271D02*
X1220936Y120636D01*
G01X1221686Y121386D02*
X1232954Y110117D01*
G01X1220936Y120636D02*
X1224536Y117036D01*
G01X1221686Y121386D02*
X1232954Y110117D01*
G01X1224536Y117036D02*
X1225617Y115954D01*
G01X1221686Y121386D02*
X1232954Y110117D01*
G01X1225617Y115953D02*
X1231894Y109676D01*
G01X1226794Y494764D02*
Y538398D01*
G01X1227854Y494324D02*
Y550020D01*
G01X1221348Y478220D02*
Y480536D01*
G01X1220288Y478660D02*
Y480976D01*
G01X1221348Y480536D02*
X1222612Y481800D01*
G01X1220288Y480976D02*
X1222172Y482860D01*
G01X1222612Y481800D02*
X1224938D01*
G01X1222172Y482860D02*
X1224498D01*
G01X1224938Y481800D02*
X1226542Y483404D01*
G01X1224498Y482860D02*
X1225482Y483844D01*
G01X1226542Y483404D02*
Y485156D01*
G01X1225482Y483844D02*
Y484716D01*
G01X1226542Y485156D02*
X1225836Y485862D01*
G01X1225482Y484716D02*
X1224776Y485422D01*
G01X1225836Y485862D02*
Y486722D01*
G01X1224776Y485422D02*
Y487162D01*
G01X1225836Y486722D02*
X1226824Y487710D01*
G01X1224776Y487162D02*
X1226384Y488770D01*
G01X1226824Y487710D02*
X1227684D01*
G01X1226384Y488770D02*
X1228124D01*
G01X1227684Y487710D02*
X1228390Y487004D01*
G01X1228124Y488770D02*
X1228830Y488064D01*
G01X1228390Y487004D02*
X1230132D01*
G01D02*
X1232954Y489826D01*
G01X1228830Y488064D02*
X1229692D01*
G01X1230132Y487004D02*
X1232954Y489826D01*
G01X1229692Y488064D02*
X1231894Y490266D01*
G01X1232954Y489826D02*
Y550234D01*
G01X1231894Y490266D02*
Y493415D01*
G01X1232954Y489826D02*
Y550234D01*
G01X1231894Y495655D02*
Y496655D01*
G01X1232954Y489826D02*
Y550234D01*
G01X1231894Y498895D02*
Y499895D01*
G01X1232954Y489826D02*
Y550234D01*
G01X1231894Y502135D02*
Y503135D01*
G01X1232954Y489826D02*
Y550234D01*
G01X1231894Y505375D02*
Y506375D01*
G01X1232954Y489826D02*
Y550234D01*
G01X1231894Y508615D02*
Y510432D01*
G01X1232954Y489826D02*
Y550234D01*
G01X1231894Y512538D02*
Y519067D01*
G01X1232954Y489826D02*
Y550234D01*
G01X1231894Y521307D02*
Y522307D01*
G01X1232954Y489826D02*
Y550234D01*
G01X1231894Y524547D02*
Y525547D01*
G01X1232954Y489826D02*
Y550234D01*
G01Y489826D02*
Y550234D01*
G01Y489826D02*
Y550234D01*
G01Y489826D02*
Y550234D01*
G01Y489826D02*
Y550234D01*
G01Y489826D02*
Y550234D01*
G01X1227854Y494324D02*
Y550020D01*
G01X1226794Y494764D02*
Y538398D01*
G01X1227854Y494324D02*
Y550020D01*
G01Y494324D02*
Y550020D01*
G01Y494324D02*
Y550020D01*
G01X1220288Y478660D02*
Y480976D01*
G01X1221348Y478220D02*
Y480536D01*
G01X1220288Y480976D02*
X1222172Y482860D01*
G01X1221348Y480536D02*
X1222612Y481800D01*
G01X1222172Y482860D02*
X1224498D01*
G01X1222612Y481800D02*
X1224938D01*
G01X1224498Y482860D02*
X1225482Y483844D01*
G01X1224938Y481800D02*
X1226542Y483404D01*
G01X1225482Y483844D02*
Y484716D01*
G01X1226542Y483404D02*
Y485156D01*
G01X1225482Y484716D02*
X1224776Y485422D01*
G01X1226542Y485156D02*
X1225836Y485862D01*
G01X1224776Y485422D02*
Y487162D01*
G01X1225836Y485862D02*
Y486722D01*
G01X1224776Y487162D02*
X1226384Y488770D01*
G01X1225836Y486722D02*
X1226824Y487710D01*
G01X1226384Y488770D02*
X1228124D01*
G01X1226824Y487710D02*
X1227684D01*
G01X1228124Y488770D02*
X1228830Y488064D01*
G01X1227684Y487710D02*
X1228390Y487004D01*
G01X1228830Y488064D02*
X1229692D01*
G01X1228390Y487004D02*
X1230132D01*
G01X1228830Y488064D02*
X1229692D01*
G01D02*
X1231894Y490266D01*
G01X1230132Y487004D02*
X1232954Y489826D01*
G01X1231894Y490266D02*
Y493415D01*
G01Y495655D02*
Y496655D01*
G01Y498895D02*
Y499895D01*
G01Y502135D02*
Y503135D01*
G01Y505375D02*
Y506375D01*
G01Y508615D02*
Y510432D01*
G01Y512538D02*
Y519067D01*
G01Y521307D02*
Y522307D01*
G01Y524547D02*
Y525547D01*
G01X1232954Y489826D02*
Y550234D01*
G01X1226794Y494764D02*
Y538398D01*
G01X1227854Y494324D02*
Y550020D01*
G01X1221348Y478220D02*
Y480536D01*
G01X1220288Y478660D02*
Y480976D01*
G01X1221348Y480536D02*
X1222612Y481800D01*
G01X1220288Y480976D02*
X1222172Y482860D01*
G01X1222612Y481800D02*
X1224938D01*
G01X1222172Y482860D02*
X1224498D01*
G01X1224938Y481800D02*
X1226542Y483404D01*
G01X1224498Y482860D02*
X1225482Y483844D01*
G01X1226542Y483404D02*
Y485156D01*
G01X1225482Y483844D02*
Y484716D01*
G01X1226542Y485156D02*
X1225836Y485862D01*
G01X1225482Y484716D02*
X1224776Y485422D01*
G01X1225836Y485862D02*
Y486722D01*
G01X1224776Y485422D02*
Y487162D01*
G01X1225836Y486722D02*
X1226824Y487710D01*
G01X1224776Y487162D02*
X1226384Y488770D01*
G01X1226824Y487710D02*
X1227684D01*
G01X1226384Y488770D02*
X1228124D01*
G01X1227684Y487710D02*
X1228390Y487004D01*
G01X1228124Y488770D02*
X1228830Y488064D01*
G01X1228390Y487004D02*
X1230132D01*
G01D02*
X1232954Y489826D01*
G01X1228830Y488064D02*
X1229692D01*
G01X1230132Y487004D02*
X1232954Y489826D01*
G01X1229692Y488064D02*
X1231894Y490266D01*
G01X1232954Y489826D02*
Y550234D01*
G01X1231894Y490266D02*
Y493415D01*
G01X1232954Y489826D02*
Y550234D01*
G01X1231894Y495655D02*
Y496655D01*
G01X1232954Y489826D02*
Y550234D01*
G01X1231894Y498895D02*
Y499895D01*
G01X1232954Y489826D02*
Y550234D01*
G01X1231894Y502135D02*
Y503135D01*
G01X1232954Y489826D02*
Y550234D01*
G01X1231894Y505375D02*
Y506375D01*
G01X1232954Y489826D02*
Y550234D01*
G01X1231894Y508615D02*
Y510432D01*
G01X1232954Y489826D02*
Y550234D01*
G01X1231894Y512538D02*
Y519067D01*
G01X1232954Y489826D02*
Y550234D01*
G01X1231894Y521307D02*
Y522307D01*
G01X1232954Y489826D02*
Y550234D01*
G01X1231894Y524547D02*
Y525547D01*
G01X1232954Y489826D02*
Y550234D01*
G01Y489826D02*
Y550234D01*
G01Y489826D02*
Y550234D01*
G01Y489826D02*
Y550234D01*
G01Y489826D02*
Y550234D01*
G01Y489826D02*
Y550234D01*
G01X1227854Y494324D02*
Y550020D01*
G01X1226794Y494764D02*
Y538398D01*
G01X1227854Y494324D02*
Y550020D01*
G01Y494324D02*
Y550020D01*
G01Y494324D02*
Y550020D01*
G01X1220288Y478660D02*
Y480976D01*
G01X1221348Y478220D02*
Y480536D01*
G01X1220288Y480976D02*
X1222172Y482860D01*
G01X1221348Y480536D02*
X1222612Y481800D01*
G01X1222172Y482860D02*
X1224498D01*
G01X1222612Y481800D02*
X1224938D01*
G01X1224498Y482860D02*
X1225482Y483844D01*
G01X1224938Y481800D02*
X1226542Y483404D01*
G01X1225482Y483844D02*
Y484716D01*
G01X1226542Y483404D02*
Y485156D01*
G01X1225482Y484716D02*
X1224776Y485422D01*
G01X1226542Y485156D02*
X1225836Y485862D01*
G01X1224776Y485422D02*
Y487162D01*
G01X1225836Y485862D02*
Y486722D01*
G01X1224776Y487162D02*
X1226384Y488770D01*
G01X1225836Y486722D02*
X1226824Y487710D01*
G01X1226384Y488770D02*
X1228124D01*
G01X1226824Y487710D02*
X1227684D01*
G01X1228124Y488770D02*
X1228830Y488064D01*
G01X1227684Y487710D02*
X1228390Y487004D01*
G01X1228830Y488064D02*
X1229692D01*
G01X1228390Y487004D02*
X1230132D01*
G01X1228830Y488064D02*
X1229692D01*
G01D02*
X1231894Y490266D01*
G01X1230132Y487004D02*
X1232954Y489826D01*
G01X1231894Y490266D02*
Y493415D01*
G01Y495655D02*
Y496655D01*
G01Y498895D02*
Y499895D01*
G01Y502135D02*
Y503135D01*
G01Y505375D02*
Y506375D01*
G01Y508615D02*
Y510432D01*
G01Y512538D02*
Y519067D01*
G01Y521307D02*
Y522307D01*
G01Y524547D02*
Y525547D01*
G01X1232954Y489826D02*
Y550234D01*
G01X1222786Y552200D02*
Y570211D01*
G01X1223846Y558090D02*
Y559460D01*
G01X1222786Y552200D02*
Y570211D01*
G01X1223846Y563140D02*
Y564560D01*
G01X1226794Y540320D02*
Y541479D01*
G01Y543719D02*
Y544719D01*
G01Y546959D02*
Y549580D01*
G01D02*
X1225874Y550500D01*
G01D02*
X1224774D01*
G01X1227854Y550020D02*
X1224774Y553100D01*
G01X1229070Y557700D02*
X1228399Y558371D01*
G01X1228168Y557101D02*
X1227339Y557930D01*
G01X1228399Y558371D02*
Y559648D01*
G01Y563138D02*
Y564029D01*
G01X1227339Y557930D02*
Y564470D01*
G01X1228399Y564029D02*
X1229170Y564800D01*
G01X1227339Y564470D02*
X1228168Y565299D01*
G01X1231894Y527787D02*
Y529287D01*
G01Y531235D02*
Y534458D01*
G01Y536326D02*
Y537841D01*
G01Y540081D02*
Y541081D01*
G01Y543321D02*
Y544321D01*
G01Y546561D02*
Y549794D01*
G01X1232954Y550234D02*
X1229874Y553314D01*
G01X1231894Y549794D02*
X1230974Y550714D01*
G01X1232954Y550234D02*
X1229874Y553314D01*
G01X1230974Y550714D02*
X1229874D01*
G01X1223846Y558090D02*
Y559460D01*
G01Y563140D02*
Y564560D01*
G01X1222786Y552200D02*
Y570211D01*
G01X1226794Y540320D02*
Y541479D01*
G01Y543719D02*
Y544719D01*
G01Y546959D02*
Y549580D01*
G01X1227854Y550020D02*
X1224774Y553100D01*
G01X1226794Y549580D02*
X1225874Y550500D01*
G01X1227854Y550020D02*
X1224774Y553100D01*
G01X1225874Y550500D02*
X1224774D01*
G01X1228168Y557101D02*
X1227339Y557930D01*
G01X1229070Y557700D02*
X1228399Y558371D01*
G01X1227339Y557930D02*
Y564470D01*
G01X1228399Y558371D02*
Y559648D01*
G01X1227339Y557930D02*
Y564470D01*
G01X1228399Y563138D02*
Y564029D01*
G01X1227339Y564470D02*
X1228168Y565299D01*
G01X1228399Y564029D02*
X1229170Y564800D01*
G01X1231894Y527787D02*
Y529287D01*
G01Y531235D02*
Y534458D01*
G01Y536326D02*
Y537841D01*
G01Y540081D02*
Y541081D01*
G01Y543321D02*
Y544321D01*
G01Y546561D02*
Y549794D01*
G01D02*
X1230974Y550714D01*
G01D02*
X1229874D01*
G01X1232954Y550234D02*
X1229874Y553314D01*
G01X1222786Y552200D02*
Y570211D01*
G01X1223846Y558090D02*
Y559460D01*
G01X1222786Y552200D02*
Y570211D01*
G01X1223846Y563140D02*
Y564560D01*
G01X1226794Y540320D02*
Y541479D01*
G01Y543719D02*
Y544719D01*
G01Y546959D02*
Y549580D01*
G01D02*
X1225874Y550500D01*
G01D02*
X1224774D01*
G01X1227854Y550020D02*
X1224774Y553100D01*
G01X1229070Y557700D02*
X1228399Y558371D01*
G01X1228168Y557101D02*
X1227339Y557930D01*
G01X1228399Y558371D02*
Y559648D01*
G01Y563138D02*
Y564029D01*
G01X1227339Y557930D02*
Y564470D01*
G01X1228399Y564029D02*
X1229170Y564800D01*
G01X1227339Y564470D02*
X1228168Y565299D01*
G01X1231894Y527787D02*
Y529287D01*
G01Y531235D02*
Y534458D01*
G01Y536326D02*
Y537841D01*
G01Y540081D02*
Y541081D01*
G01Y543321D02*
Y544321D01*
G01Y546561D02*
Y549794D01*
G01X1232954Y550234D02*
X1229874Y553314D01*
G01X1231894Y549794D02*
X1230974Y550714D01*
G01X1232954Y550234D02*
X1229874Y553314D01*
G01X1230974Y550714D02*
X1229874D01*
G01X1223846Y558090D02*
Y559460D01*
G01Y563140D02*
Y564560D01*
G01X1222786Y552200D02*
Y570211D01*
G01X1226794Y540320D02*
Y541479D01*
G01Y543719D02*
Y544719D01*
G01Y546959D02*
Y549580D01*
G01X1227854Y550020D02*
X1224774Y553100D01*
G01X1226794Y549580D02*
X1225874Y550500D01*
G01X1227854Y550020D02*
X1224774Y553100D01*
G01X1225874Y550500D02*
X1224774D01*
G01X1228168Y557101D02*
X1227339Y557930D01*
G01X1229070Y557700D02*
X1228399Y558371D01*
G01X1227339Y557930D02*
Y564470D01*
G01X1228399Y558371D02*
Y559648D01*
G01X1227339Y557930D02*
Y564470D01*
G01X1228399Y563138D02*
Y564029D01*
G01X1227339Y564470D02*
X1228168Y565299D01*
G01X1228399Y564029D02*
X1229170Y564800D01*
G01X1231894Y527787D02*
Y529287D01*
G01Y531235D02*
Y534458D01*
G01Y536326D02*
Y537841D01*
G01Y540081D02*
Y541081D01*
G01Y543321D02*
Y544321D01*
G01Y546561D02*
Y549794D01*
G01D02*
X1230974Y550714D01*
G01D02*
X1229874D01*
G01X1232954Y550234D02*
X1229874Y553314D01*
M02*
